G04 ================== begin FILE IDENTIFICATION RECORD ==================*
G04 Layout Name:  D:/<user>/Wistron_project/16317-1/gbr/16317-1.brd*
G04 Film Name:    L1*
G04 File Format:  Gerber RS274X*
G04 File Origin:  Cadence Allegro 16.5-S056*
G04 Origin Date:  Fri Jun 09 15:53:16 2017*
G04 *
G04 Layer:  VIA CLASS/TOP*
G04 Layer:  PIN/TOP*
G04 Layer:  ETCH/TOP*
G04 Layer:  DRAWING FORMAT/LAYER_PCB_STORY*
G04 Layer:  DRAWING FORMAT/LAYER_L1*
G04 *
G04 Offset:    (0.00 0.00)*
G04 Mirror:    No*
G04 Mode:      Positive*
G04 Rotation:  0*
G04 FullContactRelief:  No*
G04 UndefLineWidth:     6.00*
G04 ================== end FILE IDENTIFICATION RECORD ====================*
%FSLAX35Y35*MOIN*%
%IR0*IPPOS*OFA0.00000B0.00000*MIA0B0*SFA1.00000B1.00000*%
%AMMACRO34*
4,1,40,.017,-.013,
.017,.013,
.016939,.013695,
.016759,.014368,
.016464,.015,
.016064,.015571,
.015571,.016064,
.015,.016464,
.014368,.016759,
.013695,.016939,
.013,.017,
-.013,.017,
-.013695,.016939,
-.014368,.016759,
-.015,.016464,
-.015571,.016064,
-.016064,.015571,
-.016464,.015,
-.016759,.014368,
-.016939,.013695,
-.017,.013,
-.017,-.013,
-.016939,-.013695,
-.016759,-.014368,
-.016464,-.015,
-.016064,-.015571,
-.015571,-.016064,
-.015,-.016464,
-.014368,-.016759,
-.013695,-.016939,
-.013,-.017,
.013,-.017,
.013695,-.016939,
.014368,-.016759,
.015,-.016464,
.015571,-.016064,
.016064,-.015571,
.016464,-.015,
.016759,-.014368,
.016939,-.013695,
.017,-.013,
0.0*
%
%ADD34MACRO34*%
%AMMACRO32*
4,1,40,.013,.017,
-.013,.017,
-.013695,.016939,
-.014368,.016759,
-.015,.016464,
-.015571,.016064,
-.016064,.015571,
-.016464,.015,
-.016759,.014368,
-.016939,.013695,
-.017,.013,
-.017,-.013,
-.016939,-.013695,
-.016759,-.014368,
-.016464,-.015,
-.016064,-.015571,
-.015571,-.016064,
-.015,-.016464,
-.014368,-.016759,
-.013695,-.016939,
-.013,-.017,
.013,-.017,
.013695,-.016939,
.014368,-.016759,
.015,-.016464,
.015571,-.016064,
.016064,-.015571,
.016464,-.015,
.016759,-.014368,
.016939,-.013695,
.017,-.013,
.017,.013,
.016939,.013695,
.016759,.014368,
.016464,.015,
.016064,.015571,
.015571,.016064,
.015,.016464,
.014368,.016759,
.013695,.016939,
.013,.017,
0.0*
%
%ADD32MACRO32*%
%ADD66R,.055X.11*%
%ADD70R,.11X.055*%
%ADD23C,.01*%
%ADD99O,.115X.048*%
%ADD45C,.02*%
%ADD83R,.056X.14*%
%ADD82C,.03*%
%ADD68R,.08X.127*%
%ADD24C,.022*%
%ADD10C,.04*%
%ADD94R,.127X.08*%
%ADD51C,.032*%
%AMMACRO48*
4,1,40,-.007,.004,
-.007,-.004,
-.00697,-.004347,
-.006879,-.004684,
-.006732,-.005,
-.006532,-.005286,
-.006286,-.005532,
-.006,-.005732,
-.005684,-.005879,
-.005347,-.00597,
-.005,-.006,
.005,-.006,
.005347,-.00597,
.005684,-.005879,
.006,-.005732,
.006286,-.005532,
.006532,-.005286,
.006732,-.005,
.006879,-.004684,
.00697,-.004347,
.007,-.004,
.007,.004,
.00697,.004347,
.006879,.004684,
.006732,.005,
.006532,.005286,
.006286,.005532,
.006,.005732,
.005684,.005879,
.005347,.00597,
.005,.006,
-.005,.006,
-.005347,.00597,
-.005684,.005879,
-.006,.005732,
-.006286,.005532,
-.006532,.005286,
-.006732,.005,
-.006879,.004684,
-.00697,.004347,
-.007,.004,
0.0*
%
%ADD48MACRO48*%
%ADD44C,.05*%
%ADD72R,.096X.22*%
%ADD102R,.118X.047*%
%ADD69C,.034*%
%ADD26C,.026*%
%ADD95O,.048X.166*%
%ADD93R,.008X.037*%
%ADD92R,.037X.008*%
%ADD25C,.028*%
%ADD67C,.056*%
%ADD96C,.048*%
%ADD101R,.157X.067*%
%AMMACRO43*
4,1,40,.0225,-.007,
.022378,-.008389,
.022018,-.009736,
.021428,-.011,
.020628,-.012142,
.019642,-.013128,
.0185,-.013928,
.017236,-.014518,
.015889,-.014878,
.0145,-.015,
-.0145,-.015,
-.015889,-.014878,
-.017236,-.014518,
-.0185,-.013928,
-.019642,-.013128,
-.020628,-.012142,
-.021428,-.011,
-.022018,-.009736,
-.022378,-.008389,
-.0225,-.007,
-.0225,.007,
-.022378,.008389,
-.022018,.009736,
-.021428,.011,
-.020628,.012142,
-.019642,.013128,
-.0185,.013928,
-.017236,.014518,
-.015889,.014878,
-.0145,.015,
.0145,.015,
.015889,.014878,
.017236,.014518,
.0185,.013928,
.019642,.013128,
.020628,.012142,
.021428,.011,
.022018,.009736,
.022378,.008389,
.0225,.007,
.0225,-.007,
0.0*
%
%ADD43MACRO43*%
%AMMACRO90*
4,1,40,-.007,-.0225,
-.008389,-.022378,
-.009736,-.022018,
-.011,-.021428,
-.012142,-.020628,
-.013128,-.019642,
-.013928,-.0185,
-.014518,-.017236,
-.014878,-.015889,
-.015,-.0145,
-.015,.0145,
-.014878,.015889,
-.014518,.017236,
-.013928,.0185,
-.013128,.019642,
-.012142,.020628,
-.011,.021428,
-.009736,.022018,
-.008389,.022378,
-.007,.0225,
.007,.0225,
.008389,.022378,
.009736,.022018,
.011,.021428,
.012142,.020628,
.013128,.019642,
.013928,.0185,
.014518,.017236,
.014878,.015889,
.015,.0145,
.015,-.0145,
.014878,-.015889,
.014518,-.017236,
.013928,-.0185,
.013128,-.019642,
.012142,-.020628,
.011,-.021428,
.009736,-.022018,
.008389,-.022378,
.007,-.0225,
-.007,-.0225,
0.0*
%
%ADD90MACRO90*%
%AMMACRO16*
4,1,40,.011,-.007,
.011,.007,
.010939,.007695,
.010759,.008368,
.010464,.009,
.010064,.009571,
.009571,.010064,
.009,.010464,
.008368,.010759,
.007695,.010939,
.007,.011,
-.007,.011,
-.007695,.010939,
-.008368,.010759,
-.009,.010464,
-.009571,.010064,
-.010064,.009571,
-.010464,.009,
-.010759,.008368,
-.010939,.007695,
-.011,.007,
-.011,-.007,
-.010939,-.007695,
-.010759,-.008368,
-.010464,-.009,
-.010064,-.009571,
-.009571,-.010064,
-.009,-.010464,
-.008368,-.010759,
-.007695,-.010939,
-.007,-.011,
.007,-.011,
.007695,-.010939,
.008368,-.010759,
.009,-.010464,
.009571,-.010064,
.010064,-.009571,
.010464,-.009,
.010759,-.008368,
.010939,-.007695,
.011,-.007,
0.0*
%
%ADD16MACRO16*%
%AMMACRO14*
4,1,40,.007,.011,
-.007,.011,
-.007695,.010939,
-.008368,.010759,
-.009,.010464,
-.009571,.010064,
-.010064,.009571,
-.010464,.009,
-.010759,.008368,
-.010939,.007695,
-.011,.007,
-.011,-.007,
-.010939,-.007695,
-.010759,-.008368,
-.010464,-.009,
-.010064,-.009571,
-.009571,-.010064,
-.009,-.010464,
-.008368,-.010759,
-.007695,-.010939,
-.007,-.011,
.007,-.011,
.007695,-.010939,
.008368,-.010759,
.009,-.010464,
.009571,-.010064,
.010064,-.009571,
.010464,-.009,
.010759,-.008368,
.010939,-.007695,
.011,-.007,
.011,.007,
.010939,.007695,
.010759,.008368,
.010464,.009,
.010064,.009571,
.009571,.010064,
.009,.010464,
.008368,.010759,
.007695,.010939,
.007,.011,
0.0*
%
%ADD14MACRO14*%
%AMMACRO30*
4,1,40,-.012,.008,
-.012,-.008,
-.011939,-.008695,
-.011759,-.009368,
-.011464,-.01,
-.011064,-.010571,
-.010571,-.011064,
-.01,-.011464,
-.009368,-.011759,
-.008695,-.011939,
-.008,-.012,
.008,-.012,
.008695,-.011939,
.009368,-.011759,
.01,-.011464,
.010571,-.011064,
.011064,-.010571,
.011464,-.01,
.011759,-.009368,
.011939,-.008695,
.012,-.008,
.012,.008,
.011939,.008695,
.011759,.009368,
.011464,.01,
.011064,.010571,
.010571,.011064,
.01,.011464,
.009368,.011759,
.008695,.011939,
.008,.012,
-.008,.012,
-.008695,.011939,
-.009368,.011759,
-.01,.011464,
-.010571,.011064,
-.011064,.010571,
-.011464,.01,
-.011759,.009368,
-.011939,.008695,
-.012,.008,
0.0*
%
%ADD30MACRO30*%
%AMMACRO55*
4,1,40,.008,.012,
-.008,.012,
-.008695,.011939,
-.009368,.011759,
-.01,.011464,
-.010571,.011064,
-.011064,.010571,
-.011464,.01,
-.011759,.009368,
-.011939,.008695,
-.012,.008,
-.012,-.008,
-.011939,-.008695,
-.011759,-.009368,
-.011464,-.01,
-.011064,-.010571,
-.010571,-.011064,
-.01,-.011464,
-.009368,-.011759,
-.008695,-.011939,
-.008,-.012,
.008,-.012,
.008695,-.011939,
.009368,-.011759,
.01,-.011464,
.010571,-.011064,
.011064,-.010571,
.011464,-.01,
.011759,-.009368,
.011939,-.008695,
.012,-.008,
.012,.008,
.011939,.008695,
.011759,.009368,
.011464,.01,
.011064,.010571,
.010571,.011064,
.01,.011464,
.009368,.011759,
.008695,.011939,
.008,.012,
0.0*
%
%ADD55MACRO55*%
%AMMACRO49*
4,1,40,-.013,-.017,
.013,-.017,
.013695,-.016939,
.014368,-.016759,
.015,-.016464,
.015571,-.016064,
.016064,-.015571,
.016464,-.015,
.016759,-.014368,
.016939,-.013695,
.017,-.013,
.017,.013,
.016939,.013695,
.016759,.014368,
.016464,.015,
.016064,.015571,
.015571,.016064,
.015,.016464,
.014368,.016759,
.013695,.016939,
.013,.017,
-.013,.017,
-.013695,.016939,
-.014368,.016759,
-.015,.016464,
-.015571,.016064,
-.016064,.015571,
-.016464,.015,
-.016759,.014368,
-.016939,.013695,
-.017,.013,
-.017,-.013,
-.016939,-.013695,
-.016759,-.014368,
-.016464,-.015,
-.016064,-.015571,
-.015571,-.016064,
-.015,-.016464,
-.014368,-.016759,
-.013695,-.016939,
-.013,-.017,
0.0*
%
%ADD49MACRO49*%
%AMMACRO40*
4,1,40,-.017,.013,
-.017,-.013,
-.016939,-.013695,
-.016759,-.014368,
-.016464,-.015,
-.016064,-.015571,
-.015571,-.016064,
-.015,-.016464,
-.014368,-.016759,
-.013695,-.016939,
-.013,-.017,
.013,-.017,
.013695,-.016939,
.014368,-.016759,
.015,-.016464,
.015571,-.016064,
.016064,-.015571,
.016464,-.015,
.016759,-.014368,
.016939,-.013695,
.017,-.013,
.017,.013,
.016939,.013695,
.016759,.014368,
.016464,.015,
.016064,.015571,
.015571,.016064,
.015,.016464,
.014368,.016759,
.013695,.016939,
.013,.017,
-.013,.017,
-.013695,.016939,
-.014368,.016759,
-.015,.016464,
-.015571,.016064,
-.016064,.015571,
-.016464,.015,
-.016759,.014368,
-.016939,.013695,
-.017,.013,
0.0*
%
%ADD40MACRO40*%
%AMMACRO75*
4,1,40,.023,-.013,
.023,.013,
.022939,.013695,
.022759,.014368,
.022464,.015,
.022064,.015571,
.021571,.016064,
.021,.016464,
.020368,.016759,
.019695,.016939,
.019,.017,
-.019,.017,
-.019695,.016939,
-.020368,.016759,
-.021,.016464,
-.021571,.016064,
-.022064,.015571,
-.022464,.015,
-.022759,.014368,
-.022939,.013695,
-.023,.013,
-.023,-.013,
-.022939,-.013695,
-.022759,-.014368,
-.022464,-.015,
-.022064,-.015571,
-.021571,-.016064,
-.021,-.016464,
-.020368,-.016759,
-.019695,-.016939,
-.019,-.017,
.019,-.017,
.019695,-.016939,
.020368,-.016759,
.021,-.016464,
.021571,-.016064,
.022064,-.015571,
.022464,-.015,
.022759,-.014368,
.022939,-.013695,
.023,-.013,
0.0*
%
%ADD75MACRO75*%
%AMMACRO17*
4,1,40,.011,-.007,
.011,.007,
.010939,.007695,
.010759,.008368,
.010464,.009,
.010064,.009571,
.009571,.010064,
.009,.010464,
.008368,.010759,
.007695,.010939,
.007,.011,
-.007,.011,
-.007695,.010939,
-.008368,.010759,
-.009,.010464,
-.009571,.010064,
-.010064,.009571,
-.010464,.009,
-.010759,.008368,
-.010939,.007695,
-.011,.007,
-.011,-.007,
-.010939,-.007695,
-.010759,-.008368,
-.010464,-.009,
-.010064,-.009571,
-.009571,-.010064,
-.009,-.010464,
-.008368,-.010759,
-.007695,-.010939,
-.007,-.011,
.007,-.011,
.007695,-.010939,
.008368,-.010759,
.009,-.010464,
.009571,-.010064,
.010064,-.009571,
.010464,-.009,
.010759,-.008368,
.010939,-.007695,
.011,-.007,
0.0*
%
%ADD17MACRO17*%
%AMMACRO15*
4,1,40,.007,.011,
-.007,.011,
-.007695,.010939,
-.008368,.010759,
-.009,.010464,
-.009571,.010064,
-.010064,.009571,
-.010464,.009,
-.010759,.008368,
-.010939,.007695,
-.011,.007,
-.011,-.007,
-.010939,-.007695,
-.010759,-.008368,
-.010464,-.009,
-.010064,-.009571,
-.009571,-.010064,
-.009,-.010464,
-.008368,-.010759,
-.007695,-.010939,
-.007,-.011,
.007,-.011,
.007695,-.010939,
.008368,-.010759,
.009,-.010464,
.009571,-.010064,
.010064,-.009571,
.010464,-.009,
.010759,-.008368,
.010939,-.007695,
.011,-.007,
.011,.007,
.010939,.007695,
.010759,.008368,
.010464,.009,
.010064,.009571,
.009571,.010064,
.009,.010464,
.008368,.010759,
.007695,.010939,
.007,.011,
0.0*
%
%ADD15MACRO15*%
%AMMACRO29*
4,1,40,-.012,.008,
-.012,-.008,
-.011939,-.008695,
-.011759,-.009368,
-.011464,-.01,
-.011064,-.010571,
-.010571,-.011064,
-.01,-.011464,
-.009368,-.011759,
-.008695,-.011939,
-.008,-.012,
.008,-.012,
.008695,-.011939,
.009368,-.011759,
.01,-.011464,
.010571,-.011064,
.011064,-.010571,
.011464,-.01,
.011759,-.009368,
.011939,-.008695,
.012,-.008,
.012,.008,
.011939,.008695,
.011759,.009368,
.011464,.01,
.011064,.010571,
.010571,.011064,
.01,.011464,
.009368,.011759,
.008695,.011939,
.008,.012,
-.008,.012,
-.008695,.011939,
-.009368,.011759,
-.01,.011464,
-.010571,.011064,
-.011064,.010571,
-.011464,.01,
-.011759,.009368,
-.011939,.008695,
-.012,.008,
0.0*
%
%ADD29MACRO29*%
%AMMACRO54*
4,1,40,.008,.012,
-.008,.012,
-.008695,.011939,
-.009368,.011759,
-.01,.011464,
-.010571,.011064,
-.011064,.010571,
-.011464,.01,
-.011759,.009368,
-.011939,.008695,
-.012,.008,
-.012,-.008,
-.011939,-.008695,
-.011759,-.009368,
-.011464,-.01,
-.011064,-.010571,
-.010571,-.011064,
-.01,-.011464,
-.009368,-.011759,
-.008695,-.011939,
-.008,-.012,
.008,-.012,
.008695,-.011939,
.009368,-.011759,
.01,-.011464,
.010571,-.011064,
.011064,-.010571,
.011464,-.01,
.011759,-.009368,
.011939,-.008695,
.012,-.008,
.012,.008,
.011939,.008695,
.011759,.009368,
.011464,.01,
.011064,.010571,
.010571,.011064,
.01,.011464,
.009368,.011759,
.008695,.011939,
.008,.012,
0.0*
%
%ADD54MACRO54*%
%AMMACRO50*
4,1,40,-.013,-.017,
.013,-.017,
.013695,-.016939,
.014368,-.016759,
.015,-.016464,
.015571,-.016064,
.016064,-.015571,
.016464,-.015,
.016759,-.014368,
.016939,-.013695,
.017,-.013,
.017,.013,
.016939,.013695,
.016759,.014368,
.016464,.015,
.016064,.015571,
.015571,.016064,
.015,.016464,
.014368,.016759,
.013695,.016939,
.013,.017,
-.013,.017,
-.013695,.016939,
-.014368,.016759,
-.015,.016464,
-.015571,.016064,
-.016064,.015571,
-.016464,.015,
-.016759,.014368,
-.016939,.013695,
-.017,.013,
-.017,-.013,
-.016939,-.013695,
-.016759,-.014368,
-.016464,-.015,
-.016064,-.015571,
-.015571,-.016064,
-.015,-.016464,
-.014368,-.016759,
-.013695,-.016939,
-.013,-.017,
0.0*
%
%ADD50MACRO50*%
%AMMACRO41*
4,1,40,-.017,.013,
-.017,-.013,
-.016939,-.013695,
-.016759,-.014368,
-.016464,-.015,
-.016064,-.015571,
-.015571,-.016064,
-.015,-.016464,
-.014368,-.016759,
-.013695,-.016939,
-.013,-.017,
.013,-.017,
.013695,-.016939,
.014368,-.016759,
.015,-.016464,
.015571,-.016064,
.016064,-.015571,
.016464,-.015,
.016759,-.014368,
.016939,-.013695,
.017,-.013,
.017,.013,
.016939,.013695,
.016759,.014368,
.016464,.015,
.016064,.015571,
.015571,.016064,
.015,.016464,
.014368,.016759,
.013695,.016939,
.013,.017,
-.013,.017,
-.013695,.016939,
-.014368,.016759,
-.015,.016464,
-.015571,.016064,
-.016064,.015571,
-.016464,.015,
-.016759,.014368,
-.016939,.013695,
-.017,.013,
0.0*
%
%ADD41MACRO41*%
%AMMACRO76*
4,1,40,-.019,-.017,
.019,-.017,
.019695,-.016939,
.020368,-.016759,
.021,-.016464,
.021571,-.016064,
.022064,-.015571,
.022464,-.015,
.022759,-.014368,
.022939,-.013695,
.023,-.013,
.023,.013,
.022939,.013695,
.022759,.014368,
.022464,.015,
.022064,.015571,
.021571,.016064,
.021,.016464,
.020368,.016759,
.019695,.016939,
.019,.017,
-.019,.017,
-.019695,.016939,
-.020368,.016759,
-.021,.016464,
-.021571,.016064,
-.022064,.015571,
-.022464,.015,
-.022759,.014368,
-.022939,.013695,
-.023,.013,
-.023,-.013,
-.022939,-.013695,
-.022759,-.014368,
-.022464,-.015,
-.022064,-.015571,
-.021571,-.016064,
-.021,-.016464,
-.020368,-.016759,
-.019695,-.016939,
-.019,-.017,
0.0*
%
%ADD76MACRO76*%
%ADD87R,.2X.208*%
%ADD86R,.001X.001*%
%ADD65R,.04X.022*%
%ADD100R,.02X.06*%
%ADD88R,.06X.03*%
%ADD21R,.022X.04*%
%ADD103R,.142X.106*%
%ADD80R,.012X.042*%
%ADD78R,.042X.012*%
%ADD84R,.06X.014*%
%ADD61R,.04X.016*%
%ADD60C,.101*%
%ADD64R,.032X.016*%
%ADD52R,.014X.06*%
%ADD22R,.016X.04*%
%ADD107R,.016X.032*%
%ADD89R,.06X.016*%
%ADD79R,.012X.036*%
%ADD77R,.036X.012*%
%AMMACRO104*
4,1,40,.007,-.004,
.007,.004,
.00697,.004347,
.006879,.004684,
.006732,.005,
.006532,.005286,
.006286,.005532,
.006,.005732,
.005684,.005879,
.005347,.00597,
.005,.006,
-.005,.006,
-.005347,.00597,
-.005684,.005879,
-.006,.005732,
-.006286,.005532,
-.006532,.005286,
-.006732,.005,
-.006879,.004684,
-.00697,.004347,
-.007,.004,
-.007,-.004,
-.00697,-.004347,
-.006879,-.004684,
-.006732,-.005,
-.006532,-.005286,
-.006286,-.005532,
-.006,-.005732,
-.005684,-.005879,
-.005347,-.00597,
-.005,-.006,
.005,-.006,
.005347,-.00597,
.005684,-.005879,
.006,-.005732,
.006286,-.005532,
.006532,-.005286,
.006732,-.005,
.006879,-.004684,
.00697,-.004347,
.007,-.004,
0.0*
%
%ADD104MACRO104*%
%ADD11R,.093X.02*%
%ADD35R,.05X.065*%
%ADD36R,.065X.05*%
%ADD105R,.065X.025*%
%ADD62R,.055X.035*%
%ADD46R,.093X.024*%
%ADD39R,.028X.034*%
%ADD71R,.035X.055*%
%ADD59R,.048X.016*%
%ADD47R,.102X.102*%
%ADD37R,.045X.055*%
%ADD20R,.025X.065*%
%ADD63R,.016X.048*%
%ADD38R,.055X.045*%
%AMMACRO98*
4,1,46,.00177,.018,
.003163,.017918,
.00452,.017595,
.0058,.017042,
.006965,.016274,
.007979,.015316,
.008812,.014196,
.009437,.012949,
.009836,.011613,
.009997,.010227,
.01,.01,
.01,-.01,
.00999,-.01,
.009868,-.011389,
.009507,-.012737,
.008918,-.014001,
.008118,-.015143,
.007132,-.016129,
.005989,-.016929,
.004725,-.017519,
.003378,-.01788,
.001989,-.018001,
.00185,-.018,
-.00185,-.018,
-.003241,-.017903,
-.004595,-.017565,
-.005869,-.016998,
-.007025,-.016218,
-.008028,-.015249,
-.008848,-.01412,
-.009459,-.012867,
-.009843,-.011526,
-.009989,-.010139,
-.00999,-.01,
-.01,-.01,
-.01,.01,
-.009878,.01139,
-.009517,.012737,
-.008928,.014002,
-.008128,.015144,
-.007141,.016131,
-.005998,.016931,
-.004734,.017521,
-.003387,.017882,
-.001997,.018003,
-.00177,.018,
.00177,.018,
0.0*
%
%ADD98MACRO98*%
%ADD97R,.09X.095*%
%ADD91R,.106X.106*%
%ADD85R,.083X.057*%
%AMMACRO74*
4,1,40,-.0225,.007,
-.022378,.008389,
-.022018,.009736,
-.021428,.011,
-.020628,.012142,
-.019642,.013128,
-.0185,.013928,
-.017236,.014518,
-.015889,.014878,
-.0145,.015,
.0145,.015,
.015889,.014878,
.017236,.014518,
.0185,.013928,
.019642,.013128,
.020628,.012142,
.021428,.011,
.022018,.009736,
.022378,.008389,
.0225,.007,
.0225,-.007,
.022378,-.008389,
.022018,-.009736,
.021428,-.011,
.020628,-.012142,
.019642,-.013128,
.0185,-.013928,
.017236,-.014518,
.015889,-.014878,
.0145,-.015,
-.0145,-.015,
-.015889,-.014878,
-.017236,-.014518,
-.0185,-.013928,
-.019642,-.013128,
-.020628,-.012142,
-.021428,-.011,
-.022018,-.009736,
-.022378,-.008389,
-.0225,-.007,
-.0225,.007,
0.0*
%
%ADD74MACRO74*%
%ADD73R,.096X.035*%
%ADD53C,.375*%
%AMMACRO42*
4,1,40,.007,.0225,
.008389,.022378,
.009736,.022018,
.011,.021428,
.012142,.020628,
.013128,.019642,
.013928,.0185,
.014518,.017236,
.014878,.015889,
.015,.0145,
.015,-.0145,
.014878,-.015889,
.014518,-.017236,
.013928,-.0185,
.013128,-.019642,
.012142,-.020628,
.011,-.021428,
.009736,-.022018,
.008389,-.022378,
.007,-.0225,
-.007,-.0225,
-.008389,-.022378,
-.009736,-.022018,
-.011,-.021428,
-.012142,-.020628,
-.013128,-.019642,
-.013928,-.0185,
-.014518,-.017236,
-.014878,-.015889,
-.015,-.0145,
-.015,.0145,
-.014878,.015889,
-.014518,.017236,
-.013928,.0185,
-.013128,.019642,
-.012142,.020628,
-.011,.021428,
-.009736,.022018,
-.008389,.022378,
-.007,.0225,
.007,.0225,
0.0*
%
%ADD42MACRO42*%
%ADD81R,.136X.136*%
%ADD106R,.272X.272*%
%ADD56O,.552X.788*%
%AMMACRO58*
4,1,40,-.008,-.012,
.008,-.012,
.008695,-.011939,
.009368,-.011759,
.01,-.011464,
.010571,-.011064,
.011064,-.010571,
.011464,-.01,
.011759,-.009368,
.011939,-.008695,
.012,-.008,
.012,.008,
.011939,.008695,
.011759,.009368,
.011464,.01,
.011064,.010571,
.010571,.011064,
.01,.011464,
.009368,.011759,
.008695,.011939,
.008,.012,
-.008,.012,
-.008695,.011939,
-.009368,.011759,
-.01,.011464,
-.010571,.011064,
-.011064,.010571,
-.011464,.01,
-.011759,.009368,
-.011939,.008695,
-.012,.008,
-.012,-.008,
-.011939,-.008695,
-.011759,-.009368,
-.011464,-.01,
-.011064,-.010571,
-.010571,-.011064,
-.01,-.011464,
-.009368,-.011759,
-.008695,-.011939,
-.008,-.012,
0.0*
%
%ADD58MACRO58*%
%AMMACRO28*
4,1,40,.012,-.008,
.012,.008,
.011939,.008695,
.011759,.009368,
.011464,.01,
.011064,.010571,
.010571,.011064,
.01,.011464,
.009368,.011759,
.008695,.011939,
.008,.012,
-.008,.012,
-.008695,.011939,
-.009368,.011759,
-.01,.011464,
-.010571,.011064,
-.011064,.010571,
-.011464,.01,
-.011759,.009368,
-.011939,.008695,
-.012,.008,
-.012,-.008,
-.011939,-.008695,
-.011759,-.009368,
-.011464,-.01,
-.011064,-.010571,
-.010571,-.011064,
-.01,-.011464,
-.009368,-.011759,
-.008695,-.011939,
-.008,-.012,
.008,-.012,
.008695,-.011939,
.009368,-.011759,
.01,-.011464,
.010571,-.011064,
.011064,-.010571,
.011464,-.01,
.011759,-.009368,
.011939,-.008695,
.012,-.008,
0.0*
%
%ADD28MACRO28*%
%AMMACRO12*
4,1,40,-.007,-.011,
.007,-.011,
.007695,-.010939,
.008368,-.010759,
.009,-.010464,
.009571,-.010064,
.010064,-.009571,
.010464,-.009,
.010759,-.008368,
.010939,-.007695,
.011,-.007,
.011,.007,
.010939,.007695,
.010759,.008368,
.010464,.009,
.010064,.009571,
.009571,.010064,
.009,.010464,
.008368,.010759,
.007695,.010939,
.007,.011,
-.007,.011,
-.007695,.010939,
-.008368,.010759,
-.009,.010464,
-.009571,.010064,
-.010064,.009571,
-.010464,.009,
-.010759,.008368,
-.010939,.007695,
-.011,.007,
-.011,-.007,
-.010939,-.007695,
-.010759,-.008368,
-.010464,-.009,
-.010064,-.009571,
-.009571,-.010064,
-.009,-.010464,
-.008368,-.010759,
-.007695,-.010939,
-.007,-.011,
0.0*
%
%ADD12MACRO12*%
%AMMACRO18*
4,1,40,-.011,.007,
-.011,-.007,
-.010939,-.007695,
-.010759,-.008368,
-.010464,-.009,
-.010064,-.009571,
-.009571,-.010064,
-.009,-.010464,
-.008368,-.010759,
-.007695,-.010939,
-.007,-.011,
.007,-.011,
.007695,-.010939,
.008368,-.010759,
.009,-.010464,
.009571,-.010064,
.010064,-.009571,
.010464,-.009,
.010759,-.008368,
.010939,-.007695,
.011,-.007,
.011,.007,
.010939,.007695,
.010759,.008368,
.010464,.009,
.010064,.009571,
.009571,.010064,
.009,.010464,
.008368,.010759,
.007695,.010939,
.007,.011,
-.007,.011,
-.007695,.010939,
-.008368,.010759,
-.009,.010464,
-.009571,.010064,
-.010064,.009571,
-.010464,.009,
-.010759,.008368,
-.010939,.007695,
-.011,.007,
0.0*
%
%ADD18MACRO18*%
%AMMACRO33*
4,1,40,.017,-.013,
.017,.013,
.016939,.013695,
.016759,.014368,
.016464,.015,
.016064,.015571,
.015571,.016064,
.015,.016464,
.014368,.016759,
.013695,.016939,
.013,.017,
-.013,.017,
-.013695,.016939,
-.014368,.016759,
-.015,.016464,
-.015571,.016064,
-.016064,.015571,
-.016464,.015,
-.016759,.014368,
-.016939,.013695,
-.017,.013,
-.017,-.013,
-.016939,-.013695,
-.016759,-.014368,
-.016464,-.015,
-.016064,-.015571,
-.015571,-.016064,
-.015,-.016464,
-.014368,-.016759,
-.013695,-.016939,
-.013,-.017,
.013,-.017,
.013695,-.016939,
.014368,-.016759,
.015,-.016464,
.015571,-.016064,
.016064,-.015571,
.016464,-.015,
.016759,-.014368,
.016939,-.013695,
.017,-.013,
0.0*
%
%ADD33MACRO33*%
%AMMACRO31*
4,1,40,.013,.017,
-.013,.017,
-.013695,.016939,
-.014368,.016759,
-.015,.016464,
-.015571,.016064,
-.016064,.015571,
-.016464,.015,
-.016759,.014368,
-.016939,.013695,
-.017,.013,
-.017,-.013,
-.016939,-.013695,
-.016759,-.014368,
-.016464,-.015,
-.016064,-.015571,
-.015571,-.016064,
-.015,-.016464,
-.014368,-.016759,
-.013695,-.016939,
-.013,-.017,
.013,-.017,
.013695,-.016939,
.014368,-.016759,
.015,-.016464,
.015571,-.016064,
.016064,-.015571,
.016464,-.015,
.016759,-.014368,
.016939,-.013695,
.017,-.013,
.017,.013,
.016939,.013695,
.016759,.014368,
.016464,.015,
.016064,.015571,
.015571,.016064,
.015,.016464,
.014368,.016759,
.013695,.016939,
.013,.017,
0.0*
%
%ADD31MACRO31*%
%AMMACRO57*
4,1,40,-.008,-.012,
.008,-.012,
.008695,-.011939,
.009368,-.011759,
.01,-.011464,
.010571,-.011064,
.011064,-.010571,
.011464,-.01,
.011759,-.009368,
.011939,-.008695,
.012,-.008,
.012,.008,
.011939,.008695,
.011759,.009368,
.011464,.01,
.011064,.010571,
.010571,.011064,
.01,.011464,
.009368,.011759,
.008695,.011939,
.008,.012,
-.008,.012,
-.008695,.011939,
-.009368,.011759,
-.01,.011464,
-.010571,.011064,
-.011064,.010571,
-.011464,.01,
-.011759,.009368,
-.011939,.008695,
-.012,.008,
-.012,-.008,
-.011939,-.008695,
-.011759,-.009368,
-.011464,-.01,
-.011064,-.010571,
-.010571,-.011064,
-.01,-.011464,
-.009368,-.011759,
-.008695,-.011939,
-.008,-.012,
0.0*
%
%ADD57MACRO57*%
%AMMACRO27*
4,1,40,.012,-.008,
.012,.008,
.011939,.008695,
.011759,.009368,
.011464,.01,
.011064,.010571,
.010571,.011064,
.01,.011464,
.009368,.011759,
.008695,.011939,
.008,.012,
-.008,.012,
-.008695,.011939,
-.009368,.011759,
-.01,.011464,
-.010571,.011064,
-.011064,.010571,
-.011464,.01,
-.011759,.009368,
-.011939,.008695,
-.012,.008,
-.012,-.008,
-.011939,-.008695,
-.011759,-.009368,
-.011464,-.01,
-.011064,-.010571,
-.010571,-.011064,
-.01,-.011464,
-.009368,-.011759,
-.008695,-.011939,
-.008,-.012,
.008,-.012,
.008695,-.011939,
.009368,-.011759,
.01,-.011464,
.010571,-.011064,
.011064,-.010571,
.011464,-.01,
.011759,-.009368,
.011939,-.008695,
.012,-.008,
0.0*
%
%ADD27MACRO27*%
%AMMACRO13*
4,1,40,-.007,-.011,
.007,-.011,
.007695,-.010939,
.008368,-.010759,
.009,-.010464,
.009571,-.010064,
.010064,-.009571,
.010464,-.009,
.010759,-.008368,
.010939,-.007695,
.011,-.007,
.011,.007,
.010939,.007695,
.010759,.008368,
.010464,.009,
.010064,.009571,
.009571,.010064,
.009,.010464,
.008368,.010759,
.007695,.010939,
.007,.011,
-.007,.011,
-.007695,.010939,
-.008368,.010759,
-.009,.010464,
-.009571,.010064,
-.010064,.009571,
-.010464,.009,
-.010759,.008368,
-.010939,.007695,
-.011,.007,
-.011,-.007,
-.010939,-.007695,
-.010759,-.008368,
-.010464,-.009,
-.010064,-.009571,
-.009571,-.010064,
-.009,-.010464,
-.008368,-.010759,
-.007695,-.010939,
-.007,-.011,
0.0*
%
%ADD13MACRO13*%
%AMMACRO19*
4,1,40,-.011,.007,
-.011,-.007,
-.010939,-.007695,
-.010759,-.008368,
-.010464,-.009,
-.010064,-.009571,
-.009571,-.010064,
-.009,-.010464,
-.008368,-.010759,
-.007695,-.010939,
-.007,-.011,
.007,-.011,
.007695,-.010939,
.008368,-.010759,
.009,-.010464,
.009571,-.010064,
.010064,-.009571,
.010464,-.009,
.010759,-.008368,
.010939,-.007695,
.011,-.007,
.011,.007,
.010939,.007695,
.010759,.008368,
.010464,.009,
.010064,.009571,
.009571,.010064,
.009,.010464,
.008368,.010759,
.007695,.010939,
.007,.011,
-.007,.011,
-.007695,.010939,
-.008368,.010759,
-.009,.010464,
-.009571,.010064,
-.010064,.009571,
-.010464,.009,
-.010759,.008368,
-.010939,.007695,
-.011,.007,
0.0*
%
%ADD19MACRO19*%
%ADD108C,.012*%
%ADD109C,.014*%
%ADD110C,.024*%
%ADD111C,.025*%
%ADD112C,.016*%
%ADD113C,.018*%
%ADD114C,.006*%
%ADD115C,.005*%
%ADD116C,.008*%
%ADD117C,.00675*%
%ADD122C,.05004*%
%ADD121C,.05204*%
%ADD120C,.04604*%
%ADD119C,.12504*%
%ADD118R,.008X.008*%
G75*
%LPD*%
G75*
G36*
G01X882002Y1434128D02*
X828068Y1488063D01*
X783465D01*
G02X771528Y1500000I0J11937D01*
G01Y1511685D01*
X725913D01*
Y1509054D01*
G02X716981Y1497502I-11937J1D01*
G02X713979Y1497118I-3003J11553D01*
G01X688383D01*
G02X685381Y1497502I1J11937D01*
G02X676449Y1509054I3005J11553D01*
G01Y1511685D01*
X505244D01*
Y1500000D01*
G02X503822Y1494350I-11937J0D01*
G01X498957Y1489485D01*
G02X493307Y1488063I-5650J10515D01*
G01X288583D01*
G02X276646Y1500000I0J11937D01*
G01Y1511685D01*
X105441D01*
Y1509054D01*
G02X96509Y1497502I-11937J1D01*
G02X93507Y1497118I-3003J11553D01*
G01X67912D01*
G02X64909Y1497502I0J11937D01*
G02X55976Y1509055I3004J11553D01*
G01Y1511685D01*
X19811D01*
Y1465689D01*
X23814Y1461686D01*
X23824Y1461623D01*
G03X31733Y1449890I16776J2776D01*
G01X31867Y1449810D01*
G03X43370Y1447624I8732J14590D01*
G01X43471Y1447641D01*
X47299Y1443813D01*
X47310Y1443797D01*
G03X80699Y1445988I16064J10703D01*
G01X80746Y1446035D01*
X86720D01*
X91634Y1441121D01*
Y1437604D01*
X114742Y1414496D01*
X114724Y1414394D01*
G03X117999Y1401675I15876J-2693D01*
G01Y1225800D01*
X108614Y1216415D01*
X108595Y1216403D01*
G03X88597Y1180292I22604J-36111D01*
G01Y1156692D01*
G03X90921Y1142813I42605J0D01*
G01Y1111663D01*
X83264Y1104006D01*
X78794D01*
Y1094009D01*
X78341Y1093556D01*
X76244D01*
Y1091459D01*
X48541Y1063756D01*
X36444D01*
X32744Y1060056D01*
Y1046459D01*
X32499Y1046214D01*
Y1027286D01*
X32744Y1027041D01*
Y998744D01*
X38041D01*
X40494Y996291D01*
Y980833D01*
G03X48825Y955514I12756J-9833D01*
G03X49403Y954903I11428J10232D01*
G01X49494Y954812D01*
Y953494D01*
X50814D01*
X50872Y953438D01*
G03X52093Y952383I10626J11064D01*
G03X70344Y949945I10907J12117D01*
G03X74241Y951894I-4844J14555D01*
G01X87874D01*
X90921Y948847D01*
Y942038D01*
X86585Y937702D01*
X8000D01*
Y477962D01*
X23001D01*
X56866Y444098D01*
X102289D01*
X106394Y439993D01*
Y427900D01*
G03X122800Y411494I16406J0D01*
G01X127600D01*
G03X139577Y416688I0J16406D01*
G01X171448D01*
Y416547D01*
X175500Y412495D01*
Y406997D01*
G03X168089Y393607I8391J-13390D01*
G01Y392207D01*
G03X169840Y384978I15803J1D01*
G01Y354963D01*
X169338Y354462D01*
G03X164798Y343501I10962J-10961D01*
G01Y335346D01*
X164788Y335316D01*
G03X164798Y325254I15512J-5016D01*
G01Y310298D01*
X162676Y308176D01*
X157654D01*
X157600Y308219D01*
G03X114324Y313898I-26399J-33438D01*
G01X114286Y313882D01*
X111502D01*
X108640Y316744D01*
Y400854D01*
X101273Y408221D01*
Y410852D01*
X98642D01*
X95342Y414152D01*
G03X89498Y417806I-10847J-10847D01*
G01Y419411D01*
X79639D01*
G03X60245I-9697J-12856D01*
G01X53886D01*
Y414384D01*
X41453D01*
Y407397D01*
G03X33956Y393953I8306J-13444D01*
G01Y392552D01*
G03X35706Y385324I15803J0D01*
G01Y370135D01*
G03X39033Y360539I15502J0D01*
G03X41798Y356504I14679J7094D01*
G01Y255299D01*
G03X46338Y244338I15502J0D01*
G01X51138Y239538D01*
G03X51342Y239338I10954J10969D01*
G01X51403Y239279D01*
Y237899D01*
X53070D01*
X53122Y237862D01*
G03X62099Y234998I8977J12638D01*
G01X75512D01*
X77960Y232550D01*
Y229746D01*
X90921Y216785D01*
Y201438D01*
G03X85356Y198506I4579J-15438D01*
G01X78794D01*
Y188509D01*
X78341Y188056D01*
X76244D01*
Y185959D01*
X48541Y158256D01*
X36444D01*
Y149926D01*
G03X36323Y149756I13058J-9423D01*
G01X32744D01*
Y140959D01*
X32499Y140714D01*
Y121786D01*
X32744Y121541D01*
Y93244D01*
X38041D01*
X40494Y90791D01*
Y85550D01*
X38047Y83103D01*
X30488D01*
G03X23001Y81250I13J-16103D01*
G03X16263Y74525I7498J-14251D01*
G01X16249Y74498D01*
X8000Y66249D01*
Y8000D01*
X58659D01*
X64697Y14038D01*
G03X77653Y26321I-5297J18562D01*
G03X75759Y42847I-18253J6280D01*
G01X75728Y42896D01*
Y44634D01*
X77599Y46505D01*
X77677Y46508D01*
G03X79612Y46692I-573J16293D01*
G01X79627Y46694D01*
X87412D01*
X90921Y43185D01*
Y8000D01*
X258052D01*
Y23001D01*
G03X258743Y28239I-15403J4697D01*
G01X258740Y28326D01*
X262077Y31663D01*
Y35494D01*
X264124Y37541D01*
X264169Y37556D01*
G03X275201Y52769I-4973J15213D01*
G01Y65269D01*
G03X268292Y78439I-16007J0D01*
G01X268206Y78498D01*
Y80319D01*
G03X262077Y92914I-16006J0D01*
G01Y105181D01*
G03X264400Y106594I-7179J14418D01*
G01X273478D01*
X277350Y102722D01*
Y97793D01*
X281244Y93899D01*
Y93244D01*
X281899D01*
X288994Y86149D01*
Y75333D01*
G03X297994Y49838I12756J-9833D01*
G01Y47994D01*
X298394Y47594D01*
X320286D01*
G03X331481Y47582I5614J15306D01*
G01X331514Y47594D01*
X337018D01*
X339346Y45266D01*
Y8000D01*
X382265D01*
Y23001D01*
G03X382841Y29692I-15403J4696D01*
G01X382829Y29789D01*
X384703Y31663D01*
X386290D01*
Y35835D01*
X387846Y37391D01*
X387895Y37405D01*
G03X399414Y52769I-4487J15364D01*
G01Y64893D01*
X400674Y66153D01*
X403311D01*
X403360Y66121D01*
G03X407244Y63965I18288J28370D01*
G01Y28344D01*
X413441D01*
X424194Y17591D01*
Y8000D01*
X506477D01*
Y23001D01*
G03X507168Y28239I-15403J4697D01*
G01X507165Y28326D01*
X510502Y31663D01*
Y35158D01*
X513060Y37716D01*
G03X523626Y52769I-5440J15053D01*
G01Y65269D01*
G03X516717Y78439I-16007J0D01*
G01X516631Y78498D01*
Y80319D01*
G03X510502Y92914I-16006J0D01*
G01Y104809D01*
G03X513400Y106494I-6603J14691D01*
G01X522339D01*
X529744Y99089D01*
Y93244D01*
X532379D01*
X537494Y88129D01*
Y75333D01*
G03X546494Y49838I12756J-9833D01*
G01Y47994D01*
X553394D01*
Y47694D01*
X568412D01*
G03X580153Y47681I5887J15206D01*
G01X580188Y47694D01*
X584806D01*
X587771Y44729D01*
Y8000D01*
X775465D01*
Y140456D01*
X769460D01*
X769436Y140629D01*
G03X763740Y150874I-15963J-2169D01*
G01Y222254D01*
X748654Y237340D01*
X712962D01*
X709900Y240402D01*
Y277100D01*
X708614D01*
Y337397D01*
G03X708564Y347642I-15502J5047D01*
G03X704074Y357350I-15452J-1254D01*
G01X702206Y359217D01*
Y409325D01*
X703382Y410501D01*
X705659D01*
X707079Y409081D01*
Y407884D01*
X707068Y407852D01*
G03X704641Y393679I40176J-14174D01*
G01Y370078D01*
G03X789847I42603J0D01*
G01Y375213D01*
X795629Y380995D01*
X810907D01*
X814146Y377756D01*
Y325986D01*
G03X810266Y315354I12627J-10632D01*
G01Y262992D01*
G03X810491Y260277I16506J1D01*
G03X810411Y259193I16209J-1741D01*
G01X810403Y259004D01*
Y244000D01*
X811957D01*
Y198500D01*
X811960D01*
Y193701D01*
G02X811024Y192765I-936J0D01*
G01X806235D01*
X806232Y192768D01*
X787402D01*
G03X780461Y185827I0J-6941D01*
G01Y3937D01*
G02X779528Y3004I-933J0D01*
G01X3937D01*
G02X3004Y3937I0J933D01*
G01Y1456693D01*
G02X3937Y1457626I933J0D01*
G01X7874D01*
G03X14815Y1464567I0J6941D01*
G01Y1515748D01*
G02X15748Y1516681I933J0D01*
G01X60039D01*
G02X60972Y1515748I0J-933D01*
G01Y1509055D01*
G03X64909Y1502798I6941J0D01*
G03X67913Y1502114I3005J6257D01*
G01X93504D01*
G03X100445Y1509055I0J6941D01*
G01Y1515748D01*
G02X101378Y1516681I933J0D01*
G01X280709D01*
G02X281642Y1515748I0J-933D01*
G01Y1500000D01*
G03X288583Y1493059I6941J0D01*
G01X493307D01*
G03X500248Y1500000I0J6941D01*
G01Y1515748D01*
G02X501181Y1516681I933J0D01*
G01X680512D01*
G02X681445Y1515748I0J-933D01*
G01Y1509055D01*
G03X688386Y1502114I6941J0D01*
G01X713976D01*
G03X720917Y1509055I0J6941D01*
G01Y1515748D01*
G02X721850Y1516681I933J0D01*
G01X775591D01*
G02X776524Y1515748I0J-933D01*
G01Y1500000D01*
G03X783465Y1493059I6941J0D01*
G01X988189D01*
G03X995130Y1500000I0J6941D01*
G01Y1515748D01*
G02X996063Y1516681I933J0D01*
G01X1059198D01*
G02X1059856Y1516408I-1J-933D01*
G01X1069361Y1506903D01*
G02X1069634Y1506245I-660J-660D01*
G01Y1499000D01*
X1064638D01*
Y1504561D01*
X1057514Y1511685D01*
X1000126D01*
Y1500000D01*
G02X988189Y1488063I-11937J0D01*
G01X977817D01*
Y1476380D01*
X971515Y1470078D01*
X971399Y1470115D01*
G03X962546Y1470403I-4937J-15537D01*
G01X932510D01*
X927910Y1465803D01*
Y1419313D01*
X925358Y1416761D01*
X920803D01*
X920763Y1416780D01*
G03X907685Y1417037I-6828J-14584D01*
G03X895143Y1417019I-6250J-14841D01*
G03X890824Y1418200I-6366J-14791D01*
G03X884079Y1425051I-14324J-7357D01*
G01X882002Y1427128D01*
Y1434128D01*
G37*
G36*
G01X91000Y86000D02*
X72500D01*
X71500Y87000D01*
Y96000D01*
X72500Y97000D01*
X91000D01*
X92000Y96000D01*
Y87000D01*
X91000Y86000D01*
G37*
G36*
G01X82500Y137000D02*
X77500D01*
X77000Y137500D01*
Y143500D01*
X82500Y149000D01*
X88000D01*
X107500Y168500D01*
X123000D01*
X123500Y168000D01*
Y165000D01*
X123000Y164500D01*
X110000D01*
X82500Y137000D01*
G37*
G36*
G01X98000Y121800D02*
X90600D01*
X90000Y122400D01*
Y128000D01*
X92100Y130100D01*
X97100D01*
X105500Y138500D01*
X123000D01*
X123500Y138000D01*
Y135000D01*
X123000Y134500D01*
X110700D01*
X98000Y121800D01*
G37*
G36*
G01X68000Y127000D02*
X48500D01*
X47500Y128000D01*
Y134500D01*
X48500Y135500D01*
X57000D01*
X59000Y137500D01*
Y147500D01*
X89500Y178000D01*
X123000D01*
X123500Y177500D01*
Y170500D01*
X123000Y170000D01*
X99500D01*
X97000Y167500D01*
X90500D01*
X73500Y150500D01*
Y137133D01*
X69000Y132633D01*
Y128000D01*
X68000Y127000D01*
G37*
G36*
G01X77500Y109000D02*
X76500Y110000D01*
Y119000D01*
X77500Y120000D01*
Y128000D01*
X80500Y131000D01*
Y134952D01*
X81346Y135798D01*
X82998D01*
X83199Y136000D01*
X84000D01*
X96000Y148000D01*
X123000D01*
X123500Y147500D01*
Y140500D01*
X123000Y140000D01*
X103000D01*
X95500Y132500D01*
X92000D01*
X88500Y129000D01*
Y119000D01*
X91000Y116500D01*
Y110000D01*
X90000Y109000D01*
X77500D01*
G37*
G36*
G01X57500Y99000D02*
X56000D01*
X52000Y103000D01*
X49500D01*
X48000Y104500D01*
Y114500D01*
X49000Y115500D01*
X62000D01*
X63000Y114500D01*
Y106625D01*
X59375Y103000D01*
X58910D01*
X57893Y101983D01*
Y99393D01*
X57500Y99000D01*
G37*
G36*
G01X49494Y500494D02*
X56394D01*
Y500194D01*
X70597D01*
G03X83612Y500111I6603J14906D01*
G03X83950Y500188I-3238J14994D01*
G01X83973Y500194D01*
X88606D01*
X90921Y497879D01*
Y477644D01*
X88379Y475102D01*
X69708D01*
X34390Y510421D01*
Y544142D01*
X35992Y545744D01*
X38041D01*
X40494Y543291D01*
Y527833D01*
G03X49494Y502338I12756J-9833D01*
G01Y500494D01*
G37*
G36*
G01X77500Y561500D02*
X76500Y562500D01*
Y571500D01*
X77500Y572500D01*
Y580500D01*
X80500Y583500D01*
Y587051D01*
X81449Y588000D01*
X83500D01*
X96000Y600500D01*
X123000D01*
X123500Y600000D01*
Y593000D01*
X123000Y592500D01*
X103000D01*
X95500Y585000D01*
X92000D01*
X88500Y581500D01*
Y571500D01*
X91000Y569000D01*
Y562500D01*
X90000Y561500D01*
X77500D01*
G37*
G36*
G01X56000Y551500D02*
X52000Y555500D01*
X49500D01*
X48000Y557000D01*
Y567000D01*
X49000Y568000D01*
X62000D01*
X63000Y567000D01*
Y559182D01*
X59318Y555500D01*
X58937D01*
X58415Y554978D01*
X58412Y554975D01*
G03X58325Y554888I1088J-1175D01*
G01X58322Y554885D01*
X57887Y554450D01*
Y551887D01*
X57500Y551500D01*
X56000D01*
G37*
G36*
G01X91000Y538500D02*
X72500D01*
X71500Y539500D01*
Y548500D01*
X72500Y549500D01*
X91000D01*
X92000Y548500D01*
Y539500D01*
X91000Y538500D01*
G37*
G36*
G01X82500Y589500D02*
X77500D01*
X77000Y590000D01*
Y596000D01*
X82500Y601500D01*
X88000D01*
X107500Y621000D01*
X123000D01*
X123500Y620500D01*
Y617500D01*
X123000Y617000D01*
X110000D01*
X82500Y589500D01*
G37*
G36*
G01X98288Y574656D02*
X90388D01*
X89788Y575256D01*
Y580756D01*
X92088Y583056D01*
X97088D01*
X105288Y591256D01*
X122788D01*
X123288Y590756D01*
Y587756D01*
X122788Y587256D01*
X110888D01*
X98288Y574656D01*
G37*
G36*
G01X48585Y610800D02*
X36969D01*
X34390Y613379D01*
Y661272D01*
X35545Y662427D01*
X38387D01*
X53639Y647175D01*
X77212D01*
X78794Y645593D01*
Y641009D01*
X78341Y640556D01*
X76244D01*
Y638459D01*
X48585Y610800D01*
G37*
G36*
G01X68000Y579500D02*
X48500D01*
X47500Y580500D01*
Y587000D01*
X48500Y588000D01*
X57000D01*
X59000Y590000D01*
Y600000D01*
X89500Y630500D01*
X123000D01*
X123500Y630000D01*
Y623000D01*
X123000Y622500D01*
X99500D01*
X97000Y620000D01*
X90500D01*
X73500Y603000D01*
Y589547D01*
X69000Y585047D01*
Y580500D01*
X68000Y579500D01*
G37*
G36*
G01X87552Y814933D02*
X89002Y816384D01*
Y823994D01*
X90206D01*
Y828523D01*
X93843Y832160D01*
X139453D01*
X139454Y832161D01*
X142119D01*
X144840Y829440D01*
Y827215D01*
G03X149380Y816254I15502J0D01*
G01X150970Y814664D01*
X150984Y814636D01*
G03X158078Y807542I14516J7422D01*
G01X158106Y807528D01*
X161038Y804597D01*
Y767672D01*
X158824Y765458D01*
X150618D01*
X150575Y765480D01*
G03X96370Y752070I-19374J-37943D01*
G01X96310Y751985D01*
X89727D01*
X87552Y754160D01*
Y803059D01*
G03X87562Y813121I-15503J5046D01*
G01X87552Y813151D01*
Y814933D01*
G37*
G36*
G01X79835Y869425D02*
X77835Y871425D01*
Y891453D01*
X80968Y894586D01*
X90657D01*
X91400Y893843D01*
Y876326D01*
X91342D01*
Y870068D01*
X90700Y869425D01*
X79835D01*
G37*
G36*
G01X75863Y904025D02*
X73863Y906025D01*
Y910825D01*
X74463Y911425D01*
X83763D01*
X85463Y909725D01*
Y907925D01*
X87163Y906225D01*
Y904425D01*
X86763Y904025D01*
X83092D01*
X83053Y904042D01*
G03X82400Y904182I-655J-1462D01*
G01X81000D01*
G03X80347Y904042I2J-1602D01*
G01X80308Y904025D01*
X78825D01*
X78793Y904036D01*
G03X78263Y904126I-529J-1511D01*
G01X76863D01*
G03X76333Y904036I-1J-1601D01*
G01X76301Y904025D01*
X75863D01*
G37*
G36*
G01X67251Y871048D02*
X63084Y875215D01*
Y884339D01*
X63876Y885131D01*
X69783D01*
X69814Y885121D01*
G03X71392I789J2374D01*
G01X71423Y885131D01*
X74423D01*
X74743Y884811D01*
Y871349D01*
X74442Y871048D01*
X67251D01*
G37*
G36*
G01X82500Y1042500D02*
X77500D01*
X77000Y1043000D01*
Y1055300D01*
X83350Y1061650D01*
X95150D01*
X107500Y1074000D01*
X123000D01*
X123500Y1073500D01*
Y1070500D01*
X123000Y1070000D01*
X110000D01*
X82500Y1042500D01*
G37*
G36*
G01X98288Y1027412D02*
X90388D01*
X89788Y1028012D01*
Y1033512D01*
X92088Y1035812D01*
X97088D01*
X105288Y1044012D01*
X122788D01*
X123288Y1043512D01*
Y1040512D01*
X122788Y1040012D01*
X110888D01*
X98288Y1027412D01*
G37*
G36*
G01X63000Y1012059D02*
X59441Y1008500D01*
X59000D01*
X58670Y1008170D01*
X58650Y1008158D01*
G03X58142Y1007650I850J-1358D01*
G01X58130Y1007630D01*
X58000Y1007500D01*
Y1007362D01*
X57989Y1007330D01*
G03X57898Y1006800I1511J-532D01*
G01Y1005200D01*
G03X57910Y1005004I1602J0D01*
G01Y1004910D01*
X57500Y1004500D01*
X56000D01*
X52000Y1008500D01*
X49500D01*
X48000Y1010000D01*
Y1020000D01*
X49000Y1021000D01*
X62000D01*
X63000Y1020000D01*
Y1012059D01*
G37*
G36*
G01X70340Y1038840D02*
X69000Y1037500D01*
Y1033500D01*
X68000Y1032500D01*
X48500D01*
X47500Y1033500D01*
Y1040000D01*
X48500Y1041000D01*
X57000D01*
X59000Y1043000D01*
Y1053000D01*
X89500Y1083500D01*
X123000D01*
X123500Y1083000D01*
Y1076000D01*
X123000Y1075500D01*
X99500D01*
X97000Y1073000D01*
X90500D01*
X73500Y1056000D01*
Y1042000D01*
X72160Y1040660D01*
X72103Y1040648D01*
G03X70352Y1038897I497J-2248D01*
G01X70340Y1038840D01*
G37*
G36*
G01X91000Y991500D02*
X72500D01*
X71500Y992500D01*
Y1001500D01*
X72500Y1002500D01*
X91000D01*
X92000Y1001500D01*
Y992500D01*
X91000Y991500D01*
G37*
G36*
G01X90000Y1014500D02*
X77500D01*
X76500Y1015500D01*
Y1024500D01*
X77500Y1025500D01*
Y1033500D01*
X80500Y1036500D01*
Y1039500D01*
X82000Y1041000D01*
X83500D01*
X96000Y1053500D01*
X123000D01*
X123500Y1053000D01*
Y1046000D01*
X123000Y1045500D01*
X103000D01*
X95500Y1038000D01*
X92000D01*
X88500Y1034500D01*
Y1024500D01*
X91000Y1022000D01*
Y1015500D01*
X90000Y1014500D01*
G37*
G36*
G01X137865Y104262D02*
G03X141444Y106352I-6265J14838D01*
G01X141498Y106394D01*
X143806D01*
Y108592D01*
X143854Y108648D01*
G03X144602Y109594I-12251J10456D01*
G01X152981D01*
X155244Y107331D01*
Y90365D01*
X146834Y81955D01*
X145331D01*
X143645Y83641D01*
G03X137865Y92914I-15657J-3321D01*
G01Y104262D01*
G37*
G36*
G01X184460Y74253D02*
X180082D01*
X176693Y77642D01*
X174265D01*
X170500Y81407D01*
Y89000D01*
X171500Y90000D01*
X184500D01*
X185500Y89000D01*
Y75293D01*
X184460Y74253D01*
G37*
G36*
G01X145737Y24037D02*
X141800Y20100D01*
X137500D01*
X136850Y20750D01*
Y33450D01*
X137280Y33880D01*
X139574D01*
X140244Y34550D01*
X146250D01*
X147100Y33700D01*
Y28050D01*
X146305Y27255D01*
X146296Y27248D01*
G03X146052Y27004I1004J-1248D01*
G01X146045Y26995D01*
X145950Y26900D01*
Y26863D01*
X145922Y26816D01*
G03X145698Y26000I1378J-817D01*
G01Y24400D01*
G03X145720Y24138I1602J3D01*
G01X145737Y24037D01*
G37*
G36*
G01X157075Y148700D02*
X155840Y149935D01*
Y188253D01*
X168556Y200969D01*
X200369D01*
X202700Y198638D01*
Y190017D01*
X200744Y188061D01*
Y186459D01*
X172541Y158256D01*
X160444D01*
Y149926D01*
G03X159641Y148700I13055J-9427D01*
G01X157075D01*
G37*
G36*
G01X190000Y102500D02*
X171500D01*
X170500Y103500D01*
Y109500D01*
X180000Y119000D01*
Y133000D01*
X183000Y136000D01*
Y147500D01*
X213500Y178000D01*
X247000D01*
X247500Y177500D01*
Y170500D01*
X247000Y170000D01*
X223500D01*
X221000Y167500D01*
X214500D01*
X197500Y150500D01*
Y137005D01*
X191000Y130505D01*
Y103500D01*
X190000Y102500D01*
G37*
G36*
G01X174318Y239147D02*
X175566Y237899D01*
X176014D01*
X176067Y237860D01*
G03X185248Y234848I9182J12490D01*
G01X194852D01*
G03X204086Y237899I-1J15502D01*
G01X212967D01*
Y277061D01*
X211764D01*
Y330840D01*
X212743Y331819D01*
X214417D01*
X215360Y330876D01*
Y233674D01*
X173032D01*
X171431Y235275D01*
Y237164D01*
X171442Y237196D01*
G03X172068Y239147I-40241J13988D01*
G01X174318D01*
G37*
G36*
G01X177662Y431689D02*
X175662Y433689D01*
Y453717D01*
X178795Y456850D01*
X188484D01*
X189227Y456107D01*
Y438590D01*
X189170D01*
Y432332D01*
X188527Y431689D01*
X177662D01*
G37*
G36*
G01X173690Y466289D02*
X171690Y468289D01*
Y473089D01*
X172290Y473689D01*
X181590D01*
X183290Y471989D01*
Y470189D01*
X184990Y468489D01*
Y466689D01*
X184590Y466289D01*
X180919D01*
X180880Y466306D01*
G03X180227Y466446I-655J-1462D01*
G01X178827D01*
G03X178174Y466306I2J-1602D01*
G01X178135Y466289D01*
X176652D01*
X176620Y466300D01*
G03X176090Y466390I-529J-1511D01*
G01X174690D01*
G03X174160Y466300I-1J-1601D01*
G01X174128Y466289D01*
X173690D01*
G37*
G36*
G01X165067Y433312D02*
X160911Y437468D01*
Y446603D01*
X161703Y447395D01*
X167610D01*
X167641Y447385D01*
G03X169219I789J2374D01*
G01X169250Y447395D01*
X172250D01*
X172679Y446966D01*
Y433722D01*
X172269Y433312D01*
X165067D01*
G37*
G36*
G01X143994Y533075D02*
G03X137865Y545670I-16006J0D01*
G01Y556953D01*
X140315Y559403D01*
X140400Y559401D01*
G03X150589Y562752I351J16099D01*
G01X150643Y562794D01*
X154432D01*
X156744Y560482D01*
Y545744D01*
X157841D01*
X160788Y542797D01*
X160765Y542691D01*
G03X162045Y532211I15741J-3396D01*
G03X160435Y523207I14394J-7220D01*
G01X160436Y523196D01*
Y520661D01*
G03X164600Y509894I16003J0D01*
G01Y501227D01*
X162839Y499466D01*
X153811D01*
X150990Y502287D01*
Y508667D01*
X150989D01*
Y518025D01*
G03X144080Y531195I-16007J0D01*
G01X143994Y531254D01*
Y533075D01*
G37*
G36*
G01X173300Y551500D02*
X172000Y552800D01*
Y567000D01*
X173000Y568000D01*
X186000D01*
X187000Y567000D01*
Y559059D01*
X183441Y555500D01*
X183000D01*
X182670Y555170D01*
X182650Y555158D01*
G03X182142Y554650I850J-1358D01*
G01X182130Y554630D01*
X182000Y554500D01*
Y554362D01*
X181989Y554330D01*
G03X181898Y553800I1511J-532D01*
G01Y552200D01*
G03X181910Y552004I1602J0D01*
G01Y551910D01*
X181500Y551500D01*
X173300D01*
G37*
G36*
G01X173085Y611300D02*
X160513D01*
X158840Y612973D01*
Y646983D01*
X161532Y649675D01*
X201189D01*
X202794Y648070D01*
Y641009D01*
X202341Y640556D01*
X200744D01*
Y638959D01*
X173085Y611300D01*
G37*
G36*
G01X172500Y579500D02*
X171500Y580500D01*
Y587000D01*
X172500Y588000D01*
X181000D01*
X183000Y590000D01*
Y600000D01*
X213500Y630500D01*
X247000D01*
X247500Y630000D01*
Y623000D01*
X247000Y622500D01*
X223500D01*
X221000Y620000D01*
X214500D01*
X197500Y603000D01*
Y589000D01*
X195900Y587400D01*
X195885Y587389D01*
G03X195311Y586815I1315J-1889D01*
G01X195300Y586800D01*
X193000Y584500D01*
Y580500D01*
X192000Y579500D01*
X172500D01*
G37*
G36*
G01X172314Y689688D02*
X175680D01*
X175733Y689647D01*
G03X185099Y686498I9366J12353D01*
G01X194101D01*
G03X204665Y690655I0J15502D01*
G01X212967D01*
Y729817D01*
X211764D01*
Y802807D01*
G03X211774Y812869I-15503J5046D01*
G01X211764Y812899D01*
Y823994D01*
X212706D01*
Y853402D01*
X223352Y864048D01*
X265021D01*
X269789Y859280D01*
Y845207D01*
G03X271540Y837978I15803J1D01*
G01Y825957D01*
G03X276080Y814996I15502J0D01*
G01X279470Y811606D01*
X279484Y811578D01*
G03X286138Y804718I14515J7422D01*
G01Y710859D01*
G03X290678Y699898I15502J0D01*
G01X299828Y690748D01*
Y690655D01*
X299921D01*
X300438Y690138D01*
G03X311399Y685598I10961J10962D01*
G01X318301D01*
G03X329262Y690138I0J15502D01*
G01X329724Y690600D01*
X336330D01*
X338490Y688440D01*
Y684373D01*
X336932Y682815D01*
X171014D01*
X169753Y684076D01*
Y685808D01*
X169772Y685848D01*
G03X170750Y688101I-38574J18083D01*
G01X170765Y688139D01*
X172314Y689688D01*
G37*
G36*
G01X131127Y923296D02*
X131169Y923350D01*
G03X134531Y933751I-12732J9859D01*
G01X134528Y933838D01*
X137865Y937175D01*
Y940983D01*
X139946Y943064D01*
G03X150989Y958281I-4963J15217D01*
G01Y970781D01*
G03X144080Y983951I-16007J0D01*
G01X143994Y984010D01*
Y985832D01*
G03X141487Y994432I-16006J-1D01*
G03X137865Y1002816I-15987J-1932D01*
G01Y1010037D01*
X140234Y1012406D01*
X140320Y1012403D01*
G03X150589Y1015752I431J16097D01*
G01X150643Y1015794D01*
X154240D01*
X157244Y1012790D01*
Y998744D01*
X162541D01*
X164994Y996291D01*
Y989794D01*
X165194D01*
Y987195D01*
X165156Y987143D01*
G03X162197Y975915I13044J-9442D01*
G01X162198Y975904D01*
Y973099D01*
G03X165194Y963777I16002J0D01*
G01Y954894D01*
X172594D01*
X173994Y953494D01*
X180594D01*
X180894Y953194D01*
X195721D01*
G03X207445Y953181I5879J15206D01*
G01X207479Y953194D01*
X213696D01*
X215133Y951757D01*
Y915623D01*
X212415Y912905D01*
X208944D01*
G03X193763Y923631I-15181J-5380D01*
G01X184647D01*
G03X176395Y934661I-15784J-3207D01*
G03X163860Y940654I-12535J-10113D01*
G01X159860D01*
G03X147466Y934834I0J-16107D01*
G03X138557Y920425I7198J-14409D01*
G01Y916423D01*
G03X139661Y910563I16106J0D01*
G01X139675Y910528D01*
Y908945D01*
X137132Y906402D01*
X133235D01*
X132430Y907207D01*
Y907744D01*
X132435Y907766D01*
G03X131148Y918880I-16172J3759D01*
G01X131127Y918922D01*
Y923296D01*
G37*
G36*
G01X173000Y1032500D02*
X172000Y1033500D01*
Y1040000D01*
X173000Y1041000D01*
X181500D01*
X183500Y1043000D01*
Y1053000D01*
X214000Y1083500D01*
X247500D01*
X248000Y1083000D01*
Y1076000D01*
X247500Y1075500D01*
X224000D01*
X221500Y1073000D01*
X215000D01*
X198000Y1056000D01*
Y1042000D01*
X196731Y1040731D01*
X196681Y1040717D01*
G03X195083Y1039119I619J-2217D01*
G01X195069Y1039069D01*
X193500Y1037500D01*
Y1033500D01*
X192500Y1032500D01*
X173000D01*
G37*
G36*
G01X180500Y1004500D02*
X176500Y1008500D01*
X174000D01*
X172500Y1010000D01*
Y1020000D01*
X173500Y1021000D01*
X186500D01*
X187500Y1020000D01*
Y1012059D01*
X183941Y1008500D01*
X183500D01*
X183170Y1008170D01*
X183150Y1008158D01*
G03X182642Y1007650I850J-1358D01*
G01X182630Y1007630D01*
X182500Y1007500D01*
Y1007362D01*
X182489Y1007330D01*
G03X182398Y1006800I1511J-532D01*
G01Y1005200D01*
G03X182410Y1005004I1602J0D01*
G01Y1004910D01*
X182000Y1004500D01*
X180500D01*
G37*
G36*
G01X173585Y1064300D02*
X162757D01*
X158840Y1068217D01*
Y1105386D01*
X165854Y1112400D01*
X199807D01*
X203294Y1108913D01*
Y1094009D01*
X202841Y1093556D01*
X200744D01*
Y1091459D01*
X173585Y1064300D01*
G37*
G36*
G01X328778Y1143080D02*
X183574D01*
X173803Y1152851D01*
Y1198570D01*
X189232Y1213999D01*
X328372D01*
X336629Y1205742D01*
Y1150931D01*
X328778Y1143080D01*
G37*
G36*
G01X187076Y1410178D02*
Y1411410D01*
X187098Y1411453D01*
G03X187358Y1412298I-2224J1147D01*
G01X187366Y1412366D01*
X190500Y1415500D01*
Y1416013D01*
X190506Y1416037D01*
G03Y1417163I-2232J563D01*
G01X190500Y1417187D01*
Y1417500D01*
X190292Y1417708D01*
X190279Y1417732D01*
G03X189406Y1418605I-2005J-1132D01*
G01X189382Y1418618D01*
X189000Y1419000D01*
X182153D01*
X182108Y1419046D01*
X181495D01*
X181470Y1419052D01*
G03X181074Y1419102I-397J-1552D01*
G01X179674D01*
G03X179511Y1419093I7J-1602D01*
G01X179416Y1419084D01*
X178576Y1419924D01*
Y1423098D01*
X178500Y1423173D01*
Y1433000D01*
X180000Y1434500D01*
X183500D01*
X192000Y1426000D01*
X205000D01*
X206500Y1424500D01*
Y1297687D01*
X220174Y1284013D01*
X800830D01*
X806149Y1289332D01*
Y1316392D01*
X806757Y1317000D01*
X813500D01*
X815000Y1318500D01*
Y1326500D01*
X816000Y1327500D01*
X823500D01*
X825500Y1329500D01*
Y1336000D01*
X823500Y1338000D01*
X809702D01*
X806551Y1341151D01*
Y1358945D01*
X806904Y1359298D01*
X812998D01*
X813011Y1359312D01*
X813812D01*
X815000Y1360500D01*
Y1365000D01*
X816500Y1366500D01*
X824000D01*
X825500Y1368000D01*
Y1374500D01*
X823500Y1376500D01*
X816000D01*
X812500Y1380000D01*
X810000D01*
X806538Y1383462D01*
Y1396712D01*
X807124Y1397298D01*
X825284D01*
X825304Y1397319D01*
X827681D01*
X836800Y1388200D01*
X837601D01*
X837658Y1388142D01*
X842032D01*
X842089Y1388200D01*
X868513D01*
X868553Y1388181D01*
G03X869237Y1388028I683J1448D01*
G01X870637D01*
G03X871321Y1388181I1J1601D01*
G01X871361Y1388200D01*
X946044D01*
X946045Y1388198D01*
X952302D01*
X953300Y1387200D01*
Y1364100D01*
X951900Y1362700D01*
X942800D01*
X939900Y1359800D01*
Y1353200D01*
X941400Y1351700D01*
X943298D01*
Y1351694D01*
X952700D01*
Y1329800D01*
X954500Y1328000D01*
X963100D01*
X965900Y1325200D01*
Y1290849D01*
X973812Y1282937D01*
X1296565D01*
X1300679Y1287051D01*
Y1377325D01*
X1326251Y1402897D01*
Y1407662D01*
G03X1326252Y1407700I-1600J61D01*
G01Y1409100D01*
G03X1326251Y1409138I-1601J-23D01*
G01Y1410174D01*
X1330200Y1414123D01*
Y1416408D01*
G03Y1416592I-2300J92D01*
G01Y1418000D01*
X1329349Y1418851D01*
X1324838D01*
G03X1324800Y1418852I-61J-1600D01*
G01X1323200D01*
G03X1323162Y1418851I23J-1601D01*
G01X1322715D01*
X1322464Y1419102D01*
X1320997D01*
X1320995Y1419104D01*
X1318336D01*
X1317900Y1419541D01*
Y1421640D01*
G02X1318336Y1422038I400J0D01*
G03Y1426624I204J2293D01*
G02X1317900Y1427022I-36J398D01*
G01Y1432800D01*
X1318100Y1433000D01*
X1329700D01*
X1330200Y1432500D01*
Y1426500D01*
X1334800Y1421900D01*
X1343500D01*
X1345500Y1419900D01*
Y1417500D01*
G03Y1414900I1900J-1300D01*
G01Y1405700D01*
X1348000Y1403200D01*
Y1287082D01*
X1352335Y1282747D01*
X1684173D01*
X1691388Y1289962D01*
Y1378267D01*
X1714500Y1401379D01*
Y1411500D01*
X1718400Y1415400D01*
Y1417600D01*
X1717200Y1418800D01*
X1716118D01*
G03X1715934I-92J-2300D01*
G01X1713330D01*
X1713306Y1418806D01*
G03X1712926Y1418852I-381J-1556D01*
G01X1711326D01*
G03X1710946Y1418806I1J-1602D01*
G01X1710922Y1418800D01*
X1709500D01*
X1709200Y1419100D01*
X1708391D01*
G03X1708326Y1419102I-82J-1599D01*
G01X1706926D01*
G03X1706861Y1419100I17J-1601D01*
G01X1706700D01*
X1706500Y1419300D01*
Y1422000D01*
X1707000Y1422500D01*
X1729000D01*
X1733397Y1418103D01*
G02X1733405Y1417829I-142J-141D01*
G03X1733500Y1414670I1721J-1529D01*
G01Y1406000D01*
X1741480Y1398020D01*
Y1254480D01*
X1722500Y1235500D01*
X958624D01*
G03X952376I-3124J-2500D01*
G01X950624D01*
G03X944376I-3124J-2500D01*
G01X626500D01*
X620000Y1229000D01*
X154000D01*
X133000Y1250000D01*
Y1385500D01*
X134000Y1386500D01*
X169573D01*
X187000Y1403927D01*
Y1407281D01*
G03X187226Y1408100I-1376J820D01*
G01Y1409500D01*
G03X187092Y1410140I-1602J-1D01*
G01X187076Y1410178D01*
G37*
G36*
G01X222879Y1410500D02*
X213000D01*
X212374Y1411126D01*
Y1416800D01*
X212074Y1417100D01*
Y1422900D01*
X207674Y1427300D01*
X193374D01*
X193324Y1427350D01*
X192924D01*
X192674Y1427600D01*
Y1438400D01*
X192974Y1438700D01*
X208074D01*
X209374Y1440000D01*
Y1474500D01*
X211024Y1476150D01*
X223624D01*
X224414Y1475360D01*
Y1412035D01*
X222879Y1410500D01*
G37*
G36*
G01X167774Y1408800D02*
X166874Y1409700D01*
Y1416000D01*
X169574Y1418700D01*
Y1419394D01*
X170076Y1419895D01*
Y1423995D01*
X170180Y1424100D01*
X175874D01*
X177374Y1422600D01*
Y1419300D01*
X178830Y1417844D01*
X181610D01*
X181874Y1417580D01*
Y1411811D01*
G02X181394Y1411419I-400J0D01*
G03X181074Y1411452I-323J-1569D01*
G01X179674D01*
G03X178243Y1410569I0J-1601D01*
G01X176474Y1408800D01*
X167774D01*
G37*
G36*
G01X196500Y86000D02*
X195840Y86660D01*
Y96340D01*
X196500Y97000D01*
X215000D01*
X216000Y96000D01*
Y87000D01*
X215000Y86000D01*
X196500D01*
G37*
G36*
G01X201500Y137000D02*
X201000Y137500D01*
Y143500D01*
X206500Y149000D01*
X212000D01*
X222248Y159248D01*
X222452D01*
Y159452D01*
X231500Y168500D01*
X247000D01*
X247500Y168000D01*
Y165000D01*
X247000Y164500D01*
X234000D01*
X206500Y137000D01*
X201500D01*
G37*
G36*
G01X222500Y121900D02*
X214600D01*
X214000Y122500D01*
Y128000D01*
X216300Y130300D01*
X221300D01*
X229500Y138500D01*
X247000D01*
X247500Y138000D01*
Y135000D01*
X247000Y134500D01*
X235100D01*
X222500Y121900D01*
G37*
G36*
G01X297085Y158300D02*
X283901D01*
X282619Y159582D01*
Y193805D01*
X287757Y198943D01*
X325379D01*
X327200Y197122D01*
Y188415D01*
X326841Y188056D01*
X324744D01*
Y185959D01*
X297085Y158300D01*
G37*
G36*
G01X214000Y109000D02*
X202300D01*
X201450Y109850D01*
Y119950D01*
X201500Y120000D01*
Y128000D01*
X204500Y131000D01*
Y134529D01*
X205471Y135500D01*
X207500D01*
X220000Y148000D01*
X247000D01*
X247500Y147500D01*
Y140500D01*
X247000Y140000D01*
X227000D01*
X219500Y132500D01*
X216000D01*
X212500Y129000D01*
Y119000D01*
X215000Y116500D01*
Y110000D01*
X214000Y109000D01*
G37*
G36*
G01X279470Y358906D02*
X279484Y358878D01*
G03X286138Y352018I14515J7422D01*
G01Y258159D01*
G03X290678Y247198I15502J0D01*
G01X295745Y242131D01*
Y239021D01*
X292423Y235699D01*
X246495D01*
X246040Y236154D01*
Y386838D01*
X249508Y390306D01*
X266115D01*
X271540Y384881D01*
Y373257D01*
G03X276080Y362296I15502J0D01*
G01X279470Y358906D01*
G37*
G36*
G01X280557Y428304D02*
X280600Y428358D01*
G03X281556Y429694I-12847J10203D01*
G01X296300D01*
G03X306833Y433522I0J16405D01*
G01X430497D01*
X432516Y431503D01*
Y427715D01*
X428246Y423445D01*
G03X422610Y419065I6943J-14751D01*
G01X414219D01*
Y415740D01*
G03X410528Y414038I4844J-15357D01*
G01X401786D01*
Y407051D01*
G03X394289Y393607I8306J-13444D01*
G01Y392207D01*
G03X396040Y384978I15803J1D01*
G01Y372957D01*
G03X400580Y361996I15502J0D01*
G01X403970Y358606D01*
X403984Y358578D01*
G03X410638Y351718I14515J7422D01*
G01Y326568D01*
X399981Y315911D01*
X390339D01*
X390313Y315918D01*
G03X362996Y314169I-11081J-41137D01*
G01X362959Y314154D01*
X356451D01*
X354640Y315965D01*
Y400083D01*
X336124Y418599D01*
X325331D01*
Y419365D01*
X285131D01*
X282116Y422380D01*
G03X280585Y425778I-15352J-4873D01*
G01X280557Y425825D01*
Y428304D01*
G37*
G36*
G01X275201Y518025D02*
G03X268292Y531195I-16007J0D01*
G01X268206Y531254D01*
Y533075D01*
G03X262077Y545670I-16006J0D01*
G01Y559793D01*
X265078Y562794D01*
X277796D01*
X281244Y559346D01*
Y545744D01*
X286541D01*
X288994Y543291D01*
Y527833D01*
G03X297994Y502338I12756J-9833D01*
G01Y500494D01*
X304894D01*
Y500194D01*
X318353D01*
G03X332893Y500017I7448J14506D01*
G03X333408Y500183I-4448J14681D01*
G01X333439Y500194D01*
X337811D01*
X339346Y498659D01*
Y466778D01*
X337096Y464528D01*
X327662D01*
X304238Y487952D01*
X282044D01*
G03X275201Y496762I-15354J-4863D01*
G01Y518025D01*
G37*
G36*
G01X214000Y561500D02*
X201500D01*
X200500Y562500D01*
Y571500D01*
X201500Y572500D01*
Y580500D01*
X204500Y583500D01*
Y586500D01*
X206000Y588000D01*
X207500D01*
X220000Y600500D01*
X247000D01*
X247500Y600000D01*
Y593000D01*
X247000Y592500D01*
X227000D01*
X219500Y585000D01*
X216000D01*
X212500Y581500D01*
Y571500D01*
X215000Y569000D01*
Y562500D01*
X214000Y561500D01*
G37*
G36*
G01X215000Y538500D02*
X196500D01*
X195500Y539500D01*
Y548500D01*
X196500Y549500D01*
X215000D01*
X216000Y548500D01*
Y539500D01*
X215000Y538500D01*
G37*
G36*
G01X201500Y589500D02*
X201000Y590000D01*
Y596000D01*
X206500Y601500D01*
X212000D01*
X222248Y611748D01*
X222452D01*
Y611952D01*
X231500Y621000D01*
X247000D01*
X247500Y620500D01*
Y617500D01*
X247000Y617000D01*
X234000D01*
X206500Y589500D01*
X201500D01*
G37*
G36*
G01X222500Y574656D02*
X214600D01*
X214000Y575256D01*
Y580756D01*
X216300Y583056D01*
X221300D01*
X229500Y591256D01*
X247000D01*
X247500Y590756D01*
Y587756D01*
X247000Y587256D01*
X235100D01*
X222500Y574656D01*
G37*
G36*
G01X297085Y610800D02*
X285204D01*
X282840Y613164D01*
Y647575D01*
X287400Y652135D01*
X324931D01*
X327200Y649866D01*
Y640915D01*
X326841Y640556D01*
X324744D01*
Y638459D01*
X297085Y610800D01*
G37*
G36*
G01X275201Y970781D02*
G03X268292Y983951I-16007J0D01*
G01X268206Y984010D01*
Y985831D01*
G03X267802Y989403I-16006J-1D01*
G03X262077Y1005060I-15802J3097D01*
G01Y1010799D01*
X263685Y1012407D01*
X263771Y1012404D01*
G03X273968Y1015659I480J16096D01*
G01X274021Y1015700D01*
X277825D01*
X281244Y1012281D01*
Y998744D01*
X286541D01*
X288994Y996291D01*
Y987556D01*
G03X286097Y976415I13106J-9355D01*
G01X286098Y976404D01*
Y973999D01*
G03X289194Y964539I16002J0D01*
G01Y954894D01*
X290894Y953194D01*
X319721D01*
G03X331445Y953181I5879J15206D01*
G01X331479Y953194D01*
X336519D01*
X339346Y950367D01*
Y939922D01*
X336874Y937450D01*
X263575D01*
X262077Y938948D01*
Y941725D01*
X263115Y942763D01*
G03X275201Y958281I-3919J15518D01*
G01Y970781D01*
G37*
G36*
G01X207000Y1042500D02*
X202000D01*
X201500Y1043000D01*
Y1049000D01*
X207000Y1054500D01*
X212500D01*
X232000Y1074000D01*
X247500D01*
X248000Y1073500D01*
Y1070500D01*
X247500Y1070000D01*
X234500D01*
X207000Y1042500D01*
G37*
G36*
G01X222500Y1027412D02*
X214600D01*
X214000Y1028012D01*
Y1033512D01*
X216300Y1035812D01*
X221300D01*
X229500Y1044012D01*
X247000D01*
X247500Y1043512D01*
Y1040512D01*
X247000Y1040012D01*
X235100D01*
X222500Y1027412D01*
G37*
G36*
G01X202000Y1014500D02*
X201000Y1015500D01*
Y1024500D01*
X202000Y1025500D01*
Y1033500D01*
X205000Y1036500D01*
Y1039500D01*
X206500Y1041000D01*
X208000D01*
X220500Y1053500D01*
X247500D01*
X248000Y1053000D01*
Y1046000D01*
X247500Y1045500D01*
X227500D01*
X220000Y1038000D01*
X216500D01*
X213000Y1034500D01*
Y1034211D01*
X212798Y1034010D01*
Y1027514D01*
X213000Y1027313D01*
Y1024500D01*
X215500Y1022000D01*
Y1015500D01*
X214500Y1014500D01*
X202000D01*
G37*
G36*
G01X215500Y991500D02*
X197000D01*
X196000Y992500D01*
Y1001500D01*
X197000Y1002500D01*
X215500D01*
X216500Y1001500D01*
Y992500D01*
X215500Y991500D01*
G37*
G36*
G01X297085Y1063800D02*
X287595D01*
X284425Y1066970D01*
Y1106268D01*
X288393Y1110236D01*
X325441D01*
X327294Y1108383D01*
Y1094009D01*
X326841Y1093556D01*
X324744D01*
Y1091459D01*
X297085Y1063800D01*
G37*
G36*
G01X252999Y1460950D02*
X253008Y1460979D01*
G03X253890Y1466001I-19150J5952D01*
G01X253893Y1466078D01*
X255391Y1467576D01*
X471924D01*
X484779Y1454721D01*
Y1442271D01*
X481009Y1438501D01*
X447714D01*
X436214Y1450001D01*
X407025D01*
X401674Y1455352D01*
X366048D01*
X356122Y1445426D01*
Y1401378D01*
X366019Y1391481D01*
X391307D01*
X393749Y1389039D01*
Y1383077D01*
X391673Y1381001D01*
X282286D01*
X271499Y1370214D01*
Y1344689D01*
X267783Y1340973D01*
X252326D01*
X252300Y1340980D01*
G03X233050Y1303981I-5765J-20508D01*
G01X233123Y1303921D01*
Y1302463D01*
X229674Y1299014D01*
X226388D01*
X221501Y1303901D01*
Y1385201D01*
X233524Y1397224D01*
X245105D01*
X248378Y1400497D01*
X249427D01*
Y1401546D01*
X256175Y1408294D01*
Y1440214D01*
X253738Y1442650D01*
X253751Y1442747D01*
G03X253008Y1451224I-19893J2527D01*
G01X252999Y1451253D01*
Y1460950D01*
G37*
G36*
G01X397500Y1305000D02*
X288500D01*
X286500Y1307000D01*
Y1364000D01*
X288500Y1366000D01*
X398500D01*
X401500Y1363000D01*
Y1309000D01*
X397500Y1305000D01*
G37*
G36*
G01X238891Y1412225D02*
X229823D01*
X228476Y1413572D01*
Y1426298D01*
X225874Y1428900D01*
Y1434900D01*
X226474Y1435500D01*
X239674D01*
X241174Y1434000D01*
Y1414508D01*
X238891Y1412225D01*
G37*
G36*
G01X339500Y86000D02*
X321000D01*
X320000Y87000D01*
Y96000D01*
X321000Y97000D01*
X339500D01*
X340500Y96000D01*
Y87000D01*
X339500Y86000D01*
G37*
G36*
G01X331000Y137000D02*
X326000D01*
X325500Y137500D01*
Y143500D01*
X331000Y149000D01*
X336500D01*
X356000Y168500D01*
X371500D01*
X372000Y168000D01*
Y165000D01*
X371500Y164500D01*
X358500D01*
X331000Y137000D01*
G37*
G36*
G01X346713Y121900D02*
X338813D01*
X338213Y122500D01*
Y128000D01*
X340513Y130300D01*
X345513D01*
X353713Y138500D01*
X371213D01*
X371713Y138000D01*
Y135000D01*
X371213Y134500D01*
X359313D01*
X346713Y121900D01*
G37*
G36*
G01X297000Y127000D02*
X296000Y128000D01*
Y134500D01*
X297000Y135500D01*
X305500D01*
X307500Y137500D01*
Y147500D01*
X338000Y178000D01*
X371500D01*
X372000Y177500D01*
Y170500D01*
X371500Y170000D01*
X348000D01*
X345500Y167500D01*
X339000D01*
X322000Y150500D01*
Y136500D01*
X320633Y135133D01*
X320597Y135118D01*
G03X319368Y133868I903J-2117D01*
G01X317500Y132000D01*
Y128000D01*
X316500Y127000D01*
X297000D01*
G37*
G36*
G01X338500Y109000D02*
X326000D01*
X325000Y110000D01*
Y119000D01*
X326000Y120000D01*
Y128000D01*
X329000Y131000D01*
Y134623D01*
X330077Y135700D01*
X332200D01*
X344500Y148000D01*
X371500D01*
X372000Y147500D01*
Y140500D01*
X371500Y140000D01*
X351500D01*
X344000Y132500D01*
X340500D01*
X337000Y129000D01*
Y119000D01*
X339500Y116500D01*
Y110000D01*
X338500Y109000D01*
G37*
G36*
G01X304500Y99000D02*
X300500Y103000D01*
X293358D01*
X292351Y104007D01*
Y113421D01*
X294430Y115500D01*
X310500D01*
X311500Y114500D01*
Y106683D01*
X307817Y103000D01*
X307500D01*
X307170Y102670D01*
X307150Y102658D01*
G03X306642Y102150I850J-1358D01*
G01X306630Y102130D01*
X306405Y101905D01*
Y101444D01*
X306404Y101436D01*
G03X306398Y101300I1596J-139D01*
G01Y99700D01*
G03X306404Y99564I1602J3D01*
G01X306405Y99556D01*
Y99405D01*
X306000Y99000D01*
X304500D01*
G37*
G36*
G01X386290Y484408D02*
Y489781D01*
G03X399414Y505525I-2882J15744D01*
G01Y518025D01*
G03X392505Y531195I-16007J0D01*
G01X392419Y531254D01*
Y533075D01*
G03X386290Y545670I-16006J0D01*
G01Y556277D01*
X389410Y559397D01*
X389491Y559398D01*
G03X399089Y562752I-242J16102D01*
G01X399143Y562794D01*
X402243D01*
X405244Y559793D01*
Y545744D01*
X410541D01*
X412994Y543291D01*
Y536794D01*
X413194D01*
Y514664D01*
X413193Y514654D01*
G03Y511330I16017J-1662D01*
G01X413194Y511320D01*
Y501894D01*
X417542D01*
G03X438930Y500153I11668J11098D01*
G01X438983Y500194D01*
X443827D01*
X443840Y500192D01*
G03X443955Y500177I2042J15204D01*
G03X455653Y500181I5844J15223D01*
G01X455688Y500194D01*
X458953D01*
X463558Y495589D01*
Y468369D01*
X459717Y464528D01*
X382864D01*
X379552Y467840D01*
Y470540D01*
X379594Y470594D01*
G03X382956Y480985I-12732J9859D01*
G01X382953Y481071D01*
X386290Y484408D01*
G37*
G36*
G01X326000Y561500D02*
X325000Y562500D01*
Y571500D01*
X326000Y572500D01*
Y580500D01*
X329000Y583500D01*
Y586500D01*
X330798Y588298D01*
X331498D01*
X331499Y588300D01*
X332300D01*
X344500Y600500D01*
X371500D01*
X372000Y600000D01*
Y593000D01*
X371500Y592500D01*
X351500D01*
X344000Y585000D01*
X340500D01*
X337000Y581500D01*
Y571500D01*
X339500Y569000D01*
Y562500D01*
X338500Y561500D01*
X326000D01*
G37*
G36*
G01X304500Y551500D02*
X300500Y555500D01*
X298000D01*
X296500Y557000D01*
Y567000D01*
X297500Y568000D01*
X310500D01*
X311500Y567000D01*
Y559059D01*
X307941Y555500D01*
X307500D01*
X307169Y555169D01*
G03X306631Y554631I831J-1369D01*
G01X306500Y554500D01*
Y554362D01*
X306489Y554330D01*
G03X306398Y553800I1511J-532D01*
G01Y552200D01*
G03X306410Y552004I1602J0D01*
G01Y551910D01*
X306000Y551500D01*
X304500D01*
G37*
G36*
G01X339500Y538500D02*
X321000D01*
X320000Y539500D01*
Y548500D01*
X321000Y549500D01*
X339500D01*
X340500Y548500D01*
Y539500D01*
X339500Y538500D01*
G37*
G36*
G01X326000Y589500D02*
X325648Y589852D01*
X325636Y589911D01*
G03X325515Y590314I-2256J-458D01*
G01X325500Y590350D01*
Y596000D01*
X331000Y601500D01*
X336500D01*
X356000Y621000D01*
X371500D01*
X372000Y620500D01*
Y617500D01*
X371500Y617000D01*
X358500D01*
X331000Y589500D01*
X326000D01*
G37*
G36*
G01X346713Y574656D02*
X338813D01*
X338213Y575256D01*
Y580756D01*
X340513Y583056D01*
X345513D01*
X353713Y591256D01*
X371213D01*
X371713Y590756D01*
Y587756D01*
X371213Y587256D01*
X359313D01*
X346713Y574656D01*
G37*
G36*
G01X322000Y603000D02*
Y591294D01*
G03X321170Y588806I1380J-1843D01*
G01X321178Y588779D01*
Y588178D01*
X317500Y584500D01*
Y580500D01*
X316500Y579500D01*
X297000D01*
X296000Y580500D01*
Y587000D01*
X297000Y588000D01*
X305500D01*
X307500Y590000D01*
Y600000D01*
X338000Y630500D01*
X371500D01*
X372000Y630000D01*
Y623000D01*
X371500Y622500D01*
X348000D01*
X345500Y620000D01*
X339000D01*
X322000Y603000D01*
G37*
G36*
G01X335976Y823982D02*
G03X335977Y823994I-15448J1293D01*
G01X337206D01*
Y858180D01*
X341049Y862023D01*
X388121D01*
X393989Y856155D01*
Y844907D01*
G03X395740Y837678I15803J1D01*
G01Y822757D01*
G03X400280Y811796I15502J0D01*
G01X400470Y811606D01*
X400484Y811578D01*
G03X407606Y804470I14516J7422D01*
G01X410337Y801739D01*
Y773462D01*
X403603Y766728D01*
X395936D01*
X395899Y766744D01*
G03X344845Y752687I-16667J-39207D01*
G01X344785Y752605D01*
X338726D01*
X335976Y755355D01*
Y807623D01*
G03X335986Y817685I-15502J5046D01*
G01X335976Y817715D01*
Y823982D01*
G37*
G36*
G01X331000Y1042500D02*
X326000D01*
X325500Y1043000D01*
Y1049000D01*
X331000Y1054500D01*
X336500D01*
X356000Y1074000D01*
X371500D01*
X372000Y1073500D01*
Y1070500D01*
X371500Y1070000D01*
X358500D01*
X331000Y1042500D01*
G37*
G36*
G01X346713Y1027412D02*
X338813D01*
X338213Y1028012D01*
Y1033512D01*
X340513Y1035812D01*
X345513D01*
X353713Y1044012D01*
X371213D01*
X371713Y1043512D01*
Y1040512D01*
X371213Y1040012D01*
X359313D01*
X346713Y1027412D01*
G37*
G36*
G01X322000Y1042000D02*
X320760Y1040760D01*
X320703Y1040748D01*
G03X318952Y1038997I497J-2248D01*
G01X318940Y1038940D01*
X317500Y1037500D01*
Y1033500D01*
X316500Y1032500D01*
X297000D01*
X296000Y1033500D01*
Y1040000D01*
X297000Y1041000D01*
X305500D01*
X307500Y1043000D01*
Y1053000D01*
X338000Y1083500D01*
X371500D01*
X372000Y1083000D01*
Y1076000D01*
X371500Y1075500D01*
X348000D01*
X345500Y1073000D01*
X339000D01*
X322000Y1056000D01*
Y1042000D01*
G37*
G36*
G01X326000Y1014500D02*
X325000Y1015500D01*
Y1024500D01*
X326000Y1025500D01*
Y1033500D01*
X329000Y1036500D01*
Y1039500D01*
X330500Y1041000D01*
X332000D01*
X344500Y1053500D01*
X371500D01*
X372000Y1053000D01*
Y1046000D01*
X371500Y1045500D01*
X351500D01*
X344000Y1038000D01*
X340500D01*
X337000Y1034500D01*
Y1024500D01*
X339500Y1022000D01*
Y1015500D01*
X338500Y1014500D01*
X326000D01*
G37*
G36*
G01X304500Y1004500D02*
X300500Y1008500D01*
X298000D01*
X296500Y1010000D01*
Y1020000D01*
X297500Y1021000D01*
X310500D01*
X311500Y1020000D01*
Y1012059D01*
X307941Y1008500D01*
X307500D01*
X307169Y1008169D01*
G03X306631Y1007631I831J-1369D01*
G01X306500Y1007500D01*
Y1007362D01*
X306489Y1007330D01*
G03X306398Y1006800I1511J-532D01*
G01Y1005200D01*
G03X306410Y1005004I1602J0D01*
G01Y1004910D01*
X306000Y1004500D01*
X304500D01*
G37*
G36*
G01X339500Y991500D02*
X321000D01*
X320000Y992500D01*
Y1001500D01*
X321000Y1002500D01*
X339500D01*
X340500Y1001500D01*
Y992500D01*
X339500Y991500D01*
G37*
G36*
G01X396775Y1406482D02*
X372233D01*
X371123Y1407592D01*
Y1439212D01*
X372262Y1440351D01*
X395460D01*
X397058Y1438753D01*
Y1406765D01*
X396775Y1406482D01*
G37*
G36*
G01X442000Y75000D02*
X443000Y74000D01*
Y63800D01*
X442100Y62900D01*
X423800D01*
X422500Y64200D01*
Y74000D01*
X423087Y74587D01*
X423161Y74593D01*
G03X425931Y75000I-1508J19895D01*
G01X442000D01*
G37*
G36*
G01X435500Y39500D02*
X423500D01*
X422500Y40500D01*
Y50500D01*
X423500Y51500D01*
X436500D01*
X437500Y50500D01*
Y41500D01*
X435500Y39500D01*
G37*
G36*
G01X463900Y89600D02*
X445400D01*
X444400Y90600D01*
Y99600D01*
X445400Y100600D01*
X463900D01*
X464900Y99600D01*
Y90600D01*
X463900Y89600D01*
G37*
G36*
G01X450000Y137000D02*
X449500Y137500D01*
Y143500D01*
X455000Y149000D01*
X460500D01*
X470749Y159248D01*
X470952D01*
Y159452D01*
X480000Y168500D01*
X495500D01*
X496000Y168000D01*
Y165000D01*
X495500Y164500D01*
X482500D01*
X455000Y137000D01*
X450000D01*
G37*
G36*
G01X470925Y121900D02*
X463025D01*
X462425Y122500D01*
Y128000D01*
X464725Y130300D01*
X469725D01*
X477925Y138500D01*
X495425D01*
X495925Y138000D01*
Y135000D01*
X495425Y134500D01*
X483525D01*
X470925Y121900D01*
G37*
G36*
G01X387001Y183714D02*
X386300Y184415D01*
Y196512D01*
X388731Y198943D01*
X415707D01*
X418010Y196640D01*
Y195071D01*
X394549Y171610D01*
X391759D01*
X391722Y171626D01*
G03X387178Y172815I-6433J-15306D01*
G01X387001Y172835D01*
Y183714D01*
G37*
G36*
G01X432500Y132000D02*
X431500Y133000D01*
Y147500D01*
X462000Y178000D01*
X495500D01*
X496000Y177500D01*
Y170500D01*
X495500Y170000D01*
X472000D01*
X469500Y167500D01*
X463000D01*
X446000Y150500D01*
Y136500D01*
X444633Y135133D01*
X444597Y135118D01*
G03X443382Y133903I903J-2118D01*
G01X443367Y133867D01*
X441500Y132000D01*
X432500D01*
G37*
G36*
G01X450000Y109000D02*
X449000Y110000D01*
Y112648D01*
X449352D01*
Y119352D01*
X450000Y120000D01*
Y128000D01*
X453000Y131000D01*
Y134663D01*
X454136Y135798D01*
X455498D01*
X455599Y135900D01*
X456400D01*
X468500Y148000D01*
X495500D01*
X496000Y147500D01*
Y140500D01*
X495500Y140000D01*
X475500D01*
X468000Y132500D01*
X464500D01*
X461000Y129000D01*
Y122700D01*
X461224Y122476D01*
Y122002D01*
X462527Y120698D01*
X463001D01*
X463500Y120200D01*
Y110000D01*
X462500Y109000D01*
X450000D01*
G37*
G36*
G01X462500Y561500D02*
X450000D01*
X449000Y562500D01*
Y571500D01*
X450000Y572500D01*
Y580500D01*
X453000Y583500D01*
Y586500D01*
X454500Y588000D01*
X456000D01*
X468500Y600500D01*
X495500D01*
X496000Y600000D01*
Y593000D01*
X495500Y592500D01*
X475500D01*
X468000Y585000D01*
X464500D01*
X461000Y581500D01*
Y571500D01*
X463500Y569000D01*
Y562500D01*
X462500Y561500D01*
G37*
G36*
G01X428500Y551500D02*
X424500Y555500D01*
X422000D01*
X420500Y557000D01*
Y567000D01*
X421500Y568000D01*
X434500D01*
X435500Y567000D01*
Y559059D01*
X431941Y555500D01*
X431500D01*
X431169Y555169D01*
G03X430631Y554631I831J-1369D01*
G01X430500Y554500D01*
Y554362D01*
X430489Y554330D01*
G03X430398Y553800I1511J-532D01*
G01Y552200D01*
G03X430410Y552004I1602J0D01*
G01Y551910D01*
X430000Y551500D01*
X428500D01*
G37*
G36*
G01X463500Y538500D02*
X445000D01*
X444000Y539500D01*
Y548500D01*
X445000Y549500D01*
X463500D01*
X464500Y548500D01*
Y539500D01*
X463500Y538500D01*
G37*
G36*
G01X450000Y589500D02*
X449500Y590000D01*
Y596000D01*
X455000Y601500D01*
X460500D01*
X467527Y608527D01*
X467581Y608540D01*
G03X469264Y610223I-552J2235D01*
G01X469277Y610277D01*
X470748Y611748D01*
X470952D01*
Y611952D01*
X480000Y621000D01*
X495500D01*
X496000Y620500D01*
Y617500D01*
X495500Y617000D01*
X482500D01*
X455000Y589500D01*
X450000D01*
G37*
G36*
G01X470925Y574656D02*
X463025D01*
X462425Y575256D01*
Y580756D01*
X464725Y583056D01*
X469725D01*
X477925Y591256D01*
X495425D01*
X495925Y590756D01*
Y587756D01*
X495425Y587256D01*
X483525D01*
X470925Y574656D01*
G37*
G36*
G01X410799Y611300D02*
X407340Y614759D01*
Y671923D01*
G03X417827Y685898I-28108J32015D01*
G01X442501D01*
G03X450487Y688113I0J15502D01*
G01X450534Y688142D01*
X455537D01*
X455595Y688043D01*
G03X456848Y685992I47652J27703D01*
G03X463500Y677557I46401J29752D01*
G01Y658482D01*
X456024Y651006D01*
X451294D01*
Y641009D01*
X450841Y640556D01*
X449244D01*
Y638959D01*
X421585Y611300D01*
X410799D01*
G37*
G36*
G01X446000Y589000D02*
X445312Y588312D01*
X445245Y588303D01*
G03X443264Y586322I301J-2282D01*
G01X443255Y586255D01*
X441500Y584500D01*
Y580500D01*
X440500Y579500D01*
X421000D01*
X420000Y580500D01*
Y587000D01*
X421000Y588000D01*
X429500D01*
X431500Y590000D01*
Y600000D01*
X462000Y630500D01*
X495500D01*
X496000Y630000D01*
Y623000D01*
X495500Y622500D01*
X472000D01*
X469500Y620000D01*
X463000D01*
X446000Y603000D01*
Y589000D01*
G37*
G36*
G01X503248Y770868D02*
X503247D01*
G03X468348Y758412I1J-55121D01*
G01X468293Y758367D01*
X462599D01*
X460190Y760776D01*
Y802616D01*
G03X460200Y812678I-15503J5046D01*
G01X460190Y812708D01*
Y823994D01*
X461706D01*
Y855673D01*
X466031Y859998D01*
X541810D01*
X547294Y854514D01*
Y823994D01*
X548991D01*
G03X549456Y822508I15009J3881D01*
G01Y796801D01*
G03Y786709I15503J-5046D01*
G01Y764222D01*
X545098Y759864D01*
X536293D01*
X536239Y759904D01*
G03X503248Y770868I-32992J-44156D01*
G37*
G36*
G01X399414Y970781D02*
G03X392505Y983951I-16007J0D01*
G01X392419Y984010D01*
Y985835D01*
G03X391840Y990099I-16006J-2D01*
G03X386290Y1005386I-15840J2900D01*
G01Y1010610D01*
X388117Y1012437D01*
X388207Y1012431D01*
G03X399089Y1015752I1044J16069D01*
G01X399143Y1015794D01*
X403701D01*
X405244Y1014251D01*
Y998744D01*
X410541D01*
X412994Y996291D01*
Y985869D01*
G03X410297Y975015I13306J-9068D01*
G01X410298Y975004D01*
Y973199D01*
G03X413194Y964018I16002J0D01*
G01Y954894D01*
X414894Y953194D01*
X443094D01*
Y953094D01*
X444367D01*
X444399Y953083D01*
G03X455001I5301J15417D01*
G01X455033Y953094D01*
X460914D01*
X463558Y950450D01*
Y940346D01*
X460662Y937450D01*
X387341D01*
X386290Y938501D01*
Y941654D01*
X387423Y942787D01*
G03X399414Y958281I-4015J15494D01*
G01Y970781D01*
G37*
G36*
G01X450000Y1042500D02*
X449500Y1043000D01*
Y1049000D01*
X455000Y1054500D01*
X460500D01*
X470748Y1064748D01*
X470952D01*
Y1064952D01*
X480000Y1074000D01*
X495500D01*
X496000Y1073500D01*
Y1070500D01*
X495500Y1070000D01*
X482500D01*
X455000Y1042500D01*
X450000D01*
G37*
G36*
G01X470925Y1027412D02*
X463025D01*
X462425Y1028012D01*
Y1033512D01*
X464725Y1035812D01*
X469725D01*
X477925Y1044012D01*
X495425D01*
X495925Y1043512D01*
Y1040512D01*
X495425Y1040012D01*
X483525D01*
X470925Y1027412D01*
G37*
G36*
G01X440500Y1032500D02*
X421000D01*
X420000Y1033500D01*
Y1040000D01*
X421000Y1041000D01*
X429500D01*
X431500Y1043000D01*
Y1053000D01*
X462000Y1083500D01*
X495500D01*
X496000Y1083000D01*
Y1076000D01*
X495500Y1075500D01*
X472000D01*
X469500Y1073000D01*
X463000D01*
X446000Y1056000D01*
Y1042700D01*
X441500Y1038200D01*
Y1033500D01*
X440500Y1032500D01*
G37*
G36*
G01X450000Y1014500D02*
X449000Y1015500D01*
Y1024500D01*
X450000Y1025500D01*
Y1033500D01*
X453000Y1036500D01*
Y1039500D01*
X454500Y1041000D01*
X456000D01*
X468500Y1053500D01*
X495500D01*
X496000Y1053000D01*
Y1046000D01*
X495500Y1045500D01*
X475500D01*
X468000Y1038000D01*
X464500D01*
X461000Y1034500D01*
Y1024500D01*
X463500Y1022000D01*
Y1015500D01*
X462500Y1014500D01*
X450000D01*
G37*
G36*
G01X428500Y1004500D02*
X424500Y1008500D01*
X422000D01*
X420500Y1010000D01*
Y1020000D01*
X421500Y1021000D01*
X434500D01*
X435500Y1020000D01*
Y1012059D01*
X431941Y1008500D01*
X431500D01*
X431169Y1008169D01*
G03X430631Y1007631I831J-1369D01*
G01X430500Y1007500D01*
Y1007362D01*
X430489Y1007330D01*
G03X430398Y1006800I1511J-532D01*
G01Y1005200D01*
G03X430410Y1005004I1602J0D01*
G01Y1004910D01*
X430000Y1004500D01*
X428500D01*
G37*
G36*
G01X463500Y991500D02*
X445000D01*
X444000Y992500D01*
Y1001500D01*
X445000Y1002500D01*
X463500D01*
X464500Y1001500D01*
Y992500D01*
X463500Y991500D01*
G37*
G36*
G01X421585Y1064300D02*
X409824D01*
X407340Y1066784D01*
Y1106031D01*
X409519Y1108210D01*
X448861D01*
X451200Y1105871D01*
Y1093915D01*
X450841Y1093556D01*
X449244D01*
Y1091959D01*
X421585Y1064300D01*
G37*
G36*
G01X576185Y1143080D02*
X426871D01*
X421835Y1148116D01*
Y1200212D01*
X435622Y1213999D01*
X580205D01*
X584660Y1209544D01*
Y1151555D01*
X576185Y1143080D01*
G37*
G36*
G01X599811Y1288250D02*
X597750Y1290311D01*
Y1302811D01*
X595837Y1304724D01*
X536520D01*
G02X536396Y1305504I0J400D01*
G03X531496Y1336222I-4899J14968D01*
G01X511496D01*
G03X506596Y1305504I0J-15750D01*
G02X506472Y1304724I-124J-380D01*
G01X410337D01*
X405502Y1309559D01*
Y1362941D01*
X408750Y1366189D01*
Y1433798D01*
X409952Y1435000D01*
X430000D01*
X441500Y1423500D01*
X484200D01*
X497450Y1410250D01*
X622698D01*
Y1409894D01*
X632250D01*
Y1295806D01*
X622698D01*
Y1295750D01*
X621689D01*
X619750Y1293811D01*
Y1288811D01*
X619189Y1288250D01*
X599811D01*
G37*
G36*
G01X588000Y86000D02*
X569500D01*
X568500Y87000D01*
Y96000D01*
X569500Y97000D01*
X588000D01*
X589000Y96000D01*
Y87000D01*
X588000Y86000D01*
G37*
G36*
G01X579500Y137000D02*
X574500D01*
X574000Y137500D01*
Y143500D01*
X579500Y149000D01*
X585000D01*
X604500Y168500D01*
X620000D01*
X620500Y168000D01*
Y165000D01*
X620000Y164500D01*
X607000D01*
X579500Y137000D01*
G37*
G36*
G01X545585Y158300D02*
X538113D01*
X532813Y163600D01*
Y223429D01*
X533380Y223996D01*
X534648D01*
X559301Y199343D01*
X572809D01*
X575700Y196452D01*
Y188415D01*
X575341Y188056D01*
X573244D01*
Y185959D01*
X545585Y158300D01*
G37*
G36*
G01X570500Y136500D02*
X569190Y135190D01*
X569147Y135175D01*
G03X567725Y133753I753J-2175D01*
G01X567710Y133710D01*
X566000Y132000D01*
Y128000D01*
X565000Y127000D01*
X545500D01*
X544500Y128000D01*
Y134500D01*
X545500Y135500D01*
X554000D01*
X556000Y137500D01*
Y147500D01*
X586500Y178000D01*
X620000D01*
X620500Y177500D01*
Y170500D01*
X620000Y170000D01*
X596500D01*
X594000Y167500D01*
X587500D01*
X570500Y150500D01*
Y136500D01*
G37*
G36*
G01X574500Y109000D02*
X573500Y110000D01*
Y119000D01*
X574500Y120000D01*
Y128000D01*
X577500Y131000D01*
Y134000D01*
X579200Y135700D01*
X580700D01*
X593000Y148000D01*
X620000D01*
X620500Y147500D01*
Y140500D01*
X620000Y140000D01*
X600000D01*
X592500Y132500D01*
X589000D01*
X585500Y129000D01*
Y128561D01*
X585436Y128498D01*
Y122002D01*
X585500Y121939D01*
Y119000D01*
X588000Y116500D01*
Y110000D01*
X587000Y109000D01*
X574500D01*
G37*
G36*
G01X547838Y99000D02*
X545000Y101838D01*
Y114500D01*
X546000Y115500D01*
X559000D01*
X560000Y114500D01*
Y106559D01*
X556441Y103000D01*
X556000D01*
X555670Y102670D01*
X555650Y102658D01*
G03X555142Y102150I850J-1358D01*
G01X555130Y102130D01*
X555000Y102000D01*
Y101862D01*
X554989Y101830D01*
G03X554898Y101300I1511J-532D01*
G01Y99700D01*
G03X554910Y99504I1602J0D01*
G01Y99410D01*
X554500Y99000D01*
X547838D01*
G37*
G36*
G01X523626Y518025D02*
G03X516717Y531195I-16007J0D01*
G01X516631Y531254D01*
Y533075D01*
G03X510502Y545670I-16006J0D01*
G01Y555705D01*
X512949Y558152D01*
X513033Y558151D01*
G03X523915Y562186I219J16102D01*
G01X523971Y562236D01*
X527836D01*
X529744Y560328D01*
Y545744D01*
X532382D01*
X537494Y540632D01*
Y527833D01*
G03X546494Y502338I12756J-9833D01*
G01Y500494D01*
X553394D01*
Y500194D01*
X568058D01*
G03X578175Y489417I15492J4406D01*
G01X578218Y489402D01*
X578800Y488820D01*
Y486532D01*
X577450Y485182D01*
X513109D01*
X511059Y487232D01*
Y488821D01*
X512529Y490291D01*
G03X523626Y505525I-4908J15234D01*
G01Y518025D01*
G37*
G36*
G01X574500Y561500D02*
X573500Y562500D01*
Y571500D01*
X574500Y572500D01*
Y580500D01*
X577500Y583500D01*
Y586900D01*
X578898Y588298D01*
X579998D01*
X579999Y588300D01*
X580800D01*
X593000Y600500D01*
X620000D01*
X620500Y600000D01*
Y593000D01*
X620000Y592500D01*
X600000D01*
X592500Y585000D01*
X589000D01*
X585500Y581500D01*
Y581317D01*
X585436Y581254D01*
Y574758D01*
X585500Y574695D01*
Y571500D01*
X588000Y569000D01*
Y562500D01*
X587000Y561500D01*
X574500D01*
G37*
G36*
G01X547841Y551500D02*
X545342Y553999D01*
Y572574D01*
X546468Y573700D01*
X558800D01*
X560000Y572500D01*
Y559059D01*
X556441Y555500D01*
X556000D01*
X555669Y555169D01*
G03X555131Y554631I831J-1369D01*
G01X555000Y554500D01*
Y554362D01*
X554989Y554330D01*
G03X554898Y553800I1511J-532D01*
G01Y552200D01*
G03X554910Y552004I1602J0D01*
G01Y551910D01*
X554500Y551500D01*
X547841D01*
G37*
G36*
G01X588000Y538500D02*
X569500D01*
X568500Y539500D01*
Y548500D01*
X569500Y549500D01*
X588000D01*
X589000Y548500D01*
Y539500D01*
X588000Y538500D01*
G37*
G36*
G01X579500Y589500D02*
X574500D01*
X574000Y590000D01*
Y596000D01*
X579500Y601500D01*
X585000D01*
X604500Y621000D01*
X620000D01*
X620500Y620500D01*
Y617500D01*
X620000Y617000D01*
X607000D01*
X579500Y589500D01*
G37*
G36*
G01X510022Y653065D02*
X507649Y655438D01*
Y658869D01*
X509797Y661017D01*
G03X550801Y687874I-6550J54730D01*
G01X550859Y687973D01*
X555616D01*
X560818Y682772D01*
X590290D01*
G03X594070Y677231I36974J21163D01*
G01X594114Y677176D01*
Y674967D01*
X591947Y672800D01*
X587771D01*
Y657610D01*
X581167Y651006D01*
X575794D01*
Y641009D01*
X575341Y640556D01*
X573244D01*
Y638459D01*
X548587Y613802D01*
G03X542358Y611333I2689J-15877D01*
G01X542308Y611300D01*
X536068D01*
X531340Y616028D01*
Y632515D01*
G03X512240Y653071I-15340J4898D01*
G01X512217Y653065D01*
X510022D01*
G37*
G36*
G01X587500Y620000D02*
X585746Y618246D01*
X585682Y618235D01*
G03X583770Y616323I361J-2273D01*
G01X583759Y616259D01*
X570500Y603000D01*
Y589000D01*
X569190Y587690D01*
X569147Y587675D01*
G03X567725Y586253I753J-2175D01*
G01X567710Y586210D01*
X566000Y584500D01*
Y581235D01*
G02X565553Y580838I-400J0D01*
G03X563181Y579500I-274J-2286D01*
G01X545500D01*
X544500Y580500D01*
Y587000D01*
X545500Y588000D01*
X554000D01*
X556000Y590000D01*
Y600000D01*
X586500Y630500D01*
X620000D01*
X620500Y630000D01*
Y623000D01*
X620000Y622500D01*
X596500D01*
X594000Y620000D01*
X587500D01*
G37*
G36*
G01X523626Y970781D02*
G03X516717Y983951I-16007J0D01*
G01X516631Y984010D01*
Y985831D01*
G03X516008Y990253I-16005J0D01*
G03X510502Y1004207I-16008J1747D01*
G01Y1010801D01*
X512136Y1012435D01*
X512226Y1012429D01*
G03X523089Y1015752I1024J16071D01*
G01X523143Y1015794D01*
X526875D01*
X529744Y1012925D01*
Y998744D01*
X535041D01*
X537494Y996291D01*
Y988715D01*
G03X534697Y977715I13206J-9214D01*
G01X534698Y977704D01*
Y975499D01*
G03X537694Y966177I16002J0D01*
G01Y954894D01*
X539394Y953194D01*
X567781D01*
G03X568262Y953117I2665J15107D01*
G03X580296Y953179I5939J15183D01*
G01X580332Y953194D01*
X584391D01*
X586243Y951342D01*
G03X587746Y947640I15556J4160D01*
G01X587771Y947595D01*
Y941068D01*
X584153Y937450D01*
X511648D01*
X510502Y938596D01*
Y941599D01*
X511710Y942807D01*
X511762Y942821D01*
G03X523626Y958281I-4141J15460D01*
G01Y970781D01*
G37*
G36*
G01X579500Y1042500D02*
X574500D01*
X574000Y1043000D01*
Y1049000D01*
X579500Y1054500D01*
X585000D01*
X604500Y1074000D01*
X620000D01*
X620500Y1073500D01*
Y1070500D01*
X620000Y1070000D01*
X607000D01*
X579500Y1042500D01*
G37*
G36*
G01X545500Y1032500D02*
X544500Y1033500D01*
Y1040000D01*
X545500Y1041000D01*
X554000D01*
X556000Y1043000D01*
Y1053000D01*
X586500Y1083500D01*
X620000D01*
X620500Y1083000D01*
Y1076000D01*
X620000Y1075500D01*
X596500D01*
X594000Y1073000D01*
X587500D01*
X570500Y1056000D01*
Y1042000D01*
X569190Y1040690D01*
X569147Y1040675D01*
G03X567725Y1039253I753J-2175D01*
G01X567710Y1039210D01*
X566000Y1037500D01*
Y1033500D01*
X565000Y1032500D01*
X545500D01*
G37*
G36*
G01X574500Y1014500D02*
X573500Y1015500D01*
Y1024500D01*
X574500Y1025500D01*
Y1033500D01*
X577500Y1036500D01*
Y1040000D01*
X578700Y1041200D01*
X580700D01*
X593000Y1053500D01*
X620000D01*
X620500Y1053000D01*
Y1046000D01*
X620000Y1045500D01*
X600000D01*
X592500Y1038000D01*
X589000D01*
X585500Y1034500D01*
Y1034073D01*
X585436Y1034010D01*
Y1027514D01*
X585500Y1027451D01*
Y1024500D01*
X588000Y1022000D01*
Y1015500D01*
X587000Y1014500D01*
X574500D01*
G37*
G36*
G01X553000Y1004500D02*
X549000Y1008500D01*
X546500D01*
X545000Y1010000D01*
Y1020000D01*
X546000Y1021000D01*
X559000D01*
X560000Y1020000D01*
Y1012059D01*
X556441Y1008500D01*
X556000D01*
X555669Y1008169D01*
G03X555131Y1007631I831J-1369D01*
G01X555000Y1007500D01*
Y1007362D01*
X554989Y1007330D01*
G03X554898Y1006800I1511J-532D01*
G01Y1005200D01*
G03X554910Y1005004I1602J0D01*
G01Y1004910D01*
X554500Y1004500D01*
X553000D01*
G37*
G36*
G01X588000Y991500D02*
X569500D01*
X568500Y992500D01*
Y1001500D01*
X569500Y1002500D01*
X588000D01*
X589000Y1001500D01*
Y992500D01*
X588000Y991500D01*
G37*
G36*
G01X546085Y1064300D02*
X534246D01*
X531340Y1067206D01*
Y1102557D01*
X534968Y1106185D01*
X571666D01*
X575700Y1102151D01*
Y1093915D01*
X575341Y1093556D01*
X573244D01*
Y1091459D01*
X546085Y1064300D01*
G37*
G36*
G01X607996Y1465969D02*
X608000Y1465938D01*
Y1446266D01*
X607996Y1446235D01*
Y1446232D01*
X607994Y1446217D01*
G03Y1444333I6179J-942D01*
G01X607996Y1444318D01*
Y1444315D01*
X608000Y1444284D01*
Y1416871D01*
X603594Y1412465D01*
X500754D01*
X498971Y1414248D01*
Y1424122D01*
X505174Y1430325D01*
X525697D01*
X526392Y1429630D01*
X530193D01*
X532582Y1427241D01*
X544746D01*
X555705Y1438200D01*
X586200D01*
X588000Y1440000D01*
Y1474000D01*
X591500Y1477500D01*
X605000D01*
X608000Y1474500D01*
Y1467920D01*
X607996Y1467889D01*
Y1467886D01*
X607994Y1467871D01*
G03Y1465987I6179J-942D01*
G01X607996Y1465972D01*
Y1465969D01*
G37*
G36*
G01X526421Y1431379D02*
X526267Y1431533D01*
X525095D01*
G03X525011Y1431536I-99J-1598D01*
G01X523411D01*
G03X523327Y1431533I15J-1601D01*
G01X522807D01*
X522570Y1431769D01*
Y1439645D01*
X524963Y1442038D01*
X541962D01*
X545207Y1438793D01*
Y1433667D01*
X542919Y1431379D01*
X526421D01*
G37*
G36*
G01X506735Y1434531D02*
X505735Y1435531D01*
Y1448235D01*
X506850Y1449350D01*
X520200D01*
X521300Y1448250D01*
Y1445203D01*
X519321Y1443224D01*
Y1442055D01*
X518568Y1441302D01*
Y1434531D01*
X506735D01*
G37*
G36*
G01X634715Y104861D02*
G03X637448Y106456I-6712J14641D01*
G01X637500Y106494D01*
X640206D01*
Y108992D01*
X640254Y109048D01*
G03X640853Y109794I-12254J10452D01*
G01X647952D01*
X652244Y105502D01*
Y83775D01*
G03X646838Y79596I17834J-28657D01*
G01X646780Y79541D01*
X642833D01*
X641943Y80431D01*
X641900D01*
X640798Y81533D01*
X640792Y81606D01*
G03X634715Y92914I-15954J-1287D01*
G01Y104861D01*
G37*
G36*
G01X680500Y78000D02*
X668500D01*
X667500Y79000D01*
Y89000D01*
X668500Y90000D01*
X681500D01*
X682500Y89000D01*
Y80000D01*
X680500Y78000D01*
G37*
G36*
G01X595138Y121900D02*
X587238D01*
X586638Y122500D01*
Y128000D01*
X588938Y130300D01*
X593938D01*
X602138Y138500D01*
X619638D01*
X620138Y138000D01*
Y135000D01*
X619638Y134500D01*
X607738D01*
X595138Y121900D01*
G37*
G36*
G01X699794Y198506D02*
Y188509D01*
X699341Y188056D01*
X697544D01*
Y186259D01*
X669541Y158256D01*
X655497D01*
X652640Y161113D01*
Y204565D01*
X654735Y206660D01*
X709995D01*
X711984Y204671D01*
Y202580D01*
X710241Y200837D01*
G03X706356Y198506I6260J-14836D01*
G01X699794D01*
G37*
G36*
G01X692300Y134300D02*
X688000Y130000D01*
Y103500D01*
X687000Y102500D01*
X668500D01*
X667500Y103500D01*
Y109500D01*
X677000Y119000D01*
Y133000D01*
X680000Y136000D01*
Y147500D01*
X710500Y178000D01*
X744000D01*
X744500Y177500D01*
Y170500D01*
X744000Y170000D01*
X720500D01*
X718000Y167500D01*
X711500D01*
X694500Y150500D01*
Y136500D01*
X692900Y134900D01*
X692885Y134889D01*
G03X692311Y134315I1315J-1889D01*
G01X692300Y134300D01*
G37*
G36*
G01X584402Y371400D02*
X585800D01*
Y407428D01*
X593932Y415560D01*
X633101D01*
X636900Y411761D01*
Y406997D01*
G03X629489Y393607I8391J-13390D01*
G01Y392207D01*
G03X631240Y384978I15803J1D01*
G01Y372957D01*
G03X635780Y361996I15502J0D01*
G01X639170Y358606D01*
X639184Y358578D01*
G03X645838Y351718I14515J7422D01*
G01Y316947D01*
X644569Y315678D01*
X639200D01*
X639173Y315686D01*
G03X587842Y290937I-11910J-40905D01*
G01X587827Y290900D01*
X587016Y290089D01*
X585705D01*
X584402Y291392D01*
Y350706D01*
G03X584412Y360768I-15503J5046D01*
G01X584402Y360798D01*
Y371400D01*
G37*
G36*
G01X647839Y518025D02*
G03X640930Y531195I-16007J0D01*
G01X640844Y531254D01*
Y533075D01*
G03X634715Y545670I-16006J0D01*
G01Y555940D01*
X638178Y559403D01*
X638257Y559405D01*
G03X647589Y562752I-506J16095D01*
G01X647643Y562794D01*
X652146D01*
X653744Y561196D01*
Y545744D01*
X653999D01*
Y544068D01*
X661694Y536373D01*
Y530172D01*
X659911Y528389D01*
G03X674740Y500450I4739J-15389D01*
G01X674795Y500494D01*
X677394D01*
Y500194D01*
X686752D01*
G03X689417Y497872I11847J10907D01*
G01Y494841D01*
X679759Y485182D01*
X636388D01*
X634715Y486855D01*
Y489781D01*
G03X647839Y505525I-2882J15744D01*
G01Y518025D01*
G37*
G36*
G01X669877Y549405D02*
X669000Y550282D01*
Y567000D01*
X670000Y568000D01*
X683000D01*
X684000Y567000D01*
Y559059D01*
X680441Y555500D01*
X680000D01*
X679669Y555169D01*
G03X679131Y554631I831J-1369D01*
G01X679000Y554500D01*
Y554362D01*
X678989Y554330D01*
G03X678898Y553800I1511J-532D01*
G01Y552200D01*
G03X678910Y552004I1602J0D01*
G01Y551910D01*
X678500Y551500D01*
X675796D01*
X673701Y549405D01*
X669877D01*
G37*
G36*
G01X595138Y574656D02*
X587238D01*
X586638Y575256D01*
Y580756D01*
X588938Y583056D01*
X593938D01*
X602138Y591256D01*
X619638D01*
X620138Y590756D01*
Y587756D01*
X619638Y587256D01*
X607738D01*
X595138Y574656D01*
G37*
G36*
G01X665871Y649330D02*
X665960Y649325D01*
G03X671553Y680817I941J16076D01*
G01X670265Y682105D01*
Y684861D01*
X672952Y687548D01*
X691785D01*
X693783Y685550D01*
X693787Y685473D01*
G03X708810Y670178I16084J773D01*
G01X708885Y670173D01*
X711984Y667074D01*
Y656680D01*
X706310Y651006D01*
X699794D01*
Y647604D01*
X699725Y647545D01*
G03X694197Y635494I10575J-12144D01*
G01Y635412D01*
X669541Y610756D01*
X664510D01*
X662020Y613246D01*
Y641618D01*
G03X662964Y646350I-15340J5520D01*
G01X662968Y646427D01*
X665871Y649330D01*
G37*
G36*
G01X669500Y579500D02*
X668500Y580500D01*
Y587000D01*
X669500Y588000D01*
X678000D01*
X680000Y590000D01*
Y600000D01*
X710500Y630500D01*
X744000D01*
X744500Y630000D01*
Y623000D01*
X744000Y622500D01*
X720500D01*
X718000Y620000D01*
X711500D01*
X694500Y603000D01*
Y589000D01*
X692899Y587399D01*
G03X692301Y586801I1301J-1899D01*
G01X690000Y584500D01*
Y580500D01*
X689000Y579500D01*
X669500D01*
G37*
G36*
G01X653798Y793279D02*
Y768924D01*
X651178Y766304D01*
X644932D01*
X644893Y766322D01*
G03X604392Y763481I-17630J-38785D01*
G01X604343Y763450D01*
X597824D01*
X594976Y766298D01*
Y790352D01*
X609182Y804558D01*
Y822354D01*
G03X609573Y831032I-15502J5046D01*
G01X611535Y832994D01*
X614811D01*
Y847793D01*
X617054Y850036D01*
X631670D01*
X634897Y846809D01*
X634895Y846723D01*
G03X634889Y846309I15797J-436D01*
G01Y844907D01*
G03X636640Y837678I15803J1D01*
G01Y827462D01*
X636630Y827432D01*
G03Y817400I15512J-5016D01*
G01X636640Y817370D01*
Y816857D01*
G03X641180Y805896I15502J0D01*
G01X653798Y793279D01*
G37*
G36*
G01X647839Y970781D02*
G03X640930Y983951I-16007J0D01*
G01X640844Y984010D01*
Y985833D01*
G03X640825Y986602I-16006J-11D01*
G01X640821Y986690D01*
X652875Y998744D01*
X654724D01*
X661494Y991974D01*
Y988620D01*
X661467Y988574D01*
G03X659397Y978715I13933J-8072D01*
G01X659398Y978704D01*
Y972398D01*
G03X661694Y964140I16002J1D01*
G01Y954894D01*
X663394Y953194D01*
X691781D01*
G03X691933Y953168I2662J15107D01*
G03X704096Y953179I6068J15132D01*
G01X704132Y953194D01*
X709607D01*
X711984Y950817D01*
Y940010D01*
X709424Y937450D01*
X635635D01*
X634715Y938370D01*
Y941835D01*
X635607Y942727D01*
G03X647839Y958281I-3773J15554D01*
G01Y970781D01*
G37*
G36*
G01X595138Y1027412D02*
X587238D01*
X586638Y1028012D01*
Y1033512D01*
X588938Y1035812D01*
X593938D01*
X602138Y1044012D01*
X619638D01*
X620138Y1043512D01*
Y1040512D01*
X619638Y1040012D01*
X607738D01*
X595138Y1027412D01*
G37*
G36*
G01X669500Y1032500D02*
X668500Y1033500D01*
Y1040000D01*
X669500Y1041000D01*
X678000D01*
X680000Y1043000D01*
Y1053000D01*
X710500Y1083500D01*
X744000D01*
X744500Y1083000D01*
Y1076000D01*
X744000Y1075500D01*
X720500D01*
X718000Y1073000D01*
X711500D01*
X694500Y1056000D01*
Y1042000D01*
X693132Y1040632D01*
G03X691868Y1039368I868J-2132D01*
G01X690000Y1037500D01*
Y1033500D01*
X689000Y1032500D01*
X669500D01*
G37*
G36*
G01X670183Y1004500D02*
X669000Y1005683D01*
Y1020000D01*
X670000Y1021000D01*
X683000D01*
X684000Y1020000D01*
Y1012059D01*
X680441Y1008500D01*
X680000D01*
X679669Y1008169D01*
G03X679131Y1007631I831J-1369D01*
G01X679000Y1007500D01*
Y1007362D01*
X678989Y1007330D01*
G03X678898Y1006800I1511J-532D01*
G01Y1005200D01*
G03X678910Y1005004I1602J0D01*
G01Y1004910D01*
X678500Y1004500D01*
X670183D01*
G37*
G36*
G01X670085Y1064300D02*
X657462D01*
X655840Y1065922D01*
Y1103146D01*
X656854Y1104160D01*
X697903D01*
X699700Y1102363D01*
Y1093915D01*
X699341Y1093556D01*
X697544D01*
Y1091759D01*
X670085Y1064300D01*
G37*
G36*
G01X770750Y1196119D02*
Y1185877D01*
X768166Y1183293D01*
X768148Y1183281D01*
G03X760697Y1169783I8652J-13581D01*
G03X753775Y1154920I9103J-13283D01*
G01X753785Y1154826D01*
X751292Y1152333D01*
G03X744233Y1143080I8408J-13733D01*
G01X672879D01*
X669866Y1146093D01*
Y1192988D01*
X668293Y1194561D01*
Y1208160D01*
X680632Y1220499D01*
X750512D01*
X756495Y1214516D01*
Y1214434D01*
G03X768752Y1198872I16105J77D01*
G03X770750Y1196119I13961J8031D01*
G37*
G36*
G01X664702Y1295750D02*
Y1295806D01*
X655100D01*
Y1409894D01*
X664702D01*
Y1410250D01*
X803589D01*
X804900Y1408939D01*
Y1296911D01*
X803739Y1295750D01*
X664702D01*
G37*
G36*
G01X645683Y1428517D02*
X645000Y1429200D01*
Y1436900D01*
X645920Y1437820D01*
X655011D01*
G03X655095Y1437818I80J1599D01*
G01X656495D01*
G03X656579Y1437820I4J1601D01*
G01X656894D01*
X658372Y1436342D01*
Y1430096D01*
X656793Y1428517D01*
X656595D01*
G03X656495Y1428520I-98J-1598D01*
G01X655095D01*
G03X654995Y1428517I-2J-1601D01*
G01X645683D01*
G37*
G36*
G01X693500Y86000D02*
X692840Y86660D01*
Y96340D01*
X693500Y97000D01*
X712000D01*
X713000Y96000D01*
Y87000D01*
X712000Y86000D01*
X693500D01*
G37*
G36*
G01X698500Y137000D02*
X698000Y137500D01*
Y150600D01*
X706100Y158700D01*
X718700D01*
X719248Y159248D01*
X719252D01*
Y159252D01*
X728500Y168500D01*
X744000D01*
X744500Y168000D01*
Y165000D01*
X744000Y164500D01*
X731000D01*
X721050Y154550D01*
X708850D01*
X705400Y151100D01*
Y149002D01*
G03Y148798I2800J-102D01*
G01Y138900D01*
X703500Y137000D01*
X698500D01*
G37*
G36*
G01X719351Y121900D02*
X711451D01*
X710851Y122500D01*
Y128000D01*
X713151Y130300D01*
X718151D01*
X726351Y138500D01*
X743851D01*
X744351Y138000D01*
Y135000D01*
X743851Y134500D01*
X731951D01*
X719351Y121900D01*
G37*
G36*
G01X711000Y109000D02*
X698500D01*
X697500Y110000D01*
Y119000D01*
X698500Y120000D01*
Y128000D01*
X701500Y131000D01*
Y134644D01*
X702356Y135500D01*
X704500D01*
X717000Y148000D01*
X744000D01*
X744500Y147500D01*
Y140500D01*
X744000Y140000D01*
X724000D01*
X716500Y132500D01*
X713000D01*
X709500Y129000D01*
Y119000D01*
X712000Y116500D01*
Y110000D01*
X711000Y109000D01*
G37*
G36*
G01X766345Y434236D02*
X775706Y443597D01*
X780231D01*
X780276Y443573D01*
G03X784928Y441905I7697J14145D01*
G01X785842Y440991D01*
Y423297D01*
X782930Y420385D01*
X780437D01*
X780377Y420459D01*
G03X766455Y431704I-33133J-26781D01*
G01X766345Y431759D01*
Y434236D01*
G37*
G36*
G01X711000Y561500D02*
X698500D01*
X697500Y562500D01*
Y571500D01*
X698500Y572500D01*
Y580500D01*
X701500Y583500D01*
Y586500D01*
X703000Y588000D01*
X704500D01*
X717000Y600500D01*
X744000D01*
X744500Y600000D01*
Y593000D01*
X744000Y592500D01*
X724000D01*
X716500Y585000D01*
X713000D01*
X709500Y581500D01*
Y571500D01*
X712000Y569000D01*
Y562500D01*
X711000Y561500D01*
G37*
G36*
G01X693500Y538500D02*
X692500Y539500D01*
Y547941D01*
X694059Y549500D01*
X712000D01*
X713000Y548500D01*
Y539500D01*
X712000Y538500D01*
X693500D01*
G37*
G36*
G01X698500Y589500D02*
X698000Y590000D01*
Y596000D01*
X703500Y601500D01*
X709000D01*
X719248Y611748D01*
X719252D01*
Y611752D01*
X728500Y621000D01*
X744000D01*
X744500Y620500D01*
Y617500D01*
X744000Y617000D01*
X731000D01*
X703500Y589500D01*
X698500D01*
G37*
G36*
G01X719351Y574656D02*
X711451D01*
X710851Y575256D01*
Y580756D01*
X713151Y583056D01*
X718151D01*
X726351Y591256D01*
X743851D01*
X744351Y590756D01*
Y587756D01*
X743851Y587256D01*
X731951D01*
X719351Y574656D01*
G37*
G36*
G01X709818Y704425D02*
Y721259D01*
X710956Y722397D01*
X718039D01*
G03X718161I61J16103D01*
G01X727706D01*
X733239Y716864D01*
X733240Y716783D01*
G03X734201Y711491I16301J227D01*
G01Y674787D01*
X732214Y672800D01*
X724114D01*
X722477Y674437D01*
Y676226D01*
X722520Y676280D01*
G03X712107Y702193I-12649J9966D01*
G01X712041Y702202D01*
X709818Y704425D01*
G37*
G36*
G01X698500Y1042500D02*
X698000Y1043000D01*
Y1049000D01*
X703500Y1054500D01*
X709000D01*
X719248Y1064748D01*
X719252D01*
Y1064752D01*
X728500Y1074000D01*
X744000D01*
X744500Y1073500D01*
Y1070500D01*
X744000Y1070000D01*
X731000D01*
X703500Y1042500D01*
X698500D01*
G37*
G36*
G01X719351Y1027412D02*
X711451D01*
X710851Y1028012D01*
Y1033512D01*
X713151Y1035812D01*
X718151D01*
X726351Y1044012D01*
X743851D01*
X744351Y1043512D01*
Y1040512D01*
X743851Y1040012D01*
X731951D01*
X719351Y1027412D01*
G37*
G36*
G01X711000Y1014500D02*
X698500D01*
X697500Y1015500D01*
Y1024500D01*
X698500Y1025500D01*
Y1033500D01*
X701500Y1036500D01*
Y1039500D01*
X703000Y1041000D01*
X704500D01*
X717000Y1053500D01*
X744000D01*
X744500Y1053000D01*
Y1046000D01*
X744000Y1045500D01*
X724000D01*
X716500Y1038000D01*
X713000D01*
X709500Y1034500D01*
Y1024500D01*
X712000Y1022000D01*
Y1015500D01*
X711000Y1014500D01*
G37*
G36*
G01X712000Y991500D02*
X693500D01*
X692500Y992500D01*
Y1001500D01*
X693500Y1002500D01*
X712000D01*
X713000Y1001500D01*
Y992500D01*
X712000Y991500D01*
G37*
G36*
G01X768513Y1436336D02*
X768621Y1436310D01*
G03X787707Y1447096I3740J15662D01*
G01X787722Y1447142D01*
X790512Y1449932D01*
X820938D01*
X834677Y1436192D01*
Y1428998D01*
X830890Y1425211D01*
X809843D01*
X809803Y1425251D01*
X765020D01*
X764098Y1426173D01*
Y1428822D01*
X764133Y1428873D01*
G03X766545Y1434326I-13266J9128D01*
G01X766558Y1434381D01*
X768513Y1436336D01*
G37*
G36*
G01X680972Y1461750D02*
G03X679950Y1462092I-1023J-1360D01*
G01X679258D01*
X678300Y1463050D01*
Y1469950D01*
X678750Y1470400D01*
X682800D01*
X683700Y1469500D01*
Y1469423D01*
G03X683688Y1467810I2150J-823D01*
G01X683700Y1467777D01*
Y1461750D01*
X680972D01*
G37*
G36*
G01X801843Y395996D02*
X800843Y396996D01*
Y410996D01*
X802024Y412177D01*
X826934D01*
X827946Y411164D01*
Y396416D01*
X827526Y395996D01*
X801843D01*
G37*
G36*
G01X806340Y474231D02*
X849038Y516929D01*
Y546920D01*
X851306Y549188D01*
X856369D01*
X867018Y538539D01*
Y524704D01*
G03X851301Y510457I282J-16103D01*
G01X851293Y510388D01*
X820115Y479210D01*
G03X812608Y471366I7199J-14404D01*
G01X807713D01*
X806890Y472189D01*
X806875Y472226D01*
G03X806361Y473355I-14904J-6104D01*
G01X806340Y473397D01*
Y474231D01*
G37*
G36*
G01X801160Y416178D02*
X800843Y416496D01*
Y430996D01*
X801843Y431996D01*
X825071D01*
X825073Y431994D01*
X826319D01*
X827144Y431169D01*
Y429923D01*
X827146Y429921D01*
Y416178D01*
X801160D01*
G37*
G36*
G01X823400Y554000D02*
X797400D01*
X796400Y555000D01*
Y569000D01*
X797900Y570500D01*
X823400D01*
X824400Y569500D01*
Y555000D01*
X823400Y554000D01*
G37*
G36*
G01X796400Y574502D02*
Y589000D01*
X797400Y590000D01*
X821566D01*
X824160Y587406D01*
Y574502D01*
X796400D01*
G37*
G36*
G01X857208Y884422D02*
X857182Y884448D01*
Y894622D01*
X857200Y894640D01*
Y895712D01*
X858501Y897013D01*
X866168D01*
X868330Y894851D01*
Y890190D01*
X868840Y889680D01*
Y889290D01*
X868803Y889238D01*
G03X868381Y886618I2447J-1738D01*
G02X867999Y886100I-382J-118D01*
G01X865400D01*
X864640Y885340D01*
X862831D01*
X862351Y884860D01*
X860600D01*
G03X859237Y884422I0J-2340D01*
G01X857208D01*
G37*
G36*
G01X837653Y997576D02*
X837597Y997625D01*
G03X833093Y1000406I-10597J-12125D01*
G01Y1004732D01*
X835799Y1007438D01*
X835889Y1007432D01*
G03X836850Y1039603I1065J16068D01*
G01X836767Y1039602D01*
X833093Y1043276D01*
Y1052520D01*
X836775Y1056202D01*
X839113D01*
X839135Y1056197D01*
G03X837137Y1087012I3565J15703D01*
G01X837104Y1087000D01*
X830520D01*
X793972Y1123548D01*
X793957Y1123579D01*
G03X786197Y1131339I-14735J-6975D01*
G01X786166Y1131354D01*
X784307Y1133213D01*
Y1134236D01*
X785790Y1135719D01*
X788483D01*
X788522Y1135702D01*
G03X797428Y1134466I6579J14698D01*
G03X811920Y1140997I1492J16034D01*
G01X818068D01*
G03X847532I14732J6503D01*
G01X901863D01*
X906567Y1136293D01*
Y1114782D01*
X861999Y1070214D01*
Y999646D01*
X856089Y993736D01*
X850408D01*
X850352Y993783D01*
G03X839970Y997576I-10382J-12312D01*
G01X837653D01*
G37*
G36*
G01X814300Y1193900D02*
X788300D01*
X787300Y1194900D01*
Y1207785D01*
X788828Y1209313D01*
X813586D01*
X815300Y1207599D01*
Y1194900D01*
X814300Y1193900D01*
G37*
G36*
G01X813342Y1214202D02*
X789187D01*
X787300Y1216089D01*
Y1228900D01*
X788300Y1229900D01*
X814300D01*
X815300Y1228900D01*
Y1216160D01*
X813342Y1214202D01*
G37*
G36*
G01X813000Y1318500D02*
X807000D01*
X806500Y1319000D01*
Y1335000D01*
X808000Y1336500D01*
X812500D01*
X813500Y1335500D01*
Y1319000D01*
X813000Y1318500D01*
G37*
G36*
G01X823000Y1329500D02*
X816000D01*
X815000Y1330500D01*
Y1335500D01*
X816000Y1336500D01*
X823000D01*
X824000Y1335500D01*
Y1330500D01*
X823000Y1329500D01*
G37*
G36*
G01X812500Y1360500D02*
X807500D01*
X807000Y1361000D01*
Y1376500D01*
X809000Y1378500D01*
X812042D01*
X813500Y1377042D01*
Y1361500D01*
X812500Y1360500D01*
G37*
G36*
G01X824786Y1398500D02*
X806990D01*
X806728Y1398762D01*
Y1409240D01*
X807698Y1410210D01*
X824670D01*
X825428Y1409452D01*
Y1399142D01*
X824786Y1398500D01*
G37*
G36*
G01X852535Y1397751D02*
X844819D01*
X844376Y1398194D01*
Y1407847D01*
X845493Y1408964D01*
X851944D01*
X853559Y1407349D01*
Y1398775D01*
X852535Y1397751D01*
G37*
G36*
G01X823000Y1368000D02*
X816000D01*
X815000Y1369000D01*
Y1374000D01*
X816000Y1375000D01*
X823000D01*
X824000Y1374000D01*
Y1369000D01*
X823000Y1368000D01*
G37*
G36*
G01X841534Y1389344D02*
X838156D01*
X827898Y1399602D01*
Y1408247D01*
X828673Y1409022D01*
X841947D01*
X842221Y1408748D01*
Y1390031D01*
X841534Y1389344D01*
G37*
G36*
G01X858114Y1389698D02*
X845049D01*
X844549Y1390198D01*
Y1395564D01*
X845060Y1396075D01*
X857958D01*
X858768Y1395265D01*
Y1390352D01*
X858114Y1389698D01*
G37*
G36*
G01X951937Y892345D02*
X947330Y887739D01*
Y887432D01*
X946968D01*
Y880084D01*
X946485Y879600D01*
X943715D01*
X942558Y880757D01*
Y884575D01*
G03X942960Y886646I-1808J1425D01*
G01X942952Y886673D01*
Y890412D01*
X942603Y890760D01*
X942601Y890840D01*
G03X942563Y891150I-1601J-39D01*
G01X942558Y891171D01*
Y896598D01*
G03X943102Y897800I-1058J1203D01*
G01Y899200D01*
G03X942558Y900402I-1602J-1D01*
G01Y903344D01*
X945215Y906001D01*
X950440D01*
X951937Y904504D01*
Y895184D01*
G03X951920Y893122I2271J-1050D01*
G01X951937Y893083D01*
Y892345D01*
G37*
G36*
G01X926826Y867500D02*
X922899Y871427D01*
G03X921927Y872399I-2187J-1215D01*
G01X917400Y876926D01*
Y880364D01*
G03X916800Y881928I-2340J-1D01*
G01Y883200D01*
X917100Y883500D01*
X921949D01*
G03X923200Y882898I1251J999D01*
G01X924800D01*
G03X925440Y883032I-1J1602D01*
G01X925478Y883048D01*
X927577D01*
X927604Y883040D01*
G03X929692Y883456I645J2210D01*
G01X929747Y883500D01*
X930344D01*
X931663Y882181D01*
G03X931398Y881300I1337J-882D01*
G01Y878700D01*
G03X931736Y877717I1602J1D01*
G01X931778Y877663D01*
Y877237D01*
X931736Y877183D01*
G03X931398Y876200I1264J-984D01*
G01Y874800D01*
G03X931778Y873765I1602J1D01*
G01Y867896D01*
X931382Y867500D01*
X926826D01*
G37*
G36*
G01X881000Y972000D02*
X877000Y976000D01*
Y1064000D01*
X921568Y1108568D01*
Y1140335D01*
X933654Y1152421D01*
X961305D01*
X978784Y1169900D01*
X997411D01*
X1011600Y1184089D01*
X1074310D01*
X1081223Y1191002D01*
X1157419D01*
X1158946Y1189475D01*
Y1178222D01*
X1158062Y1177338D01*
X1086767D01*
X1081745Y1172316D01*
X1024300D01*
X1004384Y1152400D01*
X985835D01*
X975208Y1141773D01*
Y1133066D01*
X975203Y1133044D01*
G03Y1131936I2440J-554D01*
G01X975208Y1131914D01*
Y1101708D01*
X904500Y1031000D01*
Y978172D01*
X898328Y972000D01*
X881000D01*
G37*
G36*
G01X888700Y1188600D02*
X886750Y1190550D01*
Y1194550D01*
X887199Y1194999D01*
X887283D01*
G03X887300Y1194998I102J1596D01*
G01X888700D01*
G03X888765Y1195000I-17J1601D01*
G01X890400D01*
X891048Y1195648D01*
X891050D01*
X892100Y1196698D01*
X892205D01*
X892206Y1196700D01*
X894198D01*
Y1196638D01*
X901162D01*
X901500Y1196300D01*
Y1194800D01*
X901300Y1194600D01*
X898500D01*
X897700Y1193800D01*
Y1192565D01*
G03X897698Y1192500I1599J-82D01*
G01Y1190900D01*
G03X897700Y1190835I1601J17D01*
G01Y1188800D01*
X897500Y1188600D01*
X888700D01*
G37*
G36*
G01X946543Y1389400D02*
X943719Y1392224D01*
X927876D01*
X927600Y1392500D01*
Y1400700D01*
X928200Y1401300D01*
X940256D01*
G03X942862I1303J1898D01*
G01X945800D01*
X946600Y1400500D01*
Y1398800D01*
X948500Y1396900D01*
X951500D01*
X953600Y1394800D01*
Y1390200D01*
X952800Y1389400D01*
X951252D01*
G03X951139Y1389404I-113J-1597D01*
G01X949539D01*
G03X949426Y1389400I0J-1601D01*
G01X946543D01*
G37*
G36*
G01X966086Y1417364D02*
X965140Y1416418D01*
X964003D01*
G03X963938Y1416420I-82J-1599D01*
G01X962538D01*
G03X962473Y1416418I17J-1601D01*
G01X957238D01*
X957210Y1416390D01*
X952210D01*
X951300Y1417300D01*
Y1425100D01*
X952018Y1425818D01*
X961976D01*
X962008Y1425807D01*
G03X962538Y1425716I532J1511D01*
G01X963938D01*
G03X964468Y1425807I-2J1602D01*
G01X964500Y1425818D01*
X965516D01*
X966086Y1425248D01*
Y1417364D01*
G37*
G36*
G01X1713317Y40903D02*
X1727865Y55451D01*
Y186377D01*
G03X1698168Y198556I-15340J4890D01*
G01X1694931D01*
X1694879Y198593D01*
G03X1685500Y201606I-9380J-13093D01*
G01X1683131D01*
X1679607Y205130D01*
Y207078D01*
X1680836Y208307D01*
X1680904Y208316D01*
G03X1722938Y237790I-6987J54675D01*
G01X1722994Y237899D01*
X1728103D01*
X1728157Y237856D01*
G03X1737806Y234486I9650J12132D01*
G01X1743564D01*
G03X1750854Y236308I-2J15502D01*
G01X1750898Y236331D01*
X1754889D01*
X1758440Y232780D01*
Y185572D01*
X1732994Y160126D01*
Y109394D01*
X1744451D01*
X1747686Y106159D01*
Y76989D01*
X1746322Y75625D01*
Y70302D01*
G03X1745882Y69879I10348J-11205D01*
G01X1744976Y68974D01*
X1744928Y68960D01*
G03X1749600Y37644I4672J-15309D01*
G01X1754856D01*
X1758440Y34060D01*
Y8000D01*
X1926843D01*
Y220044D01*
X1882653D01*
Y202900D01*
X1877759Y198006D01*
X1870294D01*
Y191393D01*
G03X1867294Y185052I12707J-9892D01*
G01X1867281Y184996D01*
X1852591Y170306D01*
X1850654D01*
X1850082Y170878D01*
X1850077Y170952D01*
G03X1832060Y185764I-16058J-1169D01*
G01X1831963Y185752D01*
X1827256Y190459D01*
Y198556D01*
X1818931D01*
G03X1809500Y201606I-9431J-13056D01*
G01X1804398D01*
X1801700Y204304D01*
Y207311D01*
X1803306Y208917D01*
X1803374Y208926D01*
G03X1838900Y239487I-5441J42254D01*
G01X1840941D01*
X1842943Y237485D01*
X1846331D01*
X1846382Y237450D01*
G03X1855198Y234698I8818J12750D01*
G01X1862102D01*
G03X1871535Y237899I-1J15502D01*
G01X1880487D01*
Y333854D01*
X1851299Y363042D01*
G03X1848806Y366643I-14529J-7395D01*
G01Y410806D01*
X1841749D01*
G03X1838590Y412647I-9637J-12905D01*
G01X1835931Y415306D01*
Y419665D01*
X1828872D01*
X1826823Y421714D01*
Y429977D01*
X1829576Y432730D01*
X1846734D01*
X1859000Y444996D01*
X1866947Y452942D01*
X1926843D01*
Y672800D01*
X1882653D01*
Y654005D01*
G03X1876856Y651006I4347J-15505D01*
G01X1870294D01*
Y641009D01*
X1869841Y640556D01*
X1868044D01*
Y638759D01*
X1851551Y622266D01*
X1849657D01*
X1847501Y624422D01*
Y631714D01*
X1827659Y651556D01*
X1818931D01*
G03X1815809Y653319I-9431J-13056D01*
G01Y655977D01*
X1842554Y682722D01*
Y686293D01*
X1844149Y687888D01*
X1846922D01*
X1846970Y687859D01*
G03X1855031Y685598I8062J13241D01*
G01X1861933D01*
G03X1872894Y690138I0J15502D01*
G01X1873411Y690655D01*
X1880487D01*
Y729817D01*
X1880484Y729820D01*
Y729938D01*
X1879284Y731138D01*
Y816431D01*
G03X1880036Y822726I-15503J5044D01*
G01X1880029Y822817D01*
X1881206Y823994D01*
Y829635D01*
X1883603Y832032D01*
G03X1890934Y837036I-5063J15290D01*
G03X1899510Y848185I-7197J14409D01*
G01X1918844Y867519D01*
X1926843D01*
Y1126050D01*
G03X1909955Y1125556I-8043J-13950D01*
G01X1882653D01*
Y1111269D01*
X1875390Y1104006D01*
X1870294D01*
Y1094009D01*
X1869927Y1093642D01*
X1868207D01*
Y1091922D01*
X1851508Y1075223D01*
X1848767D01*
X1847501Y1076489D01*
Y1084214D01*
X1840536Y1091179D01*
Y1180292D01*
G03X1755330I-42603J0D01*
G01Y1156692D01*
G03X1758440Y1140713I42605J0D01*
G01Y1085350D01*
X1762959D01*
G03X1764953Y1082375I15585J8290D01*
G01X1764999Y1082320D01*
Y1079658D01*
X1762512Y1077171D01*
X1759958D01*
X1759922Y1077186D01*
G03X1737003Y1061718I-6316J-15355D01*
G01Y1052815D01*
X1732594Y1048406D01*
Y1001888D01*
X1729970Y999264D01*
X1727013D01*
X1725840Y1000437D01*
Y1012250D01*
G03X1724256Y1019039I-15341J0D01*
G01Y1083459D01*
X1703659Y1104056D01*
X1694931D01*
G03X1685500Y1107106I-9431J-13056D01*
G01X1680429D01*
X1677036Y1110499D01*
G03X1674434Y1115366I-15292J-5046D01*
G01Y1125556D01*
X1634228D01*
Y1085350D01*
X1638747D01*
G03X1640044Y1083273I15586J8289D01*
G01X1640082Y1083221D01*
Y1080539D01*
X1636842Y1077299D01*
X1635428D01*
X1635393Y1077313D01*
G03X1612967Y1059418I-5999J-15482D01*
G01X1612969Y1059404D01*
Y1052681D01*
X1608694Y1048406D01*
Y1018788D01*
X1607153Y1017247D01*
G03X1602660Y1006400I10847J-10847D01*
G01Y989821D01*
G02X1601871Y989730I-400J1D01*
G03X1601840Y989858I-15860J-3773D01*
G01Y1011000D01*
G03X1600256Y1017789I-15341J0D01*
G01Y1063756D01*
X1599501Y1064511D01*
Y1084214D01*
X1592504Y1091211D01*
Y1207904D01*
X1605099Y1220499D01*
X1728714D01*
X1756481Y1248266D01*
Y1395640D01*
X1758552Y1397711D01*
X1771767D01*
X1774499Y1400443D01*
X1776193D01*
Y1402137D01*
X1783427Y1409371D01*
Y1423060D01*
X1789712Y1429345D01*
X1792677D01*
X1792720Y1429302D01*
X1808950D01*
X1819192Y1439544D01*
Y1444758D01*
X1822278Y1447844D01*
X1855857D01*
G03X1881769Y1446598I13643J13656D01*
G03X1885582Y1450824I-12268J14903D01*
G01X1889669Y1454911D01*
G03X1900030Y1487272I4531J16388D01*
G03X1881187Y1482243I-5830J-15972D01*
G01X1881127Y1482172D01*
X1877321D01*
X1875867Y1483626D01*
X1875875Y1483718D01*
G03X1875880Y1486455I-17450J1400D01*
G03X1868636Y1499338I-17455J-1337D01*
G01X1868615Y1499353D01*
G03X1868390Y1499511I-10173J-14247D01*
G02X1861221Y1497118I-7170J9544D01*
G01X1835627D01*
G02X1832625Y1497502I1J11937D01*
G02X1823693Y1509054I3005J11553D01*
G01Y1511685D01*
X1652488D01*
Y1500000D01*
G02X1640551Y1488063I-11937J0D01*
G01X1639879D01*
Y1488000D01*
X1639000D01*
X1636500Y1485500D01*
Y1465004D01*
G03X1636404Y1463282I15406J-1723D01*
G01Y1452546D01*
X1636394Y1452516D01*
G03Y1442484I15512J-5016D01*
G01X1636404Y1442454D01*
Y1433341D01*
X1636397Y1433315D01*
G03X1651906Y1412867I15509J-4343D01*
G01X1674735D01*
X1678125Y1409477D01*
Y1403486D01*
X1684620Y1396991D01*
Y1392714D01*
X1676387Y1384481D01*
Y1323730D01*
X1650405Y1297748D01*
X1425904D01*
X1415369Y1308283D01*
Y1352692D01*
X1368924D01*
X1363001Y1358615D01*
Y1388770D01*
X1365436Y1391205D01*
X1371794D01*
X1378251Y1397662D01*
X1391693D01*
X1394528Y1400497D01*
X1395927D01*
Y1401896D01*
X1403175Y1409144D01*
Y1440214D01*
X1400953Y1442436D01*
X1400967Y1442534D01*
G03X1399807Y1452502I-19865J2740D01*
G01X1399794Y1452537D01*
Y1459667D01*
X1399807Y1459702D01*
G03X1400016Y1473590I-18705J7227D01*
G01X1400005Y1473622D01*
Y1486631D01*
G03X1402030Y1496679I-18903J9038D01*
G01Y1511685D01*
X1252685D01*
Y1509054D01*
G02X1243753Y1497502I-11937J1D01*
G02X1240751Y1497118I-3003J11553D01*
G01X1215156D01*
G02X1212153Y1497502I0J11937D01*
G02X1207986Y1499512I3004J11553D01*
G03X1200497Y1486456I9967J-14393D01*
G01X1200498Y1486455D01*
X1200491Y1486364D01*
G03X1202427Y1477029I17462J-1247D01*
G01X1202450Y1476986D01*
Y1473821D01*
G03X1206991Y1462859I15502J0D01*
G01X1215312Y1454538D01*
G03X1217118Y1452990I10962J10962D01*
G01Y1447744D01*
X1218308Y1446554D01*
X1239170D01*
X1240385Y1445339D01*
X1240388Y1445262D01*
G03X1252837Y1430313I16086J738D01*
G01X1257925Y1425225D01*
X1257912Y1425127D01*
G03X1259421Y1415900I15962J-2126D01*
G01X1259441Y1415858D01*
Y1413245D01*
X1256572Y1410376D01*
X1234562D01*
X1230977Y1413961D01*
Y1432309D01*
X1225721D01*
G03X1223646Y1434685I-13260J-9486D01*
G01Y1440860D01*
X1187065D01*
X1183399Y1437194D01*
X1125852D01*
X1115911Y1427253D01*
X1113779D01*
X1112568Y1428464D01*
Y1457858D01*
X1115122Y1460412D01*
X1122856D01*
Y1460729D01*
X1135674Y1473547D01*
X1137687D01*
X1139832Y1475692D01*
X1143429D01*
Y1479289D01*
X1147474Y1483334D01*
Y1511685D01*
X1104691D01*
X1097567Y1504561D01*
Y1503500D01*
X1092571D01*
Y1506245D01*
G02X1092844Y1506903I933J-1D01*
G01X1102349Y1516408D01*
G02X1103007Y1516681I659J-660D01*
G01X1207283D01*
G02X1208216Y1515748I0J-933D01*
G01Y1509055D01*
G03X1212153Y1502798I6941J0D01*
G03X1215157Y1502114I3005J6257D01*
G01X1240748D01*
G03X1247689Y1509055I0J6941D01*
G01Y1515748D01*
G02X1248622Y1516681I933J0D01*
G01X1427953D01*
G02X1428886Y1515748I0J-933D01*
G01Y1500000D01*
G03X1435827Y1493059I6941J0D01*
G01X1640551D01*
G03X1647492Y1500000I0J6941D01*
G01Y1515748D01*
G02X1648425Y1516681I933J0D01*
G01X1827756D01*
G02X1828689Y1515748I0J-933D01*
G01Y1509055D01*
G03X1835630Y1502114I6941J0D01*
G01X1861220D01*
G03X1868161Y1509055I0J6941D01*
G01Y1515748D01*
G02X1869094Y1516681I933J0D01*
G01X1919094D01*
G02X1920027Y1515748I0J-933D01*
G01Y1464567D01*
G03X1926967Y1457626I6941J0D01*
G01X1930906D01*
G02X1931839Y1456693I0J-933D01*
G01Y3937D01*
G02X1930906Y3004I-933J0D01*
G01X1228346D01*
G02X1227413Y3937I0J933D01*
G01Y185827D01*
G03X1220472Y192768I-6941J0D01*
G01X1066000D01*
Y192765D01*
X1062992D01*
G02X1062056Y193701I0J936D01*
G01Y196000D01*
X1062059D01*
Y259001D01*
X1060710D01*
Y267721D01*
G03X1059847Y273130I-17403J-3D01*
G03X1060710Y278539I-16540J5412D01*
G01Y290359D01*
G03X1059847Y295768I-17403J-3D01*
G03X1060710Y301177I-16540J5412D01*
G01Y312996D01*
G03X1037008Y329216I-17403J-3D01*
G03X1022834Y328513I-6300J-16223D01*
G03X1013687Y330349I-7873J-15520D01*
G01X1013596Y330342D01*
X1011950Y331988D01*
Y344358D01*
X1014238Y346646D01*
X1076095D01*
X1094201Y364752D01*
Y376194D01*
X1097978Y379971D01*
X1136390D01*
X1139286Y377075D01*
Y370078D01*
G03X1216778Y345629I42603J0D01*
G01X1216838Y345714D01*
X1220255D01*
X1222072Y343897D01*
Y237899D01*
X1231277D01*
X1232338Y236838D01*
G03X1243299Y232298I10961J10962D01*
G01X1249336D01*
X1261590Y220044D01*
Y179838D01*
X1264652Y176776D01*
Y173484D01*
X1262936Y171768D01*
X1262838D01*
G03X1247462Y170077I-6082J-15449D01*
G01X1247411Y170043D01*
X1247410D01*
G03X1243041Y165677I9347J-13723D01*
G01X1243030Y165662D01*
X1232409Y155041D01*
Y8000D01*
X1428722D01*
Y23001D01*
G03X1429340Y29319I-15402J4696D01*
G01X1429330Y29413D01*
X1431516Y31599D01*
X1434758D01*
X1435553Y32394D01*
X1436000D01*
G03X1445768Y35694I0J16107D01*
G01X1462106D01*
Y42662D01*
X1479365Y59921D01*
Y188579D01*
G03X1474872Y199426I-15340J0D01*
G01X1467802Y206496D01*
X1467787Y206527D01*
G03X1460027Y214287I-14735J-6975D01*
G01X1459996Y214302D01*
X1446173Y228125D01*
X1388267D01*
X1384206Y232186D01*
Y410006D01*
X1377149D01*
G03X1376826Y410241I-9636J-12905D01*
G01X1376812Y410251D01*
X1372113Y414950D01*
Y427630D01*
X1376068Y431585D01*
X1437240D01*
X1447600Y421225D01*
X1447615Y421194D01*
G03X1448280Y419934I14737J6972D01*
G01Y407295D01*
G03X1440783Y393851I8306J-13444D01*
G01Y392451D01*
G03X1442534Y385222I15803J1D01*
G01Y373201D01*
G03X1447074Y362240I15502J0D01*
G01X1450464Y358850D01*
X1450478Y358822D01*
G03X1457572Y351728I14516J7422D01*
G01X1457600Y351714D01*
X1459692Y349623D01*
Y255543D01*
G03X1464232Y244582I15502J0D01*
G01X1470497Y238317D01*
Y237899D01*
X1470915D01*
X1471432Y237382D01*
G03X1482393Y232842I10961J10962D01*
G01X1489295D01*
G03X1492152Y233108I-2J15502D01*
G01X1492170Y233111D01*
X1496948D01*
X1510015Y220044D01*
Y203086D01*
G03X1508606Y186683I13085J-9386D01*
G01X1508626Y186642D01*
Y184392D01*
X1487868Y163634D01*
Y156094D01*
X1484594Y152820D01*
Y109894D01*
X1498472D01*
G03X1499194Y108992I12927J9607D01*
G01Y76922D01*
X1497897Y75625D01*
Y70298D01*
G03X1497407Y69829I10299J-11250D01*
G01X1496551Y68974D01*
X1496503Y68960D01*
G03X1501175Y37644I4672J-15309D01*
G01X1508329D01*
X1510015Y35958D01*
Y8000D01*
X1583606D01*
Y29162D01*
X1606130Y51686D01*
X1608576D01*
X1609679Y50583D01*
X1609691Y50524D01*
G03X1625388Y37644I15697J3125D01*
G01X1629533D01*
X1634228Y32949D01*
Y8000D01*
X1677147D01*
Y23001D01*
G03X1677778Y29187I-15403J4696D01*
G01X1677769Y29280D01*
X1680152Y31663D01*
X1682847D01*
X1683578Y32394D01*
X1684500D01*
G03X1694268Y35694I0J16107D01*
G01X1710606D01*
Y38745D01*
G03X1713317Y40903I-8137J13004D01*
G37*
G36*
G01X1051119Y373001D02*
X1047178Y369060D01*
X1034100D01*
Y371499D01*
X1029303Y376296D01*
X1026552D01*
X1026500Y376347D01*
X1019802D01*
X1018629Y377520D01*
Y382814D01*
X1018630Y382815D01*
Y383410D01*
X1024442Y389222D01*
X1047885D01*
X1051119Y385988D01*
Y373001D01*
G37*
G36*
G01X1030098Y363552D02*
X1010947D01*
X1009835Y364664D01*
Y372596D01*
X1010695Y373456D01*
X1016431D01*
X1017593Y372294D01*
X1027646D01*
X1030098Y369842D01*
Y363552D01*
G37*
G36*
G01X1076182Y527144D02*
G03X1091089Y503551I14907J-7087D01*
G01X1093938D01*
X1094604Y502885D01*
Y501049D01*
X1094505Y500991D01*
G03X1091638Y498840I8170J-13876D01*
G01X1058354D01*
X1022156Y535038D01*
Y551413D01*
X1023268Y552525D01*
X1028330D01*
X1040500Y540355D01*
X1068697D01*
X1074585Y534467D01*
X1074584Y534383D01*
G03X1076182Y527144I16505J-152D01*
G37*
G36*
G01X997510Y517650D02*
X996187Y516327D01*
X994028D01*
Y516541D01*
X994029Y516552D01*
G03X994040Y516737I-1591J187D01*
G01Y518137D01*
G03X993931Y518717I-1602J-1D01*
G01X993917Y518752D01*
Y525084D01*
X993933Y525122D01*
G03X994064Y525757I-1470J634D01*
G01Y527157D01*
G03X994054Y527342I-1601J6D01*
G01X994052Y527353D01*
Y530396D01*
X993963Y530485D01*
X994342Y530864D01*
X999684D01*
X1000086Y530462D01*
Y529080D01*
X997510Y526504D01*
Y517650D01*
G37*
G36*
G01X971500Y526500D02*
X970000Y528000D01*
Y538900D01*
X970595Y539495D01*
X976896D01*
X977850Y538541D01*
Y535254D01*
G03X979118Y530582I2347J-1871D01*
G01X980000Y529700D01*
Y528009D01*
X979068Y527076D01*
X976213D01*
G03X975002Y526738I0J-2338D01*
G01X972012D01*
Y526500D01*
X971500D01*
G37*
G36*
G01X974350Y553190D02*
X972810Y554730D01*
Y563856D01*
X974619Y565665D01*
X974675D01*
X974710Y565700D01*
X980210D01*
X980370Y565540D01*
Y562395D01*
G03X979370Y557697I1261J-2724D01*
G01Y556060D01*
X981750Y553680D01*
Y553259D01*
X981682Y553190D01*
X974350D01*
G37*
G36*
G01X1039800Y760500D02*
X1016200D01*
X1014394Y762306D01*
Y778483D01*
X1015894Y779983D01*
X1041394D01*
X1042394Y778983D01*
Y763094D01*
X1039800Y760500D01*
G37*
G36*
G01X1067170Y768900D02*
X1047772D01*
X1046652Y770020D01*
Y781164D01*
X1043642Y784175D01*
X1024912D01*
X1023699Y785388D01*
Y797463D01*
X1024685Y798449D01*
X1070151D01*
X1071000Y797600D01*
Y772730D01*
X1067170Y768900D01*
G37*
G36*
G01X1154802Y1090802D02*
X1054509D01*
X1047799Y1097512D01*
Y1109458D01*
G03X1045025Y1123986I-15438J4581D01*
G03X1044493Y1126790I-16025J-1588D01*
G03X1044251Y1141992I-14315J7375D01*
G01Y1153211D01*
X1048355Y1157315D01*
X1083190D01*
G03X1086806Y1149386I21338J4942D01*
G01X1086844Y1149334D01*
Y1142173D01*
X1086812Y1142123D01*
G03X1085179Y1126339I14590J-9486D01*
G03X1101402Y1102637I16223J-6299D01*
G01X1108103D01*
G03X1113866Y1103619I0J17403D01*
G03X1119629Y1102637I5763J16421D01*
G01X1126330D01*
G03X1142553Y1126339I0J17403D01*
G03X1126812Y1150034I-16223J6299D01*
G01X1126733Y1150036D01*
X1124970Y1151799D01*
Y1154391D01*
X1124983Y1154425D01*
G03X1126273Y1159627I-20455J7833D01*
G01X1126281Y1159695D01*
X1128923Y1162337D01*
X1164276D01*
X1173947Y1172008D01*
Y1195689D01*
X1163633Y1206003D01*
X1154629D01*
X1150601Y1210031D01*
Y1215181D01*
X1155919Y1220499D01*
X1242549D01*
X1259267Y1203781D01*
Y1156692D01*
G03X1267525Y1131484I42603J0D01*
G01X1267564Y1131431D01*
Y1127098D01*
X1266022Y1125556D01*
X1261590D01*
Y1085350D01*
X1264550D01*
X1266338Y1083562D01*
Y1080528D01*
X1263515Y1077705D01*
X1261622D01*
X1261594Y1077714D01*
G03X1241913Y1069271I-4838J-15883D01*
G01X1241899Y1069242D01*
X1240995Y1068338D01*
X1229154D01*
G03X1218114I-5520J-15340D01*
G01X1175061D01*
X1171492Y1071907D01*
X1171508Y1072007D01*
G03X1158733Y1090295I-15908J2493D01*
G03X1154802Y1090802I-3932J-14995D01*
G37*
G36*
G01X1036444Y1324888D02*
X1035559Y1325773D01*
X1025296D01*
X1024874Y1326195D01*
Y1330917D01*
X1025788Y1331831D01*
X1044597D01*
X1045134Y1331294D01*
Y1325457D01*
X1044565Y1324888D01*
X1040146D01*
G03X1039890I-128J-2899D01*
G01X1036444D01*
G37*
G36*
G01X1047519Y1324874D02*
X1047041Y1325352D01*
Y1331120D01*
X1047401Y1331480D01*
X1055286D01*
X1055918Y1330848D01*
Y1325175D01*
X1055617Y1324874D01*
X1051132D01*
X1051121Y1324875D01*
G03X1050515I-303J-2886D01*
G01X1050504Y1324874D01*
X1047519D01*
G37*
G36*
G01X979400Y1298900D02*
X975300Y1303000D01*
Y1351300D01*
X975694Y1351694D01*
X985302D01*
Y1351700D01*
X986900D01*
X988500Y1353300D01*
Y1362200D01*
X986918Y1363782D01*
Y1388666D01*
X986927Y1388675D01*
Y1393349D01*
X988836Y1395258D01*
X1016649D01*
X1023718Y1388189D01*
Y1387060D01*
X1023672Y1387015D01*
Y1381297D01*
X1023718Y1381252D01*
Y1380329D01*
X1023716Y1380328D01*
Y1361062D01*
X1023718Y1361061D01*
Y1359260D01*
X1023672Y1359215D01*
Y1353497D01*
X1023718Y1353452D01*
Y1352220D01*
X1023716Y1352219D01*
Y1333513D01*
X1023718Y1333512D01*
Y1331460D01*
X1023672Y1331415D01*
Y1325697D01*
X1023718Y1325652D01*
Y1324188D01*
X1023716Y1324187D01*
Y1310591D01*
X1023718Y1310590D01*
Y1304770D01*
X1023674Y1304726D01*
X1023800Y1304600D01*
Y1300700D01*
X1022000Y1298900D01*
X979400D01*
G37*
G36*
G01X1027032Y1308975D02*
X1024918Y1311089D01*
Y1323689D01*
X1025218Y1323989D01*
X1035394D01*
X1035960Y1323423D01*
X1056052D01*
X1057265Y1324636D01*
Y1331635D01*
X1055733Y1333167D01*
X1025762D01*
X1024918Y1334011D01*
Y1351721D01*
X1025296Y1352099D01*
X1035892D01*
X1036785Y1351206D01*
X1056083D01*
X1057265Y1352388D01*
Y1352894D01*
X1057272Y1352900D01*
Y1358731D01*
X1057265Y1358737D01*
Y1358883D01*
X1057057Y1359091D01*
X1057042Y1359128D01*
G03X1055807Y1360363I-2124J-889D01*
G01X1055770Y1360378D01*
X1055194Y1360954D01*
X1025524D01*
X1024918Y1361560D01*
Y1379830D01*
X1025249Y1380161D01*
X1034972D01*
X1036161Y1378972D01*
X1053982D01*
X1053985Y1378975D01*
X1055596D01*
X1055859Y1379238D01*
G03X1057019Y1380398I-941J2101D01*
G01X1059107Y1382486D01*
X1062849D01*
X1071597Y1373738D01*
Y1316068D01*
X1064504Y1308975D01*
X1027032D01*
G37*
G36*
G01X1036474Y1380458D02*
X1035559Y1381373D01*
X1025296D01*
X1024874Y1381795D01*
Y1386517D01*
X1025788Y1387431D01*
X1030777D01*
X1030820Y1387388D01*
X1034565D01*
X1034591Y1387414D01*
X1044156D01*
X1044977Y1386592D01*
Y1380900D01*
X1044535Y1380458D01*
X1036474D01*
G37*
G36*
G01X1044577Y1352700D02*
X1037300D01*
X1036427Y1353573D01*
X1025296D01*
X1024874Y1353995D01*
Y1358717D01*
X1025788Y1359631D01*
X1044138D01*
X1045134Y1358635D01*
Y1353257D01*
X1044577Y1352700D01*
G37*
G36*
G01X1031013Y1395877D02*
X1030231Y1396659D01*
Y1401493D01*
X1031181Y1402443D01*
X1043812D01*
X1044956Y1401300D01*
Y1396939D01*
X1043898Y1395882D01*
X1031211D01*
X1031207Y1395877D01*
X1031013D01*
G37*
G36*
G01X1055384Y1352712D02*
X1047311D01*
X1047041Y1352982D01*
Y1358665D01*
X1047377Y1359001D01*
X1055302D01*
X1056070Y1358233D01*
Y1353398D01*
X1055384Y1352712D01*
G37*
G36*
G01X1046792Y1380484D02*
X1046178Y1381097D01*
Y1387090D01*
X1046157Y1387111D01*
Y1401659D01*
X1046791Y1402293D01*
X1056314D01*
X1057118Y1401489D01*
Y1382608D01*
X1054994Y1380484D01*
X1046792D01*
G37*
G36*
G01X1034067Y1388589D02*
X1031318D01*
X1030818Y1389089D01*
Y1393789D01*
X1031709Y1394680D01*
X1043601D01*
X1044882Y1393399D01*
Y1389803D01*
X1043694Y1388615D01*
X1034093D01*
X1034067Y1388589D01*
G37*
G36*
G01X1054664Y1407664D02*
X1047714D01*
X1047200Y1408177D01*
Y1412100D01*
X1048800Y1413700D01*
Y1418900D01*
X1049500Y1419600D01*
Y1427500D01*
X1047500Y1429500D01*
Y1434500D01*
X1048000Y1435000D01*
X1055000D01*
X1055500Y1434500D01*
Y1408500D01*
X1054664Y1407664D01*
G37*
G36*
G01X986150Y1449650D02*
X985200Y1450600D01*
Y1456000D01*
X985800Y1456600D01*
X990150D01*
X990910Y1455840D01*
X990925Y1455797D01*
G03X991150Y1455327I2175J753D01*
G01Y1449650D01*
X986150D01*
G37*
G36*
G01X1067350Y1477614D02*
X1041650D01*
X1041150Y1478114D01*
Y1486214D01*
X1041650Y1486714D01*
X1067250D01*
X1068250Y1485714D01*
Y1478514D01*
X1067350Y1477614D01*
G37*
G36*
G01X1044750Y1489814D02*
X1044150Y1490414D01*
Y1492049D01*
G03X1044152Y1492114I-1599J82D01*
G01Y1493514D01*
G03X1044150Y1493579I-1601J-17D01*
G01Y1493814D01*
X1044650Y1494314D01*
X1047350D01*
X1047650Y1494614D01*
Y1496914D01*
X1048150Y1497414D01*
X1067650D01*
X1068350Y1496714D01*
Y1490414D01*
X1067750Y1489814D01*
X1044750D01*
G37*
G36*
G01X1043303Y1429207D02*
X1042016Y1430494D01*
X1036887D01*
X1036879Y1430495D01*
G03X1036743Y1430500I-127J-1596D01*
G01X1035143D01*
G03X1035007Y1430495I-9J-1601D01*
G01X1034999Y1430494D01*
X1034758D01*
X1034200Y1431052D01*
Y1433479D01*
X1033253Y1434426D01*
X1029976D01*
X1028689Y1435713D01*
Y1440216D01*
X1029479Y1441006D01*
X1035510D01*
X1041131Y1435385D01*
X1045233D01*
X1046265Y1434353D01*
Y1429571D01*
X1045901Y1429207D01*
X1043303D01*
G37*
G36*
G01X1077300Y369066D02*
X1063568D01*
X1062254Y370380D01*
Y385970D01*
X1064957Y388673D01*
X1077800D01*
X1079200Y387273D01*
Y370966D01*
X1077300Y369066D01*
G37*
G36*
G01X1125677Y394972D02*
X1099677D01*
X1098000Y396649D01*
Y409295D01*
X1100177Y411472D01*
X1125677D01*
X1126677Y410472D01*
Y395972D01*
X1125677Y394972D01*
G37*
G36*
G01X1184923Y447917D02*
G03X1186387Y440234I16077J-918D01*
G01X1186406Y440194D01*
Y439381D01*
X1183283Y436258D01*
X1183197Y436261D01*
G03X1145554Y415923I-1309J-42583D01*
G01X1145496Y415827D01*
X1142855D01*
X1141678Y417004D01*
Y431780D01*
G03X1150005Y438901I-5678J15069D01*
G01X1150018Y438924D01*
X1163744Y452650D01*
X1163805Y452661D01*
G03X1175196Y461089I-2905J15839D01*
G01X1175210Y461116D01*
X1176987Y462893D01*
X1181581D01*
X1185008Y459467D01*
Y456395D01*
X1185001Y456368D01*
G03X1184923Y447917I15499J-4369D01*
G37*
G36*
G01X1098676Y415474D02*
X1098000Y416149D01*
Y429295D01*
X1099677Y430972D01*
X1125677D01*
X1126677Y429972D01*
Y415474D01*
X1098676D01*
G37*
G36*
G01X1134044Y997221D02*
Y989915D01*
X1131631Y987502D01*
X1098358D01*
X1096001Y989859D01*
Y996682D01*
X1097144Y997825D01*
X1133440D01*
X1134044Y997221D01*
G37*
G36*
G01X1134600Y1193400D02*
X1108600D01*
X1107600Y1194400D01*
Y1208400D01*
X1109100Y1209900D01*
X1134600D01*
X1135600Y1208900D01*
Y1194400D01*
X1134600Y1193400D01*
G37*
G36*
G01X1107600Y1213902D02*
Y1228400D01*
X1108600Y1229400D01*
X1134600D01*
X1135600Y1228400D01*
Y1213902D01*
X1107600D01*
G37*
G36*
G01X1120532Y1313668D02*
X1119500Y1314700D01*
Y1320200D01*
X1120000Y1320700D01*
X1133500D01*
X1134000Y1320200D01*
Y1315200D01*
X1132468Y1313668D01*
X1126515D01*
G03X1126415Y1313672I-114J-1597D01*
G01X1124815D01*
G03X1124715Y1313668I14J-1601D01*
G01X1121641D01*
X1121629Y1313670D01*
G03X1121063I-283J-2285D01*
G01X1121051Y1313668D01*
X1120532D01*
G37*
G36*
G01X1111500Y1325000D02*
X1110500Y1326000D01*
Y1337500D01*
X1111000Y1338000D01*
X1117000D01*
X1118500Y1336500D01*
Y1326000D01*
X1117500Y1325000D01*
X1111500D01*
G37*
G36*
G01X1120302Y1306700D02*
Y1306722D01*
X1112978D01*
X1112500Y1307200D01*
Y1311700D01*
X1113269Y1312469D01*
X1120032D01*
X1120034Y1312466D01*
X1132966D01*
X1132968Y1312469D01*
X1133231D01*
X1134000Y1311700D01*
Y1307700D01*
X1133000Y1306700D01*
X1120302D01*
G37*
G36*
G01X1107400Y1340800D02*
Y1348100D01*
X1106900Y1348600D01*
X1105306D01*
X1103300Y1350606D01*
Y1355700D01*
X1103800Y1356200D01*
X1110900D01*
X1111300Y1355800D01*
Y1349500D01*
X1109700Y1347900D01*
Y1341000D01*
X1109500Y1340800D01*
X1107400D01*
G37*
G36*
G01X1085630Y1414319D02*
G03X1092571Y1421260I0J6941D01*
G01Y1477366D01*
X1097567D01*
Y1421260D01*
G02X1085630Y1409323I-11937J0D01*
G01X1076575D01*
G02X1064638Y1421260I0J11937D01*
G01Y1475639D01*
X1069634D01*
Y1421260D01*
G03X1076575Y1414319I6941J0D01*
G01X1085630D01*
G37*
G36*
G01X1111500Y1341000D02*
X1111000Y1341500D01*
Y1347500D01*
X1113000Y1349500D01*
Y1355800D01*
X1114100Y1356900D01*
Y1357735D01*
G03X1114102Y1357800I-1599J82D01*
G01Y1359200D01*
G03X1114100Y1359265I-1601J-17D01*
G01Y1359700D01*
X1114500Y1360100D01*
X1119300D01*
X1120000Y1359400D01*
Y1341500D01*
X1119500Y1341000D01*
X1111500D01*
G37*
G36*
G01X1131473Y1488548D02*
X1123573D01*
X1122973Y1489148D01*
Y1497548D01*
X1123573Y1498148D01*
X1131673D01*
X1132473Y1497348D01*
Y1489548D01*
X1131473Y1488548D01*
G37*
G36*
G01X1119773Y1489148D02*
X1093754D01*
X1092961Y1489941D01*
Y1500808D01*
X1094101Y1501948D01*
X1119473D01*
X1120473Y1500948D01*
Y1489848D01*
X1119773Y1489148D01*
G37*
G36*
G01X1119660Y1478748D02*
X1094039D01*
X1093187Y1479600D01*
Y1486884D01*
X1093751Y1487448D01*
X1119552D01*
X1120412Y1486588D01*
Y1479500D01*
X1119660Y1478748D01*
G37*
G36*
G01X1224492Y393678D02*
G03X1204884Y429541I-42601J0D01*
G01X1204792Y429600D01*
Y431349D01*
G03X1209071Y433065I-3793J15650D01*
G01X1209117Y433092D01*
X1211383D01*
X1226794Y417681D01*
Y368218D01*
X1226055Y367479D01*
X1224756D01*
X1224431Y367804D01*
X1224436Y367893D01*
G03X1224492Y370078I-42547J2184D01*
G01Y393678D01*
G37*
G36*
G01X1196481Y739507D02*
Y721868D01*
G03X1192749Y717063I10784J-12227D01*
G01X1192735Y717035D01*
X1178233Y702532D01*
X1153316D01*
G03X1152128Y705884I-15869J-3738D01*
G03Y720058I-14682J7087D01*
G03Y734230I-14682J7086D01*
G03Y748404I-14682J7087D01*
G03Y762576I-14682J7086D01*
G03X1153201Y765470I-14681J7089D01*
G01X1179165D01*
G03X1190967Y760292I11830J10925D01*
G02X1191348Y759775I-1J-400D01*
G03X1191666Y749294I15589J-4772D01*
G03X1196090Y739898I15271J1451D01*
G01X1196481Y739507D01*
G37*
G36*
G01X1222593Y1311283D02*
X1222392Y1311484D01*
X1210172D01*
X1210146Y1311491D01*
G03X1209733Y1311546I-416J-1547D01*
G01X1208133D01*
G03X1207720Y1311491I3J-1602D01*
G01X1207694Y1311484D01*
X1206674D01*
X1206172Y1311986D01*
Y1321711D01*
X1206843Y1322382D01*
X1218148D01*
X1236296D01*
X1236894Y1321783D01*
Y1313283D01*
X1234894Y1311283D01*
X1222593D01*
G37*
G36*
G01X1189387D02*
X1189186Y1311484D01*
X1176833D01*
X1176819Y1311486D01*
G03X1176600Y1311502I-226J-1585D01*
G01X1175000D01*
G03X1174781Y1311486I7J-1601D01*
G01X1174767Y1311484D01*
X1171486D01*
X1170688Y1312283D01*
Y1321783D01*
X1171287Y1322382D01*
X1184942D01*
X1203090D01*
X1203688Y1321783D01*
Y1313283D01*
X1201688Y1311283D01*
X1189387D01*
G37*
G36*
G01X1206687Y1301283D02*
X1206342Y1301628D01*
Y1309860D01*
X1206765Y1310283D01*
X1219798D01*
Y1310282D01*
X1221896D01*
X1222394Y1309783D01*
Y1301783D01*
X1221894Y1301283D01*
X1206687D01*
G37*
G36*
G01X1171688D02*
X1170688Y1302283D01*
Y1309283D01*
X1171688Y1310283D01*
X1186592D01*
Y1310282D01*
X1188690D01*
X1189188Y1309783D01*
Y1301783D01*
X1188688Y1301283D01*
X1171688D01*
G37*
G36*
G01X1205114Y1399323D02*
Y1399334D01*
X1198950D01*
X1198612Y1399673D01*
Y1406173D01*
X1199412Y1406973D01*
X1205512D01*
X1207459Y1405026D01*
G03X1208069Y1404416I1687J1077D01*
G01X1208412Y1404073D01*
Y1402579D01*
G03X1208410Y1402514I1599J-82D01*
G01Y1401114D01*
G03X1208412Y1401049I1601J17D01*
G01Y1400873D01*
X1206862Y1399323D01*
X1205114D01*
G37*
G36*
G01X1298000Y75000D02*
X1297340Y75661D01*
Y85339D01*
X1298000Y86000D01*
X1316500D01*
X1317500Y85000D01*
Y76000D01*
X1316500Y75000D01*
X1298000D01*
G37*
G36*
G01X1301550Y156244D02*
X1294730Y163064D01*
Y163720D01*
X1294074D01*
X1293550Y164244D01*
X1283450D01*
X1282450Y165244D01*
Y167344D01*
X1283350Y168244D01*
X1306950D01*
X1310950Y164244D01*
Y156744D01*
X1310450Y156244D01*
X1301550D01*
G37*
G36*
G01X1301500Y122000D02*
X1297000D01*
X1296000Y123000D01*
Y133000D01*
X1294500Y134500D01*
X1284500D01*
X1283500Y135500D01*
Y137000D01*
X1284500Y138000D01*
X1297500D01*
X1302500Y133000D01*
Y123000D01*
X1301500Y122000D01*
G37*
G36*
G01X1307764Y201606D02*
X1305872Y203498D01*
Y207100D01*
X1307758Y208986D01*
G03X1336835Y226840I-5888J42194D01*
G01X1336895Y226926D01*
X1339180D01*
X1349260Y216846D01*
Y195120D01*
G03X1349248Y184113I15340J-5520D01*
G01X1349260Y184080D01*
Y179147D01*
X1346752Y176639D01*
X1344576D01*
X1330756Y190459D01*
Y198556D01*
X1322431D01*
G03X1313000Y201606I-9431J-13056D01*
G01X1307764D01*
G37*
G36*
G01X1335000Y135500D02*
X1317500D01*
X1316500Y136500D01*
Y153000D01*
X1314450Y155050D01*
Y164150D01*
X1309100Y169500D01*
X1284500D01*
X1283500Y170500D01*
Y177000D01*
X1284500Y178000D01*
X1300000D01*
X1302000Y176000D01*
X1324000D01*
X1336000Y164000D01*
Y136500D01*
X1335000Y135500D01*
G37*
G36*
G01X1304000Y97500D02*
X1302000Y99500D01*
Y120500D01*
X1303048Y121548D01*
X1303202D01*
Y121702D01*
X1304500Y123000D01*
Y133000D01*
X1298000Y139500D01*
X1284500D01*
X1283500Y140500D01*
Y147000D01*
X1284500Y148000D01*
X1302500D01*
X1305000Y145500D01*
X1312000D01*
X1314000Y143500D01*
Y108500D01*
X1318500Y104000D01*
Y98500D01*
X1317500Y97500D01*
X1304000D01*
G37*
G36*
G01X1317000Y108000D02*
X1315500Y109500D01*
Y123500D01*
X1316500Y124500D01*
X1329000D01*
X1330000Y123500D01*
Y115500D01*
X1330500Y115000D01*
X1331441D01*
X1331912Y114529D01*
X1331904Y114437D01*
G03X1331898Y114300I1596J-139D01*
G01Y112700D01*
G03X1331909Y112515I1602J2D01*
G01X1331910Y112504D01*
Y110396D01*
X1331909Y110385D01*
G03X1331898Y110200I1591J-187D01*
G01Y108800D01*
G03X1331909Y108615I1602J2D01*
G01X1331910Y108604D01*
Y108000D01*
X1317000D01*
G37*
G36*
G01X1309936Y347724D02*
X1315610Y342050D01*
Y317709D01*
X1314413Y316512D01*
X1310443D01*
X1310423Y316516D01*
G03X1279869Y311263I-8553J-41736D01*
G01X1279821Y311234D01*
X1277709D01*
X1276562Y312381D01*
Y328851D01*
X1290858Y343146D01*
X1290966Y343120D01*
G03X1306252Y347662I3658J15682D01*
G01X1306311Y347724D01*
X1309936D01*
G37*
G36*
G01X1316208Y397187D02*
X1314175D01*
X1312105Y399257D01*
Y410093D01*
X1297652Y424546D01*
Y427731D01*
X1299481Y429560D01*
X1316939D01*
X1323311Y423188D01*
Y406797D01*
G03X1317165Y398144I9063J-12946D01*
G01X1316208Y397187D01*
G37*
G36*
G01X1313000Y542500D02*
X1305500D01*
X1304500Y543500D01*
Y586000D01*
X1298000Y592500D01*
X1284500D01*
X1283500Y593500D01*
Y600000D01*
X1284500Y601000D01*
X1302500D01*
X1305000Y598500D01*
X1312000D01*
X1314000Y596500D01*
Y543500D01*
X1313000Y542500D01*
G37*
G36*
G01X1317500Y561000D02*
X1315500Y563000D01*
Y576500D01*
X1316500Y577500D01*
X1329500D01*
X1330500Y576500D01*
Y568500D01*
X1331000Y568000D01*
X1332500D01*
X1332910Y567590D01*
Y567496D01*
G03X1332898Y567300I1590J-196D01*
G01Y565700D01*
G03X1332909Y565515I1602J2D01*
G01X1332910Y565504D01*
Y563396D01*
X1332909Y563385D01*
G03X1332898Y563200I1591J-187D01*
G01Y561800D01*
G03X1332920Y561538I1602J3D01*
G01X1332937Y561437D01*
X1332500Y561000D01*
X1317500D01*
G37*
G36*
G01X1326000Y537000D02*
X1325000Y538000D01*
Y556500D01*
X1326000Y557500D01*
X1335000D01*
X1335660Y556840D01*
Y537660D01*
X1335000Y537000D01*
X1326000D01*
G37*
G36*
G01X1310462Y609000D02*
X1303262D01*
X1295662Y616600D01*
X1283862D01*
X1282862Y617600D01*
Y620400D01*
X1283412Y620950D01*
X1292412D01*
X1292462Y621000D01*
X1306962D01*
X1310962Y617000D01*
Y609500D01*
X1310462Y609000D01*
G37*
G36*
G01X1301500Y575000D02*
X1297000D01*
X1296000Y576000D01*
Y586000D01*
X1294500Y587500D01*
X1284500D01*
X1283500Y588500D01*
Y590000D01*
X1284500Y591000D01*
X1297500D01*
X1302500Y586000D01*
Y576000D01*
X1301500Y575000D01*
G37*
G36*
G01X1353340Y559750D02*
G03X1351756Y566539I-15341J0D01*
G01Y630959D01*
X1338714Y644001D01*
X1332138D01*
X1330756Y645383D01*
Y648422D01*
X1331794Y649460D01*
X1384081D01*
X1385803Y647738D01*
Y637592D01*
X1360394Y612183D01*
Y556692D01*
X1361760Y555326D01*
Y523346D01*
X1351699Y513285D01*
X1350863D01*
X1350037Y514111D01*
Y516971D01*
X1351435Y518369D01*
Y518747D01*
X1351556Y518799D01*
G03X1353340Y547504I-6341J14802D01*
G01Y559750D01*
G37*
G36*
G01X1335000Y589000D02*
X1317500D01*
X1316500Y590000D01*
Y606000D01*
X1314700Y607800D01*
Y616800D01*
X1309000Y622500D01*
X1284500D01*
X1283500Y623500D01*
Y630000D01*
X1284500Y631000D01*
X1300000D01*
X1302000Y629000D01*
X1332500D01*
X1336000Y625500D01*
Y590000D01*
X1335000Y589000D01*
G37*
G36*
G01X1384206Y863506D02*
X1375647Y872065D01*
X1365844D01*
X1361496Y876413D01*
X1328919D01*
X1315376Y862870D01*
Y776514D01*
X1308688Y769826D01*
X1307031D01*
X1307019Y769827D01*
G03X1283298Y765879I-5151J-42290D01*
G01X1283257Y765859D01*
X1277639D01*
X1274440Y769058D01*
Y858954D01*
X1262095Y871299D01*
Y876140D01*
X1266812Y880857D01*
X1718582D01*
X1719260Y880179D01*
Y878505D01*
X1716508Y875753D01*
X1705926D01*
X1697211Y867038D01*
X1696705D01*
Y866532D01*
X1656860Y826687D01*
Y684332D01*
X1654693Y682165D01*
X1599883D01*
X1598640Y683408D01*
Y686034D01*
X1599795Y687189D01*
X1600553D01*
X1600587Y687176D01*
G03X1606006Y686198I5419J14524D01*
G01X1614107D01*
G03X1624985Y690655I0J15503D01*
G01X1632062D01*
X1632706Y691299D01*
Y863006D01*
X1623647Y872065D01*
X1612511D01*
X1608736Y875840D01*
X1577623D01*
X1563149Y861366D01*
Y817257D01*
X1567960Y812446D01*
Y770777D01*
X1566157Y768974D01*
X1559800D01*
X1559777Y768979D01*
G03X1511055Y745029I-9876J-41442D01*
G01X1511002Y744911D01*
X1507694D01*
X1506646Y745959D01*
Y751911D01*
X1508706Y753971D01*
Y847801D01*
G03X1508717Y858367I-15206J5299D01*
G01X1508706Y858399D01*
Y863006D01*
X1499647Y872065D01*
X1488023D01*
X1484115Y875973D01*
X1450779D01*
X1433660Y858854D01*
Y697554D01*
X1422321Y686215D01*
X1377660D01*
X1376959Y686916D01*
Y689426D01*
X1378188Y690655D01*
X1383637D01*
Y729817D01*
X1382434Y731020D01*
Y784066D01*
X1384206Y785838D01*
Y863506D01*
G37*
G36*
G01X1301500Y1027500D02*
X1297000D01*
X1296000Y1028500D01*
Y1038500D01*
X1294500Y1040000D01*
X1284500D01*
X1283500Y1041000D01*
Y1042500D01*
X1284500Y1043500D01*
X1297500D01*
X1302500Y1038500D01*
Y1028500D01*
X1301500Y1027500D01*
G37*
G36*
G01X1335000Y1041500D02*
X1317500D01*
X1316500Y1042500D01*
Y1058500D01*
X1314500Y1060500D01*
Y1069100D01*
X1308600Y1075000D01*
X1284500D01*
X1283500Y1076000D01*
Y1082500D01*
X1284500Y1083500D01*
X1300000D01*
X1302000Y1081500D01*
X1332500D01*
X1336000Y1078000D01*
Y1042500D01*
X1335000Y1041500D01*
G37*
G36*
G01X1313000Y995000D02*
X1305500D01*
X1304500Y996000D01*
Y1038500D01*
X1298000Y1045000D01*
X1284500D01*
X1283500Y1046000D01*
Y1052500D01*
X1284500Y1053500D01*
X1302500D01*
X1305000Y1051000D01*
X1312000D01*
X1314000Y1049000D01*
Y996000D01*
X1313000Y995000D01*
G37*
G36*
G01X1332500Y1013500D02*
X1317500D01*
X1315500Y1015500D01*
Y1029000D01*
X1316500Y1030000D01*
X1329500D01*
X1330500Y1029000D01*
Y1021000D01*
X1331000Y1020500D01*
X1332500D01*
X1332888Y1020112D01*
Y1013888D01*
X1332500Y1013500D01*
G37*
G36*
G01X1326000Y989500D02*
X1325000Y990500D01*
Y1009000D01*
X1326000Y1010000D01*
X1335000D01*
X1335660Y1009340D01*
Y990160D01*
X1335000Y989500D01*
X1326000D01*
G37*
G36*
G01X1310462Y1061756D02*
X1303262D01*
X1295662Y1069356D01*
X1283862D01*
X1282862Y1070356D01*
Y1073156D01*
X1283412Y1073706D01*
X1292412D01*
X1292462Y1073756D01*
X1306962D01*
X1310962Y1069756D01*
Y1062256D01*
X1310462Y1061756D01*
G37*
G36*
G01X1353340Y1012250D02*
G03X1351756Y1019039I-15341J0D01*
G01Y1083459D01*
X1338707Y1096508D01*
Y1135290D01*
G03X1344473Y1156692I-36837J21402D01*
G01Y1210848D01*
X1354124Y1220499D01*
X1497463D01*
X1507298Y1210664D01*
Y1156692D01*
G03X1510000Y1141761I42605J0D01*
G01Y1090518D01*
X1483994Y1064512D01*
Y1012174D01*
X1481590Y1009770D01*
X1478846D01*
X1477340Y1011276D01*
Y1012250D01*
G03X1475756Y1019039I-15341J0D01*
G01Y1083459D01*
X1455159Y1104056D01*
X1446431D01*
G03X1437000Y1107106I-9431J-13056D01*
G01X1431959D01*
X1428633Y1110432D01*
G03X1426009Y1115366I-15314J-4979D01*
G01Y1125556D01*
X1385803D01*
Y1085350D01*
X1379531Y1079078D01*
X1374163D01*
X1364631Y1069546D01*
Y1064984D01*
X1364662Y1064953D01*
X1364643Y1064850D01*
G03X1364411Y1060601I16326J-3022D01*
G01X1364412Y1060594D01*
Y1052524D01*
X1360194Y1048306D01*
Y1006592D01*
X1361560Y1005226D01*
Y989057D01*
X1358422Y985919D01*
X1354973D01*
Y985975D01*
X1353760Y987188D01*
X1353754Y987261D01*
G03X1353340Y989858I-16254J-1260D01*
G01Y1012250D01*
G37*
G36*
G01X1284796Y1393419D02*
G03X1293636Y1398479I-3170J15791D01*
G01X1293695Y1398546D01*
X1294308D01*
X1295621Y1397233D01*
Y1393482D01*
X1285678Y1383539D01*
Y1302520D01*
X1281096Y1297938D01*
X1255886D01*
X1253856Y1299968D01*
Y1319956D01*
X1257800Y1323900D01*
Y1367615D01*
G03X1258253Y1368044I-10844J11904D01*
G03X1262148Y1371117I-7908J14028D01*
G03X1276425Y1381879I-924J16076D01*
G03X1282597Y1391220I-9511J12994D01*
G01X1284796Y1393419D01*
G37*
G36*
G01X1369874Y1410500D02*
X1360074D01*
X1358874Y1411700D01*
Y1416100D01*
X1351474Y1423500D01*
X1335500D01*
X1331500Y1427500D01*
Y1435500D01*
X1335000Y1439000D01*
X1354374D01*
X1356374Y1441000D01*
Y1475000D01*
X1359374Y1478000D01*
X1365374D01*
X1371874Y1471500D01*
Y1440041D01*
X1371309Y1439476D01*
Y1411935D01*
X1369874Y1410500D01*
G37*
G36*
G01X1307100Y1408800D02*
X1304500Y1411400D01*
Y1422700D01*
X1305900Y1424100D01*
X1312084D01*
X1312115Y1423938D01*
G03X1315504Y1422369I2260J437D01*
G02X1316100Y1422020I196J-349D01*
G01Y1419000D01*
X1317197Y1417903D01*
X1318687D01*
G03X1318800Y1417898I127J1596D01*
G01X1320200D01*
G03X1320313Y1417903I-14J1601D01*
G01X1320497D01*
X1320900Y1417500D01*
Y1412100D01*
X1320300Y1411500D01*
X1317000D01*
X1314300Y1408800D01*
X1307100D01*
G37*
G36*
G01X1437000Y89500D02*
X1429500D01*
X1428500Y90500D01*
Y133000D01*
X1422000Y139500D01*
X1408500D01*
X1407500Y140500D01*
Y147000D01*
X1408500Y148000D01*
X1426500D01*
X1429000Y145500D01*
X1436000D01*
X1438000Y143500D01*
Y90500D01*
X1437000Y89500D01*
G37*
G36*
G01X1425763Y156244D02*
X1418942Y163064D01*
Y163720D01*
X1418286D01*
X1417763Y164244D01*
X1407663D01*
X1406663Y165244D01*
Y167344D01*
X1407563Y168244D01*
X1431163D01*
X1435163Y164244D01*
Y156744D01*
X1434663Y156244D01*
X1425763D01*
G37*
G36*
G01X1425500Y122000D02*
X1421000D01*
X1420000Y123000D01*
Y133000D01*
X1418500Y134500D01*
X1408500D01*
X1407500Y135500D01*
Y137000D01*
X1408500Y138000D01*
X1421500D01*
X1426500Y133000D01*
Y123000D01*
X1425500Y122000D01*
G37*
G36*
G01X1459000Y136000D02*
X1441500D01*
X1440500Y137000D01*
Y153000D01*
X1438450Y155050D01*
Y163450D01*
X1432400Y169500D01*
X1408500D01*
X1407500Y170500D01*
Y177000D01*
X1408500Y178000D01*
X1424000D01*
X1426000Y176000D01*
X1456500D01*
X1460000Y172500D01*
Y137000D01*
X1459000Y136000D01*
G37*
G36*
G01X1437000Y542500D02*
X1429500D01*
X1428500Y543500D01*
Y586000D01*
X1422000Y592500D01*
X1408500D01*
X1407500Y593500D01*
Y600000D01*
X1408500Y601000D01*
X1426500D01*
X1429000Y598500D01*
X1436000D01*
X1438000Y596500D01*
Y543500D01*
X1437000Y542500D01*
G37*
G36*
G01X1434675Y609000D02*
X1427475D01*
X1419875Y616600D01*
X1408075D01*
X1407075Y617600D01*
Y620400D01*
X1407625Y620950D01*
X1416625D01*
X1416675Y621000D01*
X1431175D01*
X1435175Y617000D01*
Y609500D01*
X1434675Y609000D01*
G37*
G36*
G01X1425500Y575000D02*
X1421000D01*
X1420000Y576000D01*
Y586000D01*
X1418500Y587500D01*
X1408500D01*
X1407500Y588500D01*
Y590000D01*
X1408500Y591000D01*
X1421500D01*
X1426500Y586000D01*
Y576000D01*
X1425500Y575000D01*
G37*
G36*
G01X1459000Y589000D02*
X1441500D01*
X1440500Y590000D01*
Y606000D01*
X1438700Y607800D01*
Y617800D01*
X1434000Y622500D01*
X1408500D01*
X1407500Y623500D01*
Y630000D01*
X1408500Y631000D01*
X1424000D01*
X1426000Y629000D01*
X1456500D01*
X1460000Y625500D01*
Y590000D01*
X1459000Y589000D01*
G37*
G36*
G01X1425500Y1027500D02*
X1421000D01*
X1420000Y1028500D01*
Y1038500D01*
X1418500Y1040000D01*
X1408500D01*
X1407500Y1041000D01*
Y1042500D01*
X1408500Y1043500D01*
X1421500D01*
X1426500Y1038500D01*
Y1028500D01*
X1425500Y1027500D01*
G37*
G36*
G01X1437000Y995000D02*
X1429500D01*
X1428500Y996000D01*
Y1038500D01*
X1422000Y1045000D01*
X1408500D01*
X1407500Y1046000D01*
Y1052500D01*
X1408500Y1053500D01*
X1426500D01*
X1429000Y1051000D01*
X1436000D01*
X1438000Y1049000D01*
Y996000D01*
X1437000Y995000D01*
G37*
G36*
G01X1434675Y1061756D02*
X1427475D01*
X1419875Y1069356D01*
X1408075D01*
X1407075Y1070356D01*
Y1073156D01*
X1407625Y1073706D01*
X1416625D01*
X1416675Y1073756D01*
X1431175D01*
X1435175Y1069756D01*
Y1062256D01*
X1434675Y1061756D01*
G37*
G36*
G01X1459000Y1041500D02*
X1441500D01*
X1440500Y1042500D01*
Y1058500D01*
X1438700Y1060300D01*
Y1069400D01*
X1433100Y1075000D01*
X1408500D01*
X1407500Y1076000D01*
Y1082500D01*
X1408500Y1083500D01*
X1424000D01*
X1426000Y1081500D01*
X1456500D01*
X1460000Y1078000D01*
Y1042500D01*
X1459000Y1041500D01*
G37*
G36*
G01X1385479Y1412663D02*
X1376703D01*
X1375274Y1414092D01*
Y1426500D01*
X1372874Y1428900D01*
Y1434900D01*
X1373474Y1435500D01*
X1386674D01*
X1388174Y1434000D01*
Y1415358D01*
X1385479Y1412663D01*
G37*
G36*
G01X1450000Y84000D02*
X1449000Y85000D01*
Y103500D01*
X1450000Y104500D01*
X1459000D01*
X1459660Y103840D01*
Y84661D01*
X1459000Y84000D01*
X1450000D01*
G37*
G36*
G01X1441500Y108000D02*
X1439500Y110000D01*
Y123500D01*
X1440500Y124500D01*
X1453500D01*
X1454500Y123500D01*
Y115500D01*
X1455000Y115000D01*
X1456500D01*
X1456910Y114590D01*
Y114496D01*
G03X1456898Y114300I1590J-196D01*
G01Y112700D01*
G03X1456909Y112515I1602J2D01*
G01X1456910Y112504D01*
Y110396D01*
X1456909Y110385D01*
G03X1456898Y110200I1591J-187D01*
G01Y108800D01*
G03X1456920Y108538I1602J3D01*
G01X1456937Y108437D01*
X1456500Y108000D01*
X1441500D01*
G37*
G36*
G01X1509770Y290472D02*
X1507524D01*
X1506646Y291350D01*
Y297261D01*
X1508706Y299321D01*
Y410494D01*
X1498608Y420592D01*
X1491598D01*
G03X1491116Y421097I-11335J-10336D01*
G01X1482276Y429937D01*
Y432688D01*
X1483198Y433610D01*
X1554552D01*
X1563583Y424579D01*
X1563598Y424548D01*
G03X1569758Y417658I14735J6975D01*
G01Y405157D01*
G03X1564996Y393851I11040J-11306D01*
G01Y392450D01*
G03X1566746Y385222I15803J0D01*
G01Y373202D01*
G03X1571287Y362240I15502J0D01*
G01X1574677Y358850D01*
X1574691Y358822D01*
G03X1581785Y351728I14516J7422D01*
G01X1581813Y351714D01*
X1583904Y349623D01*
Y319911D01*
X1577510Y313517D01*
X1567636D01*
X1567596Y313535D01*
G03X1510670Y291393I-17695J-38754D01*
G01X1510655Y291357D01*
X1509770Y290472D01*
G37*
G36*
G01X1477340Y534998D02*
Y559750D01*
G03X1475756Y566539I-15341J0D01*
G01Y630959D01*
X1462714Y644001D01*
X1456263D01*
X1454756Y645508D01*
Y648507D01*
X1455709Y649460D01*
X1504987D01*
X1508711Y645736D01*
Y630908D01*
X1503384Y625581D01*
X1503315Y625573D01*
G03X1492021Y598952I1866J-16498D01*
G01X1492062Y598898D01*
Y597272D01*
X1490096Y595306D01*
X1484094D01*
Y556294D01*
X1484095D01*
X1485460Y554929D01*
Y524077D01*
X1477571Y516188D01*
X1474614D01*
X1473506Y517296D01*
Y523670D01*
X1473546Y523723D01*
G03X1476275Y529383I-13046J9778D01*
G03X1477340Y534998I-14275J5616D01*
G37*
G36*
G01X1441500Y561000D02*
X1439500Y563000D01*
Y576500D01*
X1440500Y577500D01*
X1453500D01*
X1454500Y576500D01*
Y568500D01*
X1455000Y568000D01*
X1456500D01*
X1456910Y567590D01*
Y567496D01*
G03X1456898Y567300I1590J-196D01*
G01Y565700D01*
G03X1456909Y565515I1602J2D01*
G01X1456910Y565504D01*
Y563396D01*
X1456909Y563385D01*
G03X1456898Y563200I1591J-187D01*
G01Y561800D01*
G03X1456920Y561538I1602J3D01*
G01X1456937Y561437D01*
X1456500Y561000D01*
X1441500D01*
G37*
G36*
G01X1450000Y537000D02*
X1449000Y538000D01*
Y556500D01*
X1450000Y557500D01*
X1459000D01*
X1459660Y556840D01*
Y537660D01*
X1459000Y537000D01*
X1450000D01*
G37*
G36*
G01X1441500Y1013500D02*
X1439500Y1015500D01*
Y1029000D01*
X1440500Y1030000D01*
X1453500D01*
X1454500Y1029000D01*
Y1021000D01*
X1455000Y1020500D01*
X1456500D01*
X1456910Y1020090D01*
Y1019996D01*
G03X1456898Y1019800I1590J-196D01*
G01Y1018200D01*
G03X1456909Y1018015I1602J2D01*
G01X1456910Y1018004D01*
Y1015896D01*
X1456909Y1015885D01*
G03X1456898Y1015700I1591J-187D01*
G01Y1014300D01*
G03X1456920Y1014038I1602J3D01*
G01X1456937Y1013937D01*
X1456500Y1013500D01*
X1441500D01*
G37*
G36*
G01X1450000Y989500D02*
X1449000Y990500D01*
Y1009000D01*
X1450000Y1010000D01*
X1459000D01*
X1459660Y1009340D01*
Y990160D01*
X1459000Y989500D01*
X1450000D01*
G37*
G36*
G01X1567000Y76000D02*
X1566000Y75000D01*
X1553059D01*
X1552419Y75640D01*
X1547669D01*
X1547340Y75969D01*
Y85839D01*
X1547500Y86000D01*
X1566000D01*
X1567000Y85000D01*
Y76000D01*
G37*
G36*
G01X1558875Y156244D02*
X1550876D01*
X1542876Y164244D01*
X1531875D01*
X1530875Y165244D01*
Y167344D01*
X1531775Y168244D01*
X1555375D01*
X1559375Y164244D01*
Y156744D01*
X1558875Y156244D01*
G37*
G36*
G01X1550000Y122000D02*
X1545500D01*
X1544500Y123000D01*
Y133000D01*
X1543000Y134500D01*
X1533000D01*
X1532000Y135500D01*
Y137000D01*
X1533000Y138000D01*
X1546000D01*
X1551000Y133000D01*
Y123000D01*
X1550000Y122000D01*
G37*
G36*
G01X1592967Y159256D02*
X1592101Y160122D01*
Y177814D01*
X1579256Y190659D01*
Y198556D01*
X1570926D01*
G03X1570491Y198859I-9420J-13060D01*
G01X1570475Y198870D01*
X1563049Y206296D01*
Y208668D01*
X1566200Y211819D01*
X1566237Y211834D01*
G03X1590394Y237940I-16336J39347D01*
G01X1594710D01*
Y237899D01*
X1595128D01*
X1595645Y237382D01*
G03X1606606Y232842I10961J10962D01*
G01X1613508D01*
G03X1618324Y233609I0J15502D01*
G01X1618354Y233619D01*
X1627276D01*
G03X1634200Y224772I46642J29371D01*
G01Y179800D01*
X1636328D01*
X1639744Y176384D01*
Y174775D01*
X1637922Y172953D01*
X1633516D01*
X1631440Y175029D01*
Y198895D01*
G03X1600760I-15340J4891D01*
G01Y161782D01*
X1598234Y159256D01*
X1592967D01*
G37*
G36*
G01X1575400Y121400D02*
X1565800D01*
X1565000Y122200D01*
Y153000D01*
X1562950Y155050D01*
Y164550D01*
X1558000Y169500D01*
X1533000D01*
X1532000Y170500D01*
Y177000D01*
X1533000Y178000D01*
X1548500D01*
X1550500Y176000D01*
X1572700D01*
X1577100Y171600D01*
Y123100D01*
X1575400Y121400D01*
G37*
G36*
G01X1565000Y97500D02*
X1552500D01*
X1551500Y98500D01*
Y120500D01*
X1553000Y122000D01*
Y133000D01*
X1546500Y139500D01*
X1533000D01*
X1532000Y140500D01*
Y147000D01*
X1533000Y148000D01*
X1551000D01*
X1553500Y145500D01*
X1560500D01*
X1562500Y143500D01*
Y109500D01*
X1566000Y106000D01*
Y98500D01*
X1565000Y97500D01*
G37*
G36*
G01X1597591Y138000D02*
X1602298Y133293D01*
Y132200D01*
G03X1602309Y132015I1602J2D01*
G01X1602310Y132004D01*
Y129896D01*
X1602309Y129885D01*
G03X1602298Y129700I1591J-187D01*
G01Y128300D01*
G03X1602389Y127770I1602J2D01*
G01X1602400Y127738D01*
Y125000D01*
X1600400Y123000D01*
X1586900D01*
X1585900Y124000D01*
Y137000D01*
X1586900Y138000D01*
X1597591D01*
G37*
G36*
G01X1711369Y303434D02*
X1711312Y303487D01*
G03X1660241Y316388I-37394J-40495D01*
G03X1641843Y307818I13677J-53395D01*
G01X1641791Y307781D01*
X1634983D01*
X1632706Y310058D01*
Y410006D01*
X1629169D01*
X1620538Y418637D01*
Y419309D01*
X1612241D01*
X1601361Y430189D01*
Y434466D01*
X1602530Y435635D01*
X1620113D01*
X1659574Y396174D01*
X1713749D01*
X1718294Y391629D01*
Y304925D01*
X1716803Y303434D01*
X1711369D01*
G37*
G36*
G01X1601840Y534998D02*
Y559750D01*
G03X1600256Y566539I-15341J0D01*
G01Y630959D01*
X1587214Y644001D01*
X1580048D01*
X1579256Y644793D01*
Y648059D01*
X1580657Y649460D01*
X1632758D01*
X1633664Y648554D01*
Y637242D01*
X1608794Y612372D01*
Y517726D01*
X1594610Y503542D01*
X1592677D01*
X1591597Y504622D01*
Y507313D01*
X1594278Y509994D01*
X1598006D01*
Y523670D01*
G03X1600775Y529383I-13005J9831D01*
G03X1601840Y534998I-14275J5616D01*
G37*
G36*
G01X1561500Y542500D02*
X1554000D01*
X1553000Y543500D01*
Y586000D01*
X1546500Y592500D01*
X1533000D01*
X1532000Y593500D01*
Y600000D01*
X1533000Y601000D01*
X1551000D01*
X1553500Y598500D01*
X1560500D01*
X1562500Y596500D01*
Y543500D01*
X1561500Y542500D01*
G37*
G36*
G01X1566000Y561000D02*
X1564000Y563000D01*
Y576500D01*
X1565000Y577500D01*
X1578000D01*
X1579000Y576500D01*
Y568500D01*
X1579500Y568000D01*
X1581000D01*
X1581410Y567590D01*
Y567496D01*
G03X1581398Y567300I1590J-196D01*
G01Y565700D01*
G03X1581409Y565515I1602J2D01*
G01X1581410Y565504D01*
Y563396D01*
X1581409Y563385D01*
G03X1581398Y563200I1591J-187D01*
G01Y561800D01*
G03X1581420Y561538I1602J3D01*
G01X1581437Y561437D01*
X1581000Y561000D01*
X1566000D01*
G37*
G36*
G01X1574500Y537000D02*
X1573500Y538000D01*
Y556500D01*
X1574500Y557500D01*
X1583500D01*
X1584160Y556840D01*
Y537660D01*
X1583500Y537000D01*
X1574500D01*
G37*
G36*
G01X1558887Y609000D02*
X1551687D01*
X1544087Y616600D01*
X1532287D01*
X1531287Y617600D01*
Y620400D01*
X1531837Y620950D01*
X1540837D01*
X1540887Y621000D01*
X1555387D01*
X1559387Y617000D01*
Y609500D01*
X1558887Y609000D01*
G37*
G36*
G01X1550000Y575000D02*
X1545500D01*
X1544500Y576000D01*
Y586000D01*
X1543000Y587500D01*
X1533000D01*
X1532000Y588500D01*
Y590000D01*
X1533000Y591000D01*
X1546000D01*
X1551000Y586000D01*
Y576000D01*
X1550000Y575000D01*
G37*
G36*
G01X1583500Y589000D02*
X1566000D01*
X1565000Y590000D01*
Y606000D01*
X1562950Y608050D01*
Y617950D01*
X1558400Y622500D01*
X1533000D01*
X1532000Y623500D01*
Y630000D01*
X1533000Y631000D01*
X1548500D01*
X1550500Y629000D01*
X1581000D01*
X1584500Y625500D01*
Y590000D01*
X1583500Y589000D01*
G37*
G36*
G01X1578353Y938561D02*
X1576981Y939933D01*
Y940907D01*
X1577268Y941194D01*
X1586606D01*
Y947230D01*
G03X1588668Y950606I-12607J10018D01*
G01X1588683Y950639D01*
X1598006Y959962D01*
Y974971D01*
G03X1601871Y982271I-12006J11030D01*
G02X1602660Y982179I389J-92D01*
G01Y941689D01*
X1600940Y939969D01*
X1600909Y939954D01*
G03X1598515Y938561I6972J-14737D01*
G01X1578353D01*
G37*
G36*
G01X1550000Y1027500D02*
X1545500D01*
X1544500Y1028500D01*
Y1038500D01*
X1543000Y1040000D01*
X1533000D01*
X1532000Y1041000D01*
Y1042500D01*
X1533000Y1043500D01*
X1546000D01*
X1551000Y1038500D01*
Y1028500D01*
X1550000Y1027500D01*
G37*
G36*
G01X1583500Y1041500D02*
X1566000D01*
X1565000Y1042500D01*
Y1058500D01*
X1563000Y1060500D01*
Y1070100D01*
X1558100Y1075000D01*
X1533000D01*
X1532000Y1076000D01*
Y1082500D01*
X1533000Y1083500D01*
X1548500D01*
X1550500Y1081500D01*
X1581000D01*
X1584500Y1078000D01*
Y1042500D01*
X1583500Y1041500D01*
G37*
G36*
G01X1561500Y995000D02*
X1554000D01*
X1553000Y996000D01*
Y1038500D01*
X1546500Y1045000D01*
X1533000D01*
X1532000Y1046000D01*
Y1052500D01*
X1533000Y1053500D01*
X1551000D01*
X1553500Y1051000D01*
X1560500D01*
X1562500Y1049000D01*
Y996000D01*
X1561500Y995000D01*
G37*
G36*
G01X1581000Y1013500D02*
X1566000D01*
X1564000Y1015500D01*
Y1029000D01*
X1565000Y1030000D01*
X1578000D01*
X1579000Y1029000D01*
Y1021000D01*
X1579500Y1020500D01*
X1581000D01*
X1581398Y1020102D01*
Y1013898D01*
X1581000Y1013500D01*
G37*
G36*
G01X1574500Y989500D02*
X1573500Y990500D01*
Y1009000D01*
X1574500Y1010000D01*
X1583500D01*
X1584160Y1009340D01*
Y990160D01*
X1583500Y989500D01*
X1574500D01*
G37*
G36*
G01X1558887Y1061756D02*
X1551687D01*
X1544087Y1069356D01*
X1532287D01*
X1531287Y1070356D01*
Y1073156D01*
X1531837Y1073706D01*
X1540837D01*
X1540887Y1073756D01*
X1555387D01*
X1559387Y1069756D01*
Y1062256D01*
X1558887Y1061756D01*
G37*
G36*
G01X1685500Y89500D02*
X1678000D01*
X1677000Y90500D01*
Y133000D01*
X1670500Y139500D01*
X1657000D01*
X1656000Y140500D01*
Y147000D01*
X1657000Y148000D01*
X1675000D01*
X1677500Y145500D01*
X1684500D01*
X1686500Y143500D01*
Y90500D01*
X1685500Y89500D01*
G37*
G36*
G01X1692500Y84000D02*
X1690400Y86100D01*
Y102600D01*
X1692300Y104500D01*
X1707500D01*
X1708160Y103840D01*
Y84661D01*
X1707500Y84000D01*
X1692500D01*
G37*
G36*
G01X1674188Y156244D02*
X1667368Y163064D01*
Y163720D01*
X1666712D01*
X1666188Y164244D01*
X1656088D01*
X1655088Y165244D01*
Y167344D01*
X1655988Y168244D01*
X1679588D01*
X1683588Y164244D01*
Y156744D01*
X1683088Y156244D01*
X1674188D01*
G37*
G36*
G01X1674000Y122000D02*
X1669500D01*
X1668500Y123000D01*
Y133000D01*
X1667000Y134500D01*
X1657000D01*
X1656000Y135500D01*
Y137000D01*
X1657000Y138000D01*
X1670000D01*
X1675000Y133000D01*
Y123000D01*
X1674000Y122000D01*
G37*
G36*
G01X1707500Y136000D02*
X1690000D01*
X1689000Y137000D01*
Y153000D01*
X1686900Y155100D01*
Y164000D01*
X1681400Y169500D01*
X1657000D01*
X1656000Y170500D01*
Y177000D01*
X1657000Y178000D01*
X1672500D01*
X1674500Y176000D01*
X1705000D01*
X1708500Y172500D01*
Y137000D01*
X1707500Y136000D01*
G37*
G36*
G01X1690000Y108000D02*
X1688000Y110000D01*
Y123500D01*
X1689000Y124500D01*
X1702000D01*
X1703000Y123500D01*
Y115500D01*
X1703500Y115000D01*
X1705000D01*
X1705410Y114590D01*
Y114496D01*
G03X1705398Y114300I1590J-196D01*
G01Y112700D01*
G03X1705409Y112515I1602J2D01*
G01X1705410Y112504D01*
Y110396D01*
X1705409Y110385D01*
G03X1705398Y110200I1591J-187D01*
G01Y108800D01*
G03X1705420Y108538I1602J3D01*
G01X1705437Y108437D01*
X1705000Y108000D01*
X1690000D01*
G37*
G36*
G01X1720431Y435107D02*
X1718431Y437107D01*
Y457135D01*
X1721564Y460268D01*
X1731253D01*
X1731996Y459525D01*
Y442008D01*
X1731938D01*
Y435750D01*
X1731296Y435107D01*
X1720431D01*
G37*
G36*
G01X1724359Y477107D02*
X1726059Y475407D01*
Y473767D01*
X1726508Y473318D01*
Y473317D01*
X1727887Y471939D01*
Y470177D01*
X1727574Y469864D01*
X1716302D01*
X1714257Y471909D01*
Y474207D01*
G03X1714260Y474307I-1598J98D01*
G01Y475707D01*
G03X1714257Y475807I-1601J2D01*
G01Y476305D01*
X1715059Y477107D01*
X1724359D01*
G37*
G36*
G01X1707836Y436730D02*
X1703680Y440886D01*
Y450021D01*
X1704472Y450813D01*
X1710379D01*
X1710410Y450803D01*
G03X1711988I789J2374D01*
G01X1712019Y450813D01*
X1715019D01*
X1715448Y450384D01*
Y437140D01*
X1715038Y436730D01*
X1707836D01*
G37*
G36*
G01X1685500Y542500D02*
X1678000D01*
X1677000Y543500D01*
Y586000D01*
X1670500Y592500D01*
X1657000D01*
X1656000Y593500D01*
Y600000D01*
X1657000Y601000D01*
X1675000D01*
X1677500Y598500D01*
X1684500D01*
X1686500Y596500D01*
Y543500D01*
X1685500Y542500D01*
G37*
G36*
G01X1690000Y561000D02*
X1688000Y563000D01*
Y576500D01*
X1689000Y577500D01*
X1702000D01*
X1703000Y576500D01*
Y568500D01*
X1703500Y568000D01*
X1705000D01*
X1705410Y567590D01*
Y567496D01*
G03X1705398Y567300I1590J-196D01*
G01Y565700D01*
G03X1705409Y565515I1602J2D01*
G01X1705410Y565504D01*
Y563396D01*
X1705409Y563385D01*
G03X1705398Y563200I1591J-187D01*
G01Y561800D01*
G03X1705420Y561538I1602J3D01*
G01X1705437Y561437D01*
X1705000Y561000D01*
X1690000D01*
G37*
G36*
G01X1698500Y537000D02*
X1697500Y538000D01*
Y556500D01*
X1698500Y557500D01*
X1707500D01*
X1708160Y556840D01*
Y537660D01*
X1707500Y537000D01*
X1698500D01*
G37*
G36*
G01X1683100Y609000D02*
X1675900D01*
X1668300Y616600D01*
X1656500D01*
X1655500Y617600D01*
Y620400D01*
X1656050Y620950D01*
X1665050D01*
X1665100Y621000D01*
X1679600D01*
X1683600Y617000D01*
Y609500D01*
X1683100Y609000D01*
G37*
G36*
G01X1674000Y575000D02*
X1669500D01*
X1668500Y576000D01*
Y586000D01*
X1667000Y587500D01*
X1657000D01*
X1656000Y588500D01*
Y590000D01*
X1657000Y591000D01*
X1670000D01*
X1675000Y586000D01*
Y576000D01*
X1674000Y575000D01*
G37*
G36*
G01X1724256Y630959D02*
X1711214Y644001D01*
X1704770D01*
X1703256Y645515D01*
Y648201D01*
X1704515Y649460D01*
X1756418D01*
X1758440Y647438D01*
Y632594D01*
X1761105D01*
X1763510Y630189D01*
Y627245D01*
X1762154Y625889D01*
X1745928D01*
X1733184Y613145D01*
Y551157D01*
X1730919Y548892D01*
X1726970D01*
X1725840Y550022D01*
Y559750D01*
G03X1724256Y566539I-15341J0D01*
G01Y630959D01*
G37*
G36*
G01X1707500Y589000D02*
X1690000D01*
X1689000Y590000D01*
Y605600D01*
X1686950Y607650D01*
Y618650D01*
X1683100Y622500D01*
X1657000D01*
X1656000Y623500D01*
Y630000D01*
X1657000Y631000D01*
X1672500D01*
X1674500Y629000D01*
X1705000D01*
X1708500Y625500D01*
Y590000D01*
X1707500Y589000D01*
G37*
G36*
G01X1708116Y704581D02*
G03X1712657Y693619I15502J0D01*
G01X1716138Y690138D01*
G03X1727099Y685598I10961J10962D01*
G01X1737720D01*
G03X1743136Y686575I0J15502D01*
G01X1759028D01*
G03X1761173Y682404I38902J17369D01*
G01X1761200Y682357D01*
Y681406D01*
X1759934Y680140D01*
X1687540D01*
Y813043D01*
X1690114Y815617D01*
X1694878D01*
X1708116Y802379D01*
Y782646D01*
G03Y772554I15503J-5046D01*
G01Y704581D01*
G37*
G36*
G01X1715106Y961306D02*
X1716294Y962494D01*
X1719112D01*
X1720160Y961446D01*
Y938112D01*
X1718584Y936536D01*
X1688759D01*
X1688158Y937137D01*
X1688123D01*
Y937846D01*
X1688739Y938462D01*
X1688790Y938476D01*
G03X1694215Y941154I-4290J15525D01*
G01X1694268Y941194D01*
X1696771D01*
X1696779Y941193D01*
G03X1699221I1221J16057D01*
G01X1699229Y941194D01*
X1710606D01*
Y946421D01*
X1715106Y950921D01*
Y961306D01*
G37*
G36*
G01X1674000Y1027500D02*
X1669500D01*
X1668500Y1028500D01*
Y1038500D01*
X1667000Y1040000D01*
X1657000D01*
X1656000Y1041000D01*
Y1042500D01*
X1657000Y1043500D01*
X1670000D01*
X1675000Y1038500D01*
Y1028500D01*
X1674000Y1027500D01*
G37*
G36*
G01X1707500Y1041500D02*
X1690000D01*
X1689000Y1042500D01*
Y1058500D01*
X1687450Y1060050D01*
Y1070050D01*
X1682500Y1075000D01*
X1657000D01*
X1656000Y1076000D01*
Y1082500D01*
X1657000Y1083500D01*
X1672500D01*
X1674500Y1081500D01*
X1705000D01*
X1708500Y1078000D01*
Y1042500D01*
X1707500Y1041500D01*
G37*
G36*
G01X1685500Y995000D02*
X1678000D01*
X1677000Y996000D01*
Y1038500D01*
X1670500Y1045000D01*
X1657000D01*
X1656000Y1046000D01*
Y1052500D01*
X1657000Y1053500D01*
X1675000D01*
X1677500Y1051000D01*
X1684500D01*
X1686500Y1049000D01*
Y996000D01*
X1685500Y995000D01*
G37*
G36*
G01X1705000Y1013500D02*
X1690000D01*
X1688000Y1015500D01*
Y1029000D01*
X1689000Y1030000D01*
X1702000D01*
X1703000Y1029000D01*
Y1021000D01*
X1703500Y1020500D01*
X1705000D01*
X1705398Y1020102D01*
Y1013898D01*
X1705000Y1013500D01*
G37*
G36*
G01X1698500Y989500D02*
X1697500Y990500D01*
Y1009000D01*
X1698500Y1010000D01*
X1707500D01*
X1708160Y1009340D01*
Y990160D01*
X1707500Y989500D01*
X1698500D01*
G37*
G36*
G01X1683100Y1061756D02*
X1675900D01*
X1668300Y1069356D01*
X1656500D01*
X1655500Y1070356D01*
Y1073156D01*
X1656050Y1073706D01*
X1665050D01*
X1665100Y1073756D01*
X1679600D01*
X1683600Y1069756D01*
Y1062256D01*
X1683100Y1061756D01*
G37*
G36*
G01X1738528Y1416012D02*
X1737159Y1417381D01*
X1737145Y1417406D01*
G03X1735299Y1418595I-2019J-1106D01*
G01X1735225Y1418601D01*
X1729726Y1424100D01*
X1721126D01*
X1718226Y1427000D01*
Y1435000D01*
X1721226Y1438000D01*
X1734226D01*
X1736626Y1440400D01*
Y1475000D01*
X1739626Y1478000D01*
X1749742D01*
X1752126Y1475616D01*
Y1439608D01*
X1751512Y1438994D01*
Y1411886D01*
X1749626Y1410000D01*
X1739626D01*
X1739126Y1410500D01*
Y1414800D01*
X1739026Y1414900D01*
X1738926D01*
X1738778Y1415048D01*
Y1415052D01*
X1738774D01*
X1738528Y1415298D01*
Y1416012D01*
G37*
G36*
G01X1702726Y1408800D02*
X1694026D01*
X1693126Y1409700D01*
Y1422300D01*
X1694926Y1424100D01*
X1699830D01*
X1706033Y1417897D01*
X1708629D01*
X1709026Y1417500D01*
Y1411888D01*
X1708591Y1411453D01*
X1705379D01*
X1702726Y1408800D01*
G37*
G36*
G01X1811848Y22848D02*
X1809040Y20040D01*
X1804869D01*
X1804800Y20108D01*
Y23406D01*
G03X1804362Y24769I-2340J0D01*
G01Y27608D01*
X1804300D01*
Y28400D01*
X1809060Y33160D01*
X1809069D01*
X1810009Y34100D01*
X1812900D01*
X1813300Y33700D01*
Y27370D01*
G03X1811848Y24800I1550J-2571D01*
G01Y22848D01*
G37*
G36*
G01X1794340Y94640D02*
X1794800Y95100D01*
X1813300D01*
X1814300Y94100D01*
Y85100D01*
X1813300Y84100D01*
X1804800D01*
G03X1802200I-1300J-1900D01*
G01X1800107D01*
G03X1798081I-1013J-2067D01*
G01X1794800D01*
X1794340Y84560D01*
Y94640D01*
G37*
G36*
G01X1798400Y156244D02*
X1791580Y163064D01*
Y163720D01*
X1790924D01*
X1790400Y164244D01*
X1780300D01*
X1779300Y165244D01*
Y167344D01*
X1780200Y168244D01*
X1803800D01*
X1807800Y164244D01*
Y156744D01*
X1807300Y156244D01*
X1798400D01*
G37*
G36*
G01X1798000Y122000D02*
X1793500D01*
X1792500Y123000D01*
Y133000D01*
X1791000Y134500D01*
X1781000D01*
X1780000Y135500D01*
Y137000D01*
X1781000Y138000D01*
X1794000D01*
X1799000Y133000D01*
Y123000D01*
X1798000Y122000D01*
G37*
G36*
G01X1814000Y135500D02*
X1813000Y136500D01*
Y146436D01*
G03Y149552I-1695J1558D01*
G01Y153000D01*
X1811300Y154700D01*
Y163400D01*
X1805200Y169500D01*
X1781000D01*
X1780000Y170500D01*
Y177000D01*
X1781000Y178000D01*
X1796500D01*
X1798500Y176000D01*
X1820500D01*
X1832478Y164022D01*
Y136478D01*
X1831500Y135500D01*
X1814000D01*
G37*
G36*
G01X1800500Y97500D02*
X1798500Y99500D01*
Y106648D01*
X1798752D01*
Y115552D01*
X1798500D01*
Y120500D01*
X1799548Y121548D01*
X1799702D01*
Y121702D01*
X1801000Y123000D01*
Y133000D01*
X1794500Y139500D01*
X1781000D01*
X1780000Y140500D01*
Y147000D01*
X1781000Y148000D01*
X1799000D01*
X1801500Y145500D01*
X1808500D01*
X1810500Y143500D01*
Y117200D01*
X1812048Y115652D01*
Y115548D01*
X1812152D01*
X1815000Y112700D01*
Y98500D01*
X1814000Y97500D01*
X1800500D01*
G37*
G36*
G01X1816202Y113198D02*
X1812000Y117399D01*
Y123500D01*
X1813000Y124500D01*
X1825500D01*
X1826500Y123500D01*
Y115500D01*
X1827000Y115000D01*
X1828410D01*
Y114496D01*
X1828409Y114485D01*
G03X1828398Y114300I1591J-187D01*
G01Y112700D01*
G03X1828409Y112515I1602J2D01*
G01X1828410Y112504D01*
Y110396D01*
X1828409Y110385D01*
G03X1828398Y110200I1591J-187D01*
G01Y108800D01*
G03X1828409Y108615I1602J2D01*
G01X1828410Y108604D01*
Y108000D01*
X1817000D01*
X1816202Y108798D01*
Y113198D01*
G37*
G36*
G01X1832198Y316079D02*
Y309276D01*
X1829704Y306782D01*
X1826056D01*
X1826000Y306832D01*
G03X1770504Y307379I-28067J-32052D01*
G01X1770448Y307332D01*
X1766708D01*
X1763748Y310292D01*
Y352925D01*
X1771185Y360361D01*
X1771213Y360375D01*
G03X1777781Y366521I-7423J14515D01*
G01X1777794Y366542D01*
X1778979Y367727D01*
X1782199D01*
X1783333Y366593D01*
X1783348Y366557D01*
G03X1786680Y361596I14294J6001D01*
G01X1790070Y358206D01*
G03X1797178Y351084I14530J7394D01*
G01X1797206Y351070D01*
X1832198Y316079D01*
G37*
G36*
G01X1809500Y542500D02*
X1802000D01*
X1801000Y543500D01*
Y586000D01*
X1794500Y592500D01*
X1781000D01*
X1780000Y593500D01*
Y600000D01*
X1781000Y601000D01*
X1799000D01*
X1801500Y598500D01*
X1808500D01*
X1810500Y596500D01*
Y543500D01*
X1809500Y542500D01*
G37*
G36*
G01X1829000Y561000D02*
X1814000D01*
X1812000Y563000D01*
Y576500D01*
X1813000Y577500D01*
X1826000D01*
X1827000Y576500D01*
Y568500D01*
X1827500Y568000D01*
X1829000D01*
X1829392Y567608D01*
Y561392D01*
X1829000Y561000D01*
G37*
G36*
G01X1798400Y609000D02*
X1791580Y615820D01*
Y616476D01*
X1790923D01*
X1790400Y617000D01*
X1780300D01*
X1779300Y618000D01*
Y620100D01*
X1780200Y621000D01*
X1803800D01*
X1807800Y617000D01*
Y609500D01*
X1807300Y609000D01*
X1798400D01*
G37*
G36*
G01X1798000Y575000D02*
X1793500D01*
X1792500Y576000D01*
Y586000D01*
X1791000Y587500D01*
X1781000D01*
X1780000Y588500D01*
Y590000D01*
X1781000Y591000D01*
X1794000D01*
X1799000Y586000D01*
Y576000D01*
X1798000Y575000D01*
G37*
G36*
G01X1831500Y589000D02*
X1814000D01*
X1813000Y590000D01*
Y604900D01*
X1810850Y607050D01*
Y615850D01*
X1804200Y622500D01*
X1781000D01*
X1780000Y623500D01*
Y630000D01*
X1781000Y631000D01*
X1796500D01*
X1798500Y629000D01*
X1829000D01*
X1832500Y625500D01*
Y590000D01*
X1831500Y589000D01*
G37*
G36*
G01X1757389Y744996D02*
X1755070Y747315D01*
Y819229D01*
X1756706Y820865D01*
Y849418D01*
X1759082Y851794D01*
X1809327D01*
X1811874Y849247D01*
Y785206D01*
X1796792Y770124D01*
X1796713Y770122D01*
G03X1759125Y745113I1220J-42585D01*
G01X1759072Y744996D01*
X1757389D01*
G37*
G36*
G01X1794835Y869425D02*
X1792835Y871425D01*
Y891453D01*
X1795968Y894586D01*
X1805657D01*
X1806400Y893843D01*
Y876326D01*
X1806342D01*
Y870068D01*
X1805700Y869425D01*
X1794835D01*
G37*
G36*
G01X1798763Y911425D02*
X1800463Y909725D01*
Y908078D01*
X1802296Y906245D01*
Y906151D01*
G03X1802294Y906067I1599J-80D01*
G01Y904667D01*
G03X1802296Y904583I1601J-4D01*
G01Y904461D01*
X1802018Y904183D01*
X1790705D01*
X1788660Y906228D01*
Y908512D01*
G03X1788664Y908625I-1597J113D01*
G01Y910025D01*
G03X1788660Y910138I-1601J0D01*
G01Y910622D01*
X1789463Y911425D01*
X1798763D01*
G37*
G36*
G01X1782240Y871048D02*
X1778084Y875204D01*
Y884339D01*
X1778876Y885131D01*
X1784783D01*
X1784814Y885121D01*
G03X1786392I789J2374D01*
G01X1786423Y885131D01*
X1789423D01*
X1789852Y884702D01*
Y871458D01*
X1789442Y871048D01*
X1782240D01*
G37*
G36*
G01X1798000Y1027500D02*
X1793500D01*
X1792500Y1028500D01*
Y1038500D01*
X1791000Y1040000D01*
X1781000D01*
X1780000Y1041000D01*
Y1042500D01*
X1781000Y1043500D01*
X1794000D01*
X1799000Y1038500D01*
Y1028500D01*
X1798000Y1027500D01*
G37*
G36*
G01X1831500Y1041500D02*
X1814000D01*
X1813000Y1042500D01*
Y1058500D01*
X1811250Y1060250D01*
Y1070650D01*
X1806900Y1075000D01*
X1781000D01*
X1780000Y1076000D01*
Y1082500D01*
X1781000Y1083500D01*
X1796500D01*
X1798500Y1081500D01*
X1829000D01*
X1832500Y1078000D01*
Y1042500D01*
X1831500Y1041500D01*
G37*
G36*
G01X1809500Y995000D02*
X1802000D01*
X1801000Y996000D01*
Y1038500D01*
X1794500Y1045000D01*
X1781000D01*
X1780000Y1046000D01*
Y1052500D01*
X1781000Y1053500D01*
X1799000D01*
X1801500Y1051000D01*
X1808500D01*
X1810500Y1049000D01*
Y996000D01*
X1809500Y995000D01*
G37*
G36*
G01X1829000Y1013500D02*
X1814000D01*
X1812000Y1015500D01*
Y1029000D01*
X1813000Y1030000D01*
X1826000D01*
X1827000Y1029000D01*
Y1021000D01*
X1827500Y1020500D01*
X1829000D01*
X1829394Y1020106D01*
Y1013894D01*
X1829000Y1013500D01*
G37*
G36*
G01X1807312Y1061756D02*
X1800112D01*
X1792512Y1069356D01*
X1780712D01*
X1779712Y1070356D01*
Y1073156D01*
X1780262Y1073706D01*
X1789262D01*
X1789312Y1073756D01*
X1803812D01*
X1807812Y1069756D01*
Y1062256D01*
X1807312Y1061756D01*
G37*
G36*
G01X1765553Y1412712D02*
X1756010D01*
X1755526Y1413196D01*
Y1426500D01*
X1753342Y1428684D01*
Y1435116D01*
X1753726Y1435500D01*
X1766926D01*
X1768426Y1434000D01*
Y1415585D01*
X1765553Y1412712D01*
G37*
G36*
G01X1852600Y76000D02*
X1838900D01*
X1838000Y76900D01*
Y88500D01*
X1839000Y89500D01*
X1852000D01*
X1853000Y88500D01*
Y76400D01*
X1852600Y76000D01*
G37*
G36*
G01X1864000Y85500D02*
X1863340Y86161D01*
Y95839D01*
X1864000Y96500D01*
X1882500D01*
X1882660Y96340D01*
Y87344D01*
X1881997Y86680D01*
X1878772D01*
X1877591Y85500D01*
X1864000D01*
G37*
G36*
G01X1876706Y152400D02*
X1875800Y151494D01*
Y151202D01*
X1875767Y151151D01*
G03X1875800Y148000I2333J-1551D01*
G01Y138300D01*
X1874000Y136500D01*
X1869000D01*
X1868500Y137000D01*
Y151801D01*
X1875285Y158586D01*
X1889586D01*
X1889748Y158748D01*
X1889952D01*
Y158952D01*
X1899000Y168000D01*
X1914500D01*
X1915000Y167500D01*
Y164500D01*
X1914500Y164000D01*
X1901500D01*
X1889900Y152400D01*
X1878202D01*
G03X1877998I-102J-2800D01*
G01X1876706D01*
G37*
G36*
G01X1890020Y121900D02*
X1882120D01*
X1881520Y122500D01*
Y128000D01*
X1883820Y130300D01*
X1888820D01*
X1897020Y138500D01*
X1914520D01*
X1915020Y138000D01*
Y135000D01*
X1914520Y134500D01*
X1902620D01*
X1890020Y121900D01*
G37*
G36*
G01X1857500Y102000D02*
X1839000D01*
X1838000Y103000D01*
Y109000D01*
X1847500Y118500D01*
Y132500D01*
X1850500Y135500D01*
Y147000D01*
X1881000Y177500D01*
X1914500D01*
X1915000Y177000D01*
Y170000D01*
X1914500Y169500D01*
X1891000D01*
X1888500Y167000D01*
X1882000D01*
X1865000Y150000D01*
Y136000D01*
X1858500Y129500D01*
Y103000D01*
X1857500Y102000D01*
G37*
G36*
G01X1869000Y108500D02*
X1868000Y109500D01*
Y118500D01*
X1869000Y119500D01*
Y127500D01*
X1872000Y130500D01*
Y133500D01*
X1873500Y135000D01*
X1875000D01*
X1887500Y147500D01*
X1914500D01*
X1915000Y147000D01*
Y140000D01*
X1914702Y139702D01*
X1896522D01*
X1896321Y139500D01*
X1894500D01*
X1887000Y132000D01*
X1883500D01*
X1880000Y128500D01*
Y118500D01*
X1882500Y116000D01*
Y109500D01*
X1881500Y108500D01*
X1869000D01*
G37*
G36*
G01X1881500Y561500D02*
X1869000D01*
X1868000Y562500D01*
Y571500D01*
X1869000Y572500D01*
Y580500D01*
X1872000Y583500D01*
Y586500D01*
X1873500Y588000D01*
X1875000D01*
X1887500Y600500D01*
X1914500D01*
X1915000Y600000D01*
Y593000D01*
X1914500Y592500D01*
X1894500D01*
X1887000Y585000D01*
X1883500D01*
X1880000Y581500D01*
Y571500D01*
X1882500Y569000D01*
Y562500D01*
X1881500Y561500D01*
G37*
G36*
G01X1847500Y551500D02*
X1843500Y555500D01*
X1841000D01*
X1839500Y557000D01*
Y567000D01*
X1840500Y568000D01*
X1853500D01*
X1854500Y567000D01*
Y558309D01*
X1851691Y555500D01*
X1850500D01*
X1850170Y555170D01*
X1850150Y555158D01*
G03X1849631Y554631I851J-1357D01*
G01X1849397Y554397D01*
Y551897D01*
X1849000Y551500D01*
X1847500D01*
G37*
G36*
G01X1822500Y537000D02*
X1821500Y538000D01*
Y556500D01*
X1822500Y557500D01*
X1831500D01*
X1832160Y556840D01*
Y537660D01*
X1831500Y537000D01*
X1822500D01*
G37*
G36*
G01X1864000Y538500D02*
X1863000Y539500D01*
Y548500D01*
X1864000Y549500D01*
X1882500D01*
X1883160Y548840D01*
Y540293D01*
X1882661Y539794D01*
X1878035D01*
X1876741Y538500D01*
X1864000D01*
G37*
G36*
G01X1869000Y589500D02*
X1868500Y590000D01*
Y604300D01*
X1875700Y611500D01*
X1889500D01*
X1889748Y611748D01*
X1889752D01*
Y611752D01*
X1899000Y621000D01*
X1914500D01*
X1915000Y620500D01*
Y617500D01*
X1914500Y617000D01*
X1901500D01*
X1890300Y605800D01*
X1877900D01*
X1877769Y605669D01*
X1877708Y605658D01*
G03X1876100Y601045I492J-2758D01*
G01Y591600D01*
X1874000Y589500D01*
X1869000D01*
G37*
G36*
G01X1890020Y574656D02*
X1882120D01*
X1881520Y575256D01*
Y580756D01*
X1883820Y583056D01*
X1888820D01*
X1897020Y591256D01*
X1914520D01*
X1915020Y590756D01*
Y587756D01*
X1914520Y587256D01*
X1902620D01*
X1890020Y574656D01*
G37*
G36*
G01X1840000Y579500D02*
X1839000Y580500D01*
Y587000D01*
X1840000Y588000D01*
X1848500D01*
X1850500Y590000D01*
Y600000D01*
X1881000Y630500D01*
X1914500D01*
X1915000Y630000D01*
Y623000D01*
X1914500Y622500D01*
X1891000D01*
X1888500Y620000D01*
X1882000D01*
X1865000Y603000D01*
Y589000D01*
X1863399Y587399D01*
G03X1862811Y586815I1302J-1899D01*
G01X1862800Y586800D01*
X1860500Y584500D01*
Y580500D01*
X1859500Y579500D01*
X1840000D01*
G37*
G36*
G01X1869000Y1042500D02*
X1868500Y1043000D01*
Y1056200D01*
X1877450Y1065150D01*
X1882012D01*
Y1064834D01*
X1889914D01*
Y1065150D01*
X1890150D01*
X1899000Y1074000D01*
X1914500D01*
X1915000Y1073500D01*
Y1070500D01*
X1914500Y1070000D01*
X1901500D01*
X1890200Y1058700D01*
X1879345D01*
G03X1876250Y1054190I-1045J-2600D01*
G01Y1044750D01*
X1874000Y1042500D01*
X1869000D01*
G37*
G36*
G01X1890020Y1027412D02*
X1882120D01*
X1881520Y1028012D01*
Y1033512D01*
X1883820Y1035812D01*
X1888820D01*
X1897020Y1044012D01*
X1914520D01*
X1915020Y1043512D01*
Y1040512D01*
X1914520Y1040012D01*
X1902620D01*
X1890020Y1027412D01*
G37*
G36*
G01X1840000Y1032500D02*
X1839000Y1033500D01*
Y1040000D01*
X1840000Y1041000D01*
X1848500D01*
X1850500Y1043000D01*
Y1053000D01*
X1881000Y1083500D01*
X1914500D01*
X1915000Y1083000D01*
Y1076000D01*
X1914500Y1075500D01*
X1891000D01*
X1888500Y1073000D01*
X1882000D01*
X1865000Y1056000D01*
Y1042000D01*
X1863632Y1040632D01*
G03X1862382Y1039403I867J-2132D01*
G01X1862367Y1039367D01*
X1860500Y1037500D01*
Y1033500D01*
X1859500Y1032500D01*
X1840000D01*
G37*
G36*
G01X1881500Y1014500D02*
X1869000D01*
X1868000Y1015500D01*
Y1024500D01*
X1869000Y1025500D01*
Y1033500D01*
X1872000Y1036500D01*
Y1040299D01*
X1872701Y1041000D01*
X1875000D01*
X1887500Y1053500D01*
X1914500D01*
X1915000Y1053000D01*
Y1046000D01*
X1914500Y1045500D01*
X1894500D01*
X1887000Y1038000D01*
X1883500D01*
X1880000Y1034500D01*
Y1024500D01*
X1882500Y1022000D01*
Y1015500D01*
X1881500Y1014500D01*
G37*
G36*
G01X1847500Y1004500D02*
X1843500Y1008500D01*
X1841000D01*
X1839500Y1010000D01*
Y1020000D01*
X1840500Y1021000D01*
X1853500D01*
X1854500Y1020000D01*
Y1011000D01*
X1852000Y1008500D01*
X1850420D01*
X1849402Y1007482D01*
Y1006900D01*
G03X1849398Y1006800I1597J-114D01*
G01Y1005200D01*
G03X1849402Y1005100I1601J14D01*
G01Y1004902D01*
X1849000Y1004500D01*
X1847500D01*
G37*
G36*
G01X1822500Y989500D02*
X1821500Y990500D01*
Y1009000D01*
X1822500Y1010000D01*
X1831500D01*
X1832160Y1009340D01*
Y990160D01*
X1831500Y989500D01*
X1822500D01*
G37*
G36*
G01X1864000Y991500D02*
X1863000Y992500D01*
Y1001500D01*
X1864000Y1002500D01*
X1882500D01*
X1882660Y1002340D01*
Y992219D01*
X1881941Y991500D01*
X1864000D01*
G37*
%LPC*%
G75*
G36*
G01X143600Y28000D02*
Y27200D01*
X143700Y26800D01*
Y26000D01*
X142900D01*
Y26800D01*
X142800Y27200D01*
Y28000D01*
X143600D01*
G37*
G36*
G01X824048Y1296296D02*
G03Y1295704I269J-296D01*
G02X820952I-1548J-1704D01*
G03Y1296296I-269J296D01*
G02X824048I1548J1704D01*
G37*
G36*
G01X861314Y1285980D02*
Y1284656D01*
X861323Y1284629D01*
G02X856903I-2210J-646D01*
G01X856912Y1284656D01*
Y1285980D01*
X853762D01*
Y1294084D01*
X864464D01*
Y1285980D01*
X861314D01*
G37*
G36*
G01X886258Y1285978D02*
Y1284654D01*
X886266Y1284627D01*
G02X881846I-2210J-646D01*
G01X881854Y1284654D01*
Y1285978D01*
X878704D01*
Y1294082D01*
X889408D01*
Y1285978D01*
X886258D01*
G37*
G36*
G01X873758D02*
Y1284654D01*
X873766Y1284627D01*
G02X869346I-2210J-646D01*
G01X869354Y1284654D01*
Y1285978D01*
X866204D01*
Y1294082D01*
X876908D01*
Y1285978D01*
X873758D01*
G37*
G36*
G01X939794Y1106144D02*
G02X937920Y1106110I-893J-2444D01*
G03X937906Y1106856I-151J370D01*
G02X939780Y1106890I893J2444D01*
G03X939794Y1106144I151J-370D01*
G37*
G36*
G01X1810400Y27600D02*
Y26800D01*
X1810500Y26400D01*
Y25600D01*
X1809700D01*
Y26400D01*
X1809600Y26800D01*
Y27600D01*
X1810400D01*
G37*
G54D122*
X965500Y1128000D03*
G54D121*
X944200Y1083100D03*
G54D120*
X318000Y1058000D03*
X523455Y1416564D03*
X505224Y1424156D03*
X944500Y1134500D03*
X952500D03*
X960500D03*
G54D119*
X217322Y1445275D03*
Y1466929D03*
X597637D03*
Y1445275D03*
X1364566D03*
Y1466929D03*
X1744881Y1445275D03*
Y1466929D03*
G54D118*
X93800Y174500D03*
X97200D03*
X84000Y131300D03*
Y134700D03*
X55500Y101700D03*
X83900Y583800D03*
X55500Y554200D03*
X93800Y627000D03*
X97200D03*
X76463Y906325D03*
X78663D03*
X80600Y906380D03*
X82800D03*
X85095Y906467D03*
X75863Y908225D03*
Y910425D03*
X55500Y1007200D03*
X93800Y1080000D03*
X97200D03*
X83800Y1040100D03*
Y1036700D03*
X143300Y24000D03*
X143200Y31000D03*
X217800Y174500D03*
X221200D03*
X174290Y468589D03*
X176490D03*
X178427Y468644D03*
X180627D03*
X182922Y468731D03*
X173690Y470489D03*
Y472689D03*
X179500Y554200D03*
X217800Y627000D03*
X221200D03*
X218300Y1080000D03*
X221700D03*
X180000Y1007200D03*
X949139Y1385803D03*
X951539D03*
X868837Y1385829D03*
X871037D03*
X1328450Y1407300D03*
X1716676Y1407600D03*
X189424Y1407700D03*
X1328450Y1409500D03*
X1716676Y1409800D03*
X189424Y1409900D03*
X183674Y1421250D03*
X186074D03*
X1322800D03*
X1325200D03*
X1710926D03*
X1713326D03*
X181474Y1421300D03*
X1320600D03*
X1708726D03*
X220874Y1428300D03*
Y1431700D03*
X222155Y1432829D03*
Y1435229D03*
X179274Y1413650D03*
Y1415700D03*
X208300Y131300D03*
Y134700D03*
Y583800D03*
Y587200D03*
X208400Y1036800D03*
X228155Y1432829D03*
X229874Y1431700D03*
Y1428300D03*
X342300Y174500D03*
X345700D03*
X332600Y131300D03*
Y134700D03*
X304000Y101700D03*
X332600Y583800D03*
Y587200D03*
X304000Y554200D03*
X342300Y627000D03*
X345700D03*
X342300Y1080000D03*
X345700D03*
X332400Y1036800D03*
X304000Y1007200D03*
X466300Y174500D03*
X469700D03*
X456600Y131300D03*
Y134700D03*
X456900Y583800D03*
Y587200D03*
X428000Y554200D03*
X466300Y627000D03*
X469700D03*
X466300Y1080000D03*
X469700D03*
X456400Y1036800D03*
X428000Y1007200D03*
X590800Y174500D03*
X594200D03*
X581100Y131300D03*
Y134700D03*
X552500Y101700D03*
X581000Y583800D03*
Y587200D03*
X552500Y554200D03*
X590800Y627000D03*
X594200D03*
X590800Y1080000D03*
X594200D03*
X581000Y1036800D03*
Y1040200D03*
X552500Y1007200D03*
X525411Y1427934D03*
X523011D03*
X530034Y1426229D03*
X526634D03*
X525411Y1433934D03*
X526634Y1435229D03*
X530034D03*
X714800Y174500D03*
X718200D03*
X676500Y554200D03*
X714800Y627000D03*
X718200D03*
X714800Y1080000D03*
X718200D03*
X676500Y1007200D03*
X654695Y1430719D03*
X656895D03*
X649595Y1432419D03*
X652995D03*
X649595Y1433919D03*
X652995D03*
X654695Y1435619D03*
X656895D03*
X705300Y131300D03*
Y134700D03*
Y583800D03*
Y587200D03*
X705200Y1036800D03*
Y1040200D03*
X866500Y888700D03*
X865000Y890300D03*
Y893700D03*
X855358Y1394592D03*
Y1391192D03*
X945000Y888800D03*
Y891200D03*
X946500Y892300D03*
Y895700D03*
X945300Y897400D03*
Y899600D03*
X929200Y874400D03*
Y876600D03*
X927000Y878300D03*
X930400D03*
X922800Y880500D03*
X925200D03*
X927000Y881700D03*
X930400D03*
X895300Y1190500D03*
X889100Y1192800D03*
X895300Y1192900D03*
X949139Y1391803D03*
X951539D03*
X962138Y1418618D03*
X964338D03*
X957038Y1420318D03*
X960438D03*
X957038Y1421818D03*
X960438D03*
X962138Y1423518D03*
X964338D03*
X996238Y518537D03*
X996263Y525357D03*
Y527557D03*
X975447Y532183D03*
X973618Y532417D03*
X975447Y534583D03*
X973618Y535817D03*
X976881Y558471D03*
Y560871D03*
X976841Y562111D03*
X1059018Y1380289D03*
X1061218D03*
X1034234Y1393332D03*
Y1389932D03*
X1052200Y1415300D03*
Y1418700D03*
X1045050Y1482014D03*
Y1478614D03*
X1046350Y1491714D03*
X1037143Y1432899D03*
X1038427Y1434000D03*
X1041827D03*
X1124415Y1316070D03*
X1126815D03*
X1129515Y1317570D03*
X1132915D03*
X1114500Y1329200D03*
X1129515Y1308570D03*
X1132915D03*
X1124415Y1310070D03*
X1126815D03*
X1107500Y1352300D03*
X1116500D03*
Y1355700D03*
X1116300Y1357400D03*
X1207733Y1313944D03*
X1210133D03*
X1211333Y1315444D03*
X1214733D03*
X1174600Y1313900D03*
X1177000D03*
X1178309Y1315653D03*
X1181709D03*
X1211333Y1306444D03*
X1214733D03*
X1207733Y1307944D03*
X1210133D03*
X1178309Y1306653D03*
X1181709D03*
X1174600Y1307900D03*
X1177000D03*
X1206212Y1400714D03*
Y1402914D03*
X1199762Y1404602D03*
X1202162D03*
X1300200Y174000D03*
X1296800D03*
Y144500D03*
X1300200D03*
X1329700Y110600D03*
X1329500Y112300D03*
X1300200Y597500D03*
X1296800D03*
X1330700Y563600D03*
X1330500Y565300D03*
X1300200Y627000D03*
X1296800D03*
Y1079500D03*
X1300200D03*
Y1050000D03*
X1296800D03*
X1330500Y1017800D03*
X1330700Y1016100D03*
X1367874Y1428300D03*
Y1431700D03*
X1369229Y1432845D03*
Y1435245D03*
X1318400Y1413650D03*
Y1415700D03*
X1424200Y144500D03*
X1420800D03*
Y174000D03*
X1424200D03*
Y597500D03*
X1420800D03*
X1424200Y627000D03*
X1420800D03*
X1424200Y1050000D03*
X1420800D03*
X1424200Y1079500D03*
X1420800D03*
X1375229Y1432845D03*
X1376874Y1431700D03*
Y1428300D03*
X1454700Y110600D03*
X1454500Y112300D03*
X1454700Y563600D03*
X1454500Y565300D03*
X1454700Y1016100D03*
X1454500Y1017800D03*
X1548700Y174000D03*
X1545300D03*
X1548700Y144500D03*
X1545300D03*
X1599900Y134200D03*
X1600100Y127900D03*
Y130100D03*
X1599900Y131800D03*
X1548700Y597500D03*
X1545300D03*
X1579200Y563600D03*
X1579000Y565300D03*
X1548700Y627000D03*
X1545300D03*
X1548700Y1079500D03*
X1545300D03*
X1548700Y1050000D03*
X1545300D03*
X1579000Y1017800D03*
X1579200Y1016100D03*
X1672700Y144500D03*
X1669300D03*
X1672700Y174000D03*
X1669300D03*
X1703200Y110600D03*
X1703000Y112300D03*
X1717059Y472007D03*
X1719259D03*
X1721196Y472062D03*
X1723396D03*
X1725691Y472149D03*
X1716459Y473907D03*
Y476107D03*
X1672700Y597500D03*
X1669300D03*
X1703200Y563600D03*
X1703000Y565300D03*
X1669300Y627000D03*
X1672700D03*
Y1079500D03*
X1669300D03*
X1672700Y1050000D03*
X1669300D03*
X1703000Y1017800D03*
X1703200Y1016100D03*
X1748126Y1428300D03*
Y1431700D03*
X1749374Y1432909D03*
Y1435309D03*
X1706526Y1413650D03*
Y1415700D03*
X1810100Y23600D03*
X1810000Y30600D03*
X1793300Y174000D03*
X1796700D03*
X1793300Y144500D03*
X1796700D03*
X1826200Y110600D03*
X1826000Y112300D03*
X1796700Y597500D03*
X1793300D03*
X1827000Y565300D03*
X1827200Y563600D03*
X1793300Y627000D03*
X1796700D03*
X1791463Y906325D03*
X1793663D03*
X1795600Y906380D03*
X1797800D03*
X1800095Y906467D03*
X1790863Y908225D03*
Y910425D03*
X1796700Y1079500D03*
X1793300D03*
X1796700Y1050000D03*
X1793300D03*
X1827000Y1017800D03*
X1827200Y1016100D03*
X1755374Y1432909D03*
X1757126Y1431700D03*
Y1428300D03*
X1885300Y174000D03*
X1888700D03*
X1875900Y130800D03*
Y134200D03*
X1876000Y583800D03*
Y587200D03*
X1847000Y554200D03*
X1885300Y627000D03*
X1888700D03*
X1885300Y1080000D03*
X1888700D03*
X1875700Y1036800D03*
Y1040200D03*
X1847000Y1007200D03*
%LPD*%
G75*
G54D100*
X1104760Y1334815D03*
X1112240D03*
Y1343815D03*
X1108500D03*
X1104760D03*
G54D110*
G01X111206Y878062D02*
Y882768D01*
X113363Y884925D01*
G01X1751802Y443744D02*
Y448450D01*
X1753959Y450607D01*
G54D101*
X1100000Y1493110D03*
Y1483268D03*
G54D111*
G01X930310Y858550D02*
Y858560D01*
X934000Y862250D01*
G54D102*
X1060729Y1493189D03*
Y1483189D03*
G54D112*
G01X83060Y80700D02*
X86700D01*
G01X77940Y73300D02*
X75000D01*
G01X83060Y533200D02*
X86700D01*
G01X77940Y525800D02*
X75000D01*
G01X83060Y986200D02*
X86700D01*
G01X77940Y978800D02*
X75000D01*
G01X118434Y1452450D02*
Y1450240D01*
X121274Y1447400D01*
G01X118574Y1469440D02*
Y1465900D01*
G01X114874Y1476700D02*
Y1476500D01*
X112934Y1474560D01*
X111174D01*
G01X120474Y1482800D02*
Y1485000D01*
X119434Y1486040D01*
X118709D01*
G01X110639Y1491160D02*
X105934D01*
X105774Y1491000D01*
G01X113314Y1458950D02*
X113014Y1458650D01*
X107474D01*
G01X203300Y68060D02*
Y71700D01*
G01X207060Y533200D02*
X210700D01*
G01X201940Y525800D02*
X199000D01*
G01X207560Y986200D02*
X211200D01*
G01X202440Y978800D02*
X199500D01*
G01X326440Y73300D02*
X323500D01*
G01X331560Y80700D02*
X335200D01*
G01X331560Y533200D02*
X335200D01*
G01X326440Y525800D02*
X323500D01*
G01X331560Y986200D02*
X335200D01*
G01X326440Y978800D02*
X323500D01*
G01X450300Y68060D02*
Y71700D01*
G01X455560Y533200D02*
X459200D01*
G01X450440Y525800D02*
X449061D01*
X446993Y527868D01*
G01X455560Y986200D02*
X459200D01*
G01X450440Y978800D02*
X447500D01*
G01X574940Y73300D02*
X572000D01*
G01X574940Y525800D02*
X572000D01*
G01X574940Y978800D02*
X572000D01*
G01X580060Y80700D02*
X583700D01*
G01X580060Y533200D02*
X583700D01*
G01X580060Y986200D02*
X583700D01*
G01X700300Y68060D02*
Y71700D01*
G01X704060Y533200D02*
X707700D01*
G01X698940Y525800D02*
X696000D01*
G01X704060Y986200D02*
X707700D01*
G01X698940Y978800D02*
X696000D01*
G01X743332Y1454674D02*
X744692D01*
X746832Y1452534D01*
Y1451034D01*
G01X739332Y1462234D02*
Y1461234D01*
X737892Y1459794D01*
X735932D01*
G01X746692Y1438184D02*
X750684D01*
X750867Y1438001D01*
G01X744667Y1471974D02*
X745032Y1471609D01*
Y1468534D01*
G01X732232Y1477094D02*
X736597D01*
G01X741572Y1444684D02*
Y1445794D01*
X740282Y1447084D01*
X735232D01*
G01X959913Y519617D02*
X965700D01*
G01X962271Y545731D02*
X966731D01*
X968200Y547200D01*
G01X1024883Y1444649D02*
X1021693D01*
G01X1299800Y53060D02*
Y56000D01*
G01X1307200Y47940D02*
Y45000D01*
G01X1311200Y514440D02*
Y511500D01*
G01X1303800Y519560D02*
Y522500D01*
G01X1311200Y966940D02*
Y964000D01*
G01X1303800Y972060D02*
Y975000D01*
G01X1260874Y1481400D02*
X1258434Y1478960D01*
X1257374D01*
G01X1264774Y1473840D02*
Y1470700D01*
G01X1264734Y1457550D02*
Y1455740D01*
X1266574Y1453900D01*
Y1452300D01*
G01X1266474Y1487500D02*
X1266674Y1487700D01*
Y1489900D01*
X1265734Y1490840D01*
X1265009D01*
G01X1252674Y1496800D02*
X1253514Y1495960D01*
X1256939D01*
G01X1259614Y1464050D02*
Y1465360D01*
X1258324Y1466650D01*
X1253374D01*
G01X1435200Y61440D02*
Y58500D01*
G01X1427800Y66560D02*
Y69500D01*
G01X1435200Y514440D02*
Y511500D01*
G01X1427800Y519560D02*
Y522500D01*
G01X1435200Y966940D02*
Y964000D01*
G01X1427800Y972060D02*
Y975000D01*
G01X1549300Y53060D02*
Y56000D01*
G01X1556700Y47940D02*
Y45000D01*
G01X1559700Y514440D02*
Y511500D01*
G01X1552300Y519560D02*
Y522500D01*
G01X1559700Y966940D02*
Y964000D01*
G01X1552300Y972060D02*
Y975000D01*
G01X1676300Y66560D02*
Y69500D01*
G01X1683700Y61440D02*
Y58500D01*
G01Y514440D02*
Y511500D01*
G01X1676300Y519560D02*
Y522500D01*
G01Y972060D02*
Y975000D01*
G01X1683700Y966940D02*
Y964000D01*
G01X1807700Y514440D02*
Y511500D01*
G01X1800300Y519560D02*
Y522500D01*
G01Y972060D02*
Y975000D01*
G01X1807700Y966940D02*
Y964000D01*
G01X1801786Y1456950D02*
Y1454240D01*
X1803426Y1452600D01*
G01X1804326Y1480500D02*
X1801796Y1483030D01*
Y1484390D01*
G01X1796676Y1476990D02*
Y1475750D01*
X1794226Y1473300D01*
G01X1813566Y1476665D02*
X1813101Y1476200D01*
X1810426D01*
G01X1796666Y1463450D02*
X1795676D01*
X1793276Y1465850D01*
X1790226D01*
G01X1880940Y29300D02*
X1878000D01*
G01X1886060Y36700D02*
X1887900Y38540D01*
Y41300D01*
G01X1866700Y516440D02*
Y512800D01*
G01X1859300Y521560D02*
Y524500D01*
G01Y974560D02*
Y977500D01*
G01X1866700Y969440D02*
X1869640D01*
X1870800Y970600D01*
Y973100D01*
G01X1818686Y1484735D02*
X1820491D01*
X1822326Y1482900D01*
Y1481600D01*
G54D103*
X1228100Y1316783D03*
X1194894D03*
G54D10*
G01X508867Y1497771D02*
Y1494867D01*
X498579Y1484579D01*
X150331D01*
X147502Y1481750D01*
X142396D01*
G01X892028Y1189440D02*
Y1185432D01*
X894383Y1183077D01*
X945287D01*
X947700Y1185490D01*
Y1185500D01*
G01X1087962Y959252D02*
X1086521D01*
X1060710Y933441D01*
Y895660D01*
X34900Y34200D03*
X40600Y1464400D03*
X1894200Y1471300D03*
G54D113*
G01X117724Y1480400D02*
X119174D01*
X120474Y1481700D01*
Y1482800D01*
G01X615059Y614075D02*
X622671D01*
X622687Y614091D01*
G01X615059Y604075D02*
X622675D01*
X622703Y604103D01*
G01X615059Y584075D02*
X622977D01*
X623005Y584047D01*
G01X1000557Y895075D02*
X997943D01*
X997083Y895935D01*
G01X1021883Y892965D02*
X1025216D01*
X1025251Y893000D01*
G01X1021789Y896965D02*
X1025065D01*
G01X1011531Y899075D02*
X1014807D01*
G01X1011591Y895045D02*
X1014962D01*
X1015007Y895000D01*
G01X1000557Y899075D02*
X999235Y897753D01*
X998883D01*
X997083Y895953D01*
Y895935D01*
G01X990147Y895065D02*
Y891192D01*
X990174Y891165D01*
G01D02*
X986793D01*
X986728Y891100D01*
G01X990147Y903465D02*
Y900700D01*
X989100Y899653D01*
Y899600D01*
G01X1000557Y903075D02*
X998843D01*
X996938Y901170D01*
G01X1270492Y93819D02*
X1278036D01*
X1278038Y93821D01*
G01X1270492Y84370D02*
X1278668D01*
X1278698Y84340D01*
G01X1270492Y103268D02*
X1262468D01*
G54D20*
X89000Y93500D03*
X84000D03*
X79000D03*
X74000D03*
Y113500D03*
X79000D03*
X84000D03*
X89000D03*
X51000Y131500D03*
X56000D03*
X61000D03*
X66000D03*
Y111500D03*
X61000D03*
X56000D03*
X51000D03*
X89000Y546000D03*
X84000D03*
X79000D03*
X74000D03*
Y566000D03*
X79000D03*
X84000D03*
X89000D03*
X66000Y564000D03*
X61000D03*
X56000D03*
X51000D03*
Y584000D03*
X56000D03*
X61000D03*
X66000D03*
X89000Y999000D03*
X84000D03*
X79000D03*
X74000D03*
Y1019000D03*
X79000D03*
X84000D03*
X89000D03*
X51000Y1037000D03*
X56000D03*
X61000D03*
X66000D03*
Y1017000D03*
X61000D03*
X56000D03*
X51000D03*
X188500Y86000D03*
X183500D03*
X178500D03*
X173500D03*
Y106000D03*
X178500D03*
X183500D03*
X188500D03*
X190000Y564000D03*
X185000D03*
X180000D03*
X175000D03*
Y584000D03*
X180000D03*
X185000D03*
X190000D03*
X175500Y1037000D03*
X180500D03*
X185500D03*
X190500D03*
Y1017000D03*
X185500D03*
X180500D03*
X175500D03*
X194174Y1430800D03*
Y1410800D03*
X213000Y93500D03*
X208000D03*
X203000D03*
X198000D03*
Y113500D03*
X203000D03*
X208000D03*
X213000D03*
Y546000D03*
X208000D03*
X203000D03*
X198000D03*
Y566000D03*
X203000D03*
X208000D03*
X213000D03*
X213500Y999000D03*
X208500D03*
X203500D03*
X198500D03*
Y1019000D03*
X203500D03*
X208500D03*
X213500D03*
X199174Y1430800D03*
X204174D03*
X209174D03*
Y1410800D03*
X204174D03*
X199174D03*
X337500Y93500D03*
X332500D03*
X327500D03*
X322500D03*
Y113500D03*
X327500D03*
X332500D03*
X337500D03*
X299500Y131500D03*
X304500D03*
X309500D03*
X314500D03*
Y111500D03*
X309500D03*
X304500D03*
X299500D03*
X337500Y546000D03*
X332500D03*
X327500D03*
X322500D03*
Y566000D03*
X327500D03*
X332500D03*
X337500D03*
X314500Y564000D03*
X309500D03*
X304500D03*
X299500D03*
Y584000D03*
X304500D03*
X309500D03*
X314500D03*
X337500Y999000D03*
X332500D03*
X327500D03*
X322500D03*
Y1019000D03*
X327500D03*
X332500D03*
X337500D03*
X299500Y1037000D03*
X304500D03*
X309500D03*
X314500D03*
Y1017000D03*
X309500D03*
X304500D03*
X299500D03*
X425500Y66600D03*
X430500D03*
X435500D03*
X440500D03*
Y46600D03*
X435500D03*
X430500D03*
X425500D03*
X461900Y97100D03*
X456900D03*
X451900D03*
X446900D03*
Y117100D03*
X451900D03*
X456900D03*
X461900D03*
X461500Y546000D03*
X456500D03*
X451500D03*
X446500D03*
Y566000D03*
X451500D03*
X456500D03*
X461500D03*
X438500Y564000D03*
X433500D03*
X428500D03*
X423500D03*
Y584000D03*
X428500D03*
X433500D03*
X438500D03*
X461500Y999000D03*
X456500D03*
X451500D03*
X446500D03*
Y1019000D03*
X451500D03*
X456500D03*
X461500D03*
X423500Y1037000D03*
X428500D03*
X433500D03*
X438500D03*
Y1017000D03*
X433500D03*
X428500D03*
X423500D03*
X576000Y93500D03*
X571000D03*
Y113500D03*
X576000D03*
X548000Y131500D03*
X553000D03*
X558000D03*
X563000D03*
Y111500D03*
X558000D03*
X553000D03*
X548000D03*
X576000Y546000D03*
X571000D03*
Y566000D03*
X576000D03*
X563000Y564000D03*
X558000D03*
X553000D03*
X548000D03*
Y584000D03*
X553000D03*
X558000D03*
X563000D03*
X576000Y999000D03*
X571000D03*
Y1019000D03*
X576000D03*
X548000Y1037000D03*
X553000D03*
X558000D03*
X563000D03*
Y1017000D03*
X558000D03*
X553000D03*
X548000D03*
X518035Y1418131D03*
X513035D03*
X508035D03*
X503035D03*
Y1438131D03*
X508035D03*
X513035D03*
X518035D03*
X586000Y93500D03*
X581000D03*
X670500Y86000D03*
X581000Y113500D03*
X586000D03*
X670500Y106000D03*
X586000Y546000D03*
X581000D03*
Y566000D03*
X586000D03*
X672000Y564000D03*
Y584000D03*
X586000Y999000D03*
X581000D03*
Y1019000D03*
X586000D03*
X672000Y1037000D03*
Y1017000D03*
X710000Y93500D03*
X705000D03*
X700000D03*
X695000D03*
X685500Y86000D03*
X680500D03*
X675500D03*
X695000Y113500D03*
X700000D03*
X705000D03*
X710000D03*
X675500Y106000D03*
X680500D03*
X685500D03*
X710000Y546000D03*
X705000D03*
X700000D03*
X695000D03*
Y566000D03*
X700000D03*
X705000D03*
X710000D03*
X687000Y564000D03*
X682000D03*
X677000D03*
Y584000D03*
X682000D03*
X687000D03*
X710000Y999000D03*
X705000D03*
X700000D03*
X695000D03*
Y1019000D03*
X700000D03*
X705000D03*
X710000D03*
X677000Y1037000D03*
X682000D03*
X687000D03*
Y1017000D03*
X682000D03*
X677000D03*
X989120Y845050D03*
X984120D03*
X979120D03*
X974120D03*
Y865050D03*
X979120D03*
X984120D03*
X989120D03*
X1220600Y1326833D03*
X1225600D03*
X1230600D03*
X1235600D03*
Y1306733D03*
X1230600D03*
X1225600D03*
X1220600D03*
X1187394Y1326833D03*
X1192394D03*
X1197394D03*
X1202394D03*
Y1306733D03*
X1197394D03*
X1192394D03*
X1187394D03*
X1314500Y82000D03*
X1309500D03*
X1304500D03*
X1299500D03*
Y102000D03*
X1304500D03*
X1309500D03*
X1314500D03*
X1318000Y140000D03*
X1323000D03*
X1328000D03*
X1333000D03*
Y120000D03*
X1328000D03*
X1323000D03*
X1318000D03*
X1333500Y573000D03*
X1328500D03*
X1323500D03*
X1318500D03*
Y593000D03*
X1323500D03*
X1328500D03*
X1333500D03*
X1318500Y1045500D03*
X1323500D03*
X1328500D03*
X1333500D03*
Y1025500D03*
X1328500D03*
X1323500D03*
X1318500D03*
X1333100Y1430700D03*
X1338100D03*
Y1410700D03*
X1333100D03*
X1343100Y1430700D03*
X1348100D03*
Y1410700D03*
X1343100D03*
X1442500Y140000D03*
X1447500D03*
X1452500D03*
X1457500D03*
Y120000D03*
X1452500D03*
X1447500D03*
X1442500D03*
X1457500Y573000D03*
X1452500D03*
X1447500D03*
X1442500D03*
Y593000D03*
X1447500D03*
X1452500D03*
X1457500D03*
X1442500Y1045500D03*
X1447500D03*
X1452500D03*
X1457500D03*
Y1025500D03*
X1452500D03*
X1447500D03*
X1442500D03*
X1564000Y82000D03*
X1559000D03*
X1554000D03*
X1549000D03*
Y102000D03*
X1554000D03*
X1559000D03*
X1564000D03*
X1582000Y573000D03*
X1577000D03*
X1572000D03*
X1567000D03*
Y593000D03*
X1572000D03*
X1577000D03*
X1582000D03*
X1567000Y1045500D03*
X1572000D03*
X1577000D03*
X1582000D03*
Y1025500D03*
X1577000D03*
X1572000D03*
X1567000D03*
X1691000Y140000D03*
X1696000D03*
X1701000D03*
X1706000D03*
Y120000D03*
X1701000D03*
X1696000D03*
X1691000D03*
X1706000Y573000D03*
X1701000D03*
X1696000D03*
X1691000D03*
Y593000D03*
X1696000D03*
X1701000D03*
X1706000D03*
X1691000Y1045500D03*
X1696000D03*
X1701000D03*
X1706000D03*
Y1025500D03*
X1701000D03*
X1696000D03*
X1691000D03*
X1721326Y1430600D03*
Y1410600D03*
X1811300Y91100D03*
X1806300D03*
X1801300D03*
X1796300D03*
Y111100D03*
X1801300D03*
X1806300D03*
X1811300D03*
X1814500Y140000D03*
Y120000D03*
X1815000Y573000D03*
Y593000D03*
Y1045500D03*
Y1025500D03*
X1726326Y1430600D03*
X1731326D03*
X1736326D03*
Y1410600D03*
X1731326D03*
X1726326D03*
X1880500Y93000D03*
X1875500D03*
X1870500D03*
X1865500D03*
X1856000Y85500D03*
X1851000D03*
X1846000D03*
X1841000D03*
X1865500Y113000D03*
X1870500D03*
X1875500D03*
X1880500D03*
X1819500Y140000D03*
X1824500D03*
X1829500D03*
Y120000D03*
X1824500D03*
X1819500D03*
X1841000Y105500D03*
X1846000D03*
X1851000D03*
X1856000D03*
X1880500Y546000D03*
X1875500D03*
X1870500D03*
X1865500D03*
Y566000D03*
X1870500D03*
X1875500D03*
X1880500D03*
X1830000Y573000D03*
X1825000D03*
X1820000D03*
X1857500Y564000D03*
X1852500D03*
X1847500D03*
X1842500D03*
X1820000Y593000D03*
X1825000D03*
X1830000D03*
X1842500Y584000D03*
X1847500D03*
X1852500D03*
X1857500D03*
X1880500Y999000D03*
X1875500D03*
X1870500D03*
X1865500D03*
Y1019000D03*
X1870500D03*
X1875500D03*
X1880500D03*
X1820000Y1045500D03*
X1825000D03*
X1830000D03*
Y1025500D03*
X1825000D03*
X1820000D03*
X1842500Y1037000D03*
X1847500D03*
X1852500D03*
X1857500D03*
Y1017000D03*
X1852500D03*
X1847500D03*
X1842500D03*
G54D11*
X99823Y93819D03*
Y90669D03*
Y87520D03*
Y84370D03*
Y103268D03*
Y100118D03*
Y96969D03*
Y556024D03*
Y552874D03*
Y549725D03*
Y546575D03*
Y543425D03*
Y540276D03*
Y537126D03*
Y1008780D03*
Y1005630D03*
Y1002481D03*
Y999331D03*
Y996181D03*
Y993032D03*
Y989882D03*
X224035Y93819D03*
Y90669D03*
Y87520D03*
Y84370D03*
Y103268D03*
Y100118D03*
Y96969D03*
Y556024D03*
Y552874D03*
Y549725D03*
Y546575D03*
Y543425D03*
Y540276D03*
Y537126D03*
Y1008780D03*
Y1005630D03*
Y1002481D03*
Y999331D03*
Y996181D03*
Y993032D03*
Y989882D03*
X348248Y93819D03*
Y90669D03*
Y87520D03*
Y84370D03*
Y103268D03*
Y100118D03*
Y96969D03*
Y556024D03*
Y552874D03*
Y549725D03*
Y546575D03*
Y543425D03*
Y540276D03*
Y537126D03*
Y1008780D03*
Y1005630D03*
Y1002481D03*
Y999331D03*
Y996181D03*
Y993032D03*
Y989882D03*
X472460Y93819D03*
Y90669D03*
Y87520D03*
Y84370D03*
Y103268D03*
Y100118D03*
Y96969D03*
Y556024D03*
Y552874D03*
Y549725D03*
Y546575D03*
Y543425D03*
Y540276D03*
Y537126D03*
Y1008780D03*
Y1005630D03*
Y1002481D03*
Y999331D03*
Y996181D03*
Y993032D03*
Y989882D03*
X596673Y93819D03*
Y90669D03*
Y87520D03*
Y84370D03*
Y103268D03*
Y100118D03*
Y96969D03*
Y556024D03*
Y552874D03*
Y549725D03*
Y546575D03*
Y543425D03*
Y540276D03*
Y537126D03*
Y1008780D03*
Y1005630D03*
Y1002481D03*
Y999331D03*
Y996181D03*
Y993032D03*
Y989882D03*
X720886Y93819D03*
Y90669D03*
Y87520D03*
Y84370D03*
Y103268D03*
Y100118D03*
Y96969D03*
Y556024D03*
Y552874D03*
Y549725D03*
Y546575D03*
Y543425D03*
Y540276D03*
Y537126D03*
Y1008780D03*
Y1005630D03*
Y1002481D03*
Y999331D03*
Y996181D03*
Y993032D03*
Y989882D03*
X1270492Y93819D03*
Y90669D03*
Y87520D03*
Y84370D03*
Y103268D03*
Y100118D03*
Y96969D03*
Y556024D03*
Y552874D03*
Y549725D03*
Y546575D03*
Y543425D03*
Y540276D03*
Y537126D03*
Y1008780D03*
Y1005630D03*
Y1002481D03*
Y999331D03*
Y996181D03*
Y993032D03*
Y989882D03*
X1394705Y93819D03*
Y90669D03*
Y87520D03*
Y84370D03*
Y103268D03*
Y100118D03*
Y96969D03*
Y556024D03*
Y552874D03*
Y549725D03*
Y546575D03*
Y543425D03*
Y540276D03*
Y537126D03*
Y1008780D03*
Y1005630D03*
Y1002481D03*
Y999331D03*
Y996181D03*
Y993032D03*
Y989882D03*
X1518917Y93819D03*
Y90669D03*
Y87520D03*
Y84370D03*
Y103268D03*
Y100118D03*
Y96969D03*
Y556024D03*
Y552874D03*
Y549725D03*
Y546575D03*
Y543425D03*
Y540276D03*
Y537126D03*
Y1008780D03*
Y1005630D03*
Y1002481D03*
Y999331D03*
Y996181D03*
Y993032D03*
Y989882D03*
X1643130Y93819D03*
Y90669D03*
Y87520D03*
Y84370D03*
Y103268D03*
Y100118D03*
Y96969D03*
Y556024D03*
Y552874D03*
Y549725D03*
Y546575D03*
Y543425D03*
Y540276D03*
Y537126D03*
Y1008780D03*
Y1005630D03*
Y1002481D03*
Y999331D03*
Y996181D03*
Y993032D03*
Y989882D03*
X1767342Y93819D03*
Y90669D03*
Y87520D03*
Y84370D03*
Y103268D03*
Y100118D03*
Y96969D03*
Y556024D03*
Y552874D03*
Y549725D03*
Y546575D03*
Y543425D03*
Y540276D03*
Y537126D03*
Y1008780D03*
Y1005630D03*
Y1002481D03*
Y999331D03*
Y996181D03*
Y993032D03*
Y989882D03*
X1891555Y93819D03*
Y90669D03*
Y87520D03*
Y84370D03*
Y103268D03*
Y100118D03*
Y96969D03*
Y556024D03*
Y552874D03*
Y549725D03*
Y546575D03*
Y543425D03*
Y540276D03*
Y537126D03*
Y1008780D03*
Y1005630D03*
Y1002481D03*
Y999331D03*
Y996181D03*
Y993032D03*
Y989882D03*
G54D104*
X1267378Y57719D03*
X1265178D03*
X1267378Y59919D03*
X1265178D03*
X1267378Y510475D03*
X1265178D03*
X1267378Y512675D03*
X1265178D03*
X1267378Y963231D03*
X1265178D03*
X1267378Y965431D03*
X1265178D03*
X1391591Y57719D03*
X1389391D03*
X1391591Y59919D03*
X1389391D03*
X1391591Y510475D03*
X1389391D03*
X1391591Y512675D03*
X1389391D03*
X1391591Y963231D03*
X1389391D03*
X1391591Y965431D03*
X1389391D03*
X1515803Y57719D03*
X1513603D03*
X1515803Y59919D03*
X1513603D03*
X1515803Y510475D03*
X1513603D03*
X1515803Y512675D03*
X1513603D03*
X1515803Y963231D03*
X1513603D03*
X1515803Y965431D03*
X1513603D03*
X1640016Y59919D03*
X1637816D03*
X1640016Y57719D03*
X1637816D03*
X1640016Y512675D03*
X1637816D03*
X1640016Y510475D03*
X1637816D03*
X1640016Y963231D03*
X1637816D03*
X1640016Y965431D03*
X1637816D03*
X1764228Y57719D03*
X1762028D03*
X1764228Y59919D03*
X1762028D03*
X1764228Y510475D03*
X1762028D03*
X1764228Y512675D03*
X1762028D03*
X1764228Y963231D03*
X1762028D03*
X1764228Y965431D03*
X1762028D03*
X1888441Y57719D03*
X1886241D03*
X1888441Y59919D03*
X1886241D03*
X1888441Y510475D03*
X1886241D03*
X1888441Y512675D03*
X1886241D03*
X1888441Y963231D03*
X1886241D03*
X1888441Y965431D03*
X1886241D03*
G54D114*
G01X489037Y-206331D02*
X489911Y-205456D01*
X490566Y-203998D01*
X491003Y-201955D01*
X490566Y-200206D01*
X489693Y-199039D01*
X488164Y-198164D01*
X482269D01*
Y-215664D01*
X489474D01*
X491003Y-214498D01*
X491876Y-212747D01*
X492313Y-210706D01*
X491876Y-208664D01*
X490566Y-206914D01*
X489037Y-206331D01*
X482269D01*
G01X501734Y-215664D02*
Y-203998D01*
G01Y-206331D02*
X502826Y-205164D01*
X503918Y-204289D01*
X505446Y-203998D01*
X506537Y-204289D01*
X507848Y-205164D01*
G01X517706Y-220914D02*
X519016Y-221497D01*
X520763Y-220914D01*
X521854Y-219748D01*
X522728Y-218289D01*
X524037Y-213623D01*
X526876Y-203998D01*
G01X519889D02*
X524037Y-213623D01*
G01X543284Y-205456D02*
X541756Y-204289D01*
X540446Y-203998D01*
X538699Y-204581D01*
X537389Y-205747D01*
X536516Y-207789D01*
X536297Y-209831D01*
X536516Y-211873D01*
X537389Y-213623D01*
X538699Y-215081D01*
X540446Y-215664D01*
X541974Y-215081D01*
X543284Y-213914D01*
G01X554016Y-207789D02*
X561003D01*
X560348Y-205747D01*
X559256Y-204581D01*
X557728Y-203998D01*
X556199Y-204289D01*
X554889Y-205164D01*
X554016Y-207206D01*
X553579Y-208956D01*
Y-210706D01*
X554016Y-212456D01*
X555108Y-214206D01*
X556418Y-215372D01*
X557946Y-215664D01*
X559474Y-215081D01*
X561003Y-213331D01*
G01X597094Y-199623D02*
X595784Y-198747D01*
X594256Y-198164D01*
X592509D01*
X590544Y-199039D01*
X589016Y-200497D01*
X587924Y-202248D01*
X587051Y-205164D01*
X586832Y-207789D01*
X587269Y-210414D01*
X587924Y-212164D01*
X589234Y-213914D01*
X590763Y-215081D01*
X592291Y-215664D01*
X593819D01*
X595348Y-215081D01*
X596658Y-214206D01*
X597750Y-213040D01*
G01X613721Y-215664D02*
Y-203998D01*
G01Y-206039D02*
X612848Y-204873D01*
X611537Y-204289D01*
X610009Y-203998D01*
X608481Y-204581D01*
X607171Y-205747D01*
X606297Y-207497D01*
X605861Y-209831D01*
X606297Y-212164D01*
X607171Y-213914D01*
X608481Y-215081D01*
X610009Y-215664D01*
X611537Y-215372D01*
X612848Y-214498D01*
X613721Y-213331D01*
G01X623579Y-215664D02*
Y-203998D01*
G01Y-206914D02*
X624453Y-205456D01*
X625763Y-204289D01*
X627509Y-203998D01*
X629037Y-204289D01*
X630348Y-205456D01*
X631003Y-207497D01*
Y-215664D01*
G01X640206Y-220914D02*
X641516Y-221497D01*
X643263Y-220914D01*
X644354Y-219748D01*
X645228Y-218289D01*
X646537Y-213623D01*
X649376Y-203998D01*
G01X642389D02*
X646537Y-213623D01*
G01X662291Y-215664D02*
X660981Y-215372D01*
X659671Y-214206D01*
X658797Y-212164D01*
X658361Y-209831D01*
X658797Y-207497D01*
X659671Y-205456D01*
X660981Y-204289D01*
X662291Y-203998D01*
X663601Y-204289D01*
X664911Y-205456D01*
X665784Y-207497D01*
X666003Y-209831D01*
X665784Y-212164D01*
X664911Y-214206D01*
X663601Y-215372D01*
X662291Y-215664D01*
G01X676079D02*
Y-203998D01*
G01Y-206914D02*
X676953Y-205456D01*
X678263Y-204289D01*
X680009Y-203998D01*
X681537Y-204289D01*
X682848Y-205456D01*
X683503Y-207497D01*
Y-215664D01*
G01X710424D02*
Y-198164D01*
X715883D01*
X717629Y-199039D01*
X718721Y-200206D01*
X719158Y-202539D01*
X718721Y-204873D01*
X717411Y-206331D01*
X715883Y-207206D01*
X710424D01*
G01X715883D02*
X719158Y-215664D01*
G01X732291Y-216247D02*
X731854Y-215956D01*
Y-215372D01*
X732291Y-215081D01*
X732728Y-215372D01*
Y-215956D01*
X732291Y-216247D01*
G01X744988Y-215664D02*
Y-198164D01*
X749354D01*
X751101Y-199039D01*
X752411Y-200206D01*
X753503Y-201955D01*
X754376Y-203998D01*
X754594Y-206914D01*
X754376Y-209831D01*
X753503Y-211873D01*
X752411Y-213623D01*
X751101Y-214789D01*
X749354Y-215664D01*
X744988D01*
G01X762924D02*
Y-198164D01*
X768164D01*
X769911Y-199039D01*
X771221Y-201081D01*
X771658Y-203414D01*
X771221Y-205747D01*
X770129Y-207497D01*
X768164Y-208373D01*
X762924D01*
G01X786537Y-206331D02*
X787411Y-205456D01*
X788066Y-203998D01*
X788503Y-201955D01*
X788066Y-200206D01*
X787193Y-199039D01*
X785664Y-198164D01*
X779769D01*
Y-215664D01*
X786974D01*
X788503Y-214498D01*
X789376Y-212747D01*
X789813Y-210706D01*
X789376Y-208664D01*
X788066Y-206914D01*
X786537Y-206331D01*
X779769D01*
G01X595364Y-170664D02*
Y-153164D01*
X601041Y-167747D01*
X606718Y-153164D01*
Y-170664D01*
G01X618541D02*
X617231Y-170372D01*
X615921Y-169206D01*
X615047Y-167164D01*
X614611Y-164831D01*
X615047Y-162497D01*
X615921Y-160456D01*
X617231Y-159289D01*
X618541Y-158998D01*
X619851Y-159289D01*
X621161Y-160456D01*
X622034Y-162497D01*
X622253Y-164831D01*
X622034Y-167164D01*
X621161Y-169206D01*
X619851Y-170372D01*
X618541Y-170664D01*
G01X639971Y-153164D02*
Y-170664D01*
G01Y-168040D02*
X639098Y-169498D01*
X637787Y-170372D01*
X636259Y-170664D01*
X634513Y-170081D01*
X633203Y-168623D01*
X632329Y-166873D01*
X632111Y-164831D01*
X632329Y-162789D01*
X633203Y-161039D01*
X634513Y-159581D01*
X636259Y-158998D01*
X637787Y-159289D01*
X638879Y-159873D01*
X639971Y-161039D01*
G01X650266Y-162789D02*
X657253D01*
X656598Y-160747D01*
X655506Y-159581D01*
X653978Y-158998D01*
X652449Y-159289D01*
X651139Y-160164D01*
X650266Y-162206D01*
X649829Y-163956D01*
Y-165706D01*
X650266Y-167456D01*
X651358Y-169206D01*
X652668Y-170372D01*
X654196Y-170664D01*
X655724Y-170081D01*
X657253Y-168331D01*
G01X671041Y-170664D02*
Y-153164D01*
G01X839441Y-215664D02*
Y-198164D01*
X836821Y-201664D01*
G01Y-215664D02*
X842061D01*
G01X852793Y-208373D02*
X854321Y-206331D01*
X855631Y-205164D01*
X857378Y-204581D01*
X858906Y-205164D01*
X859998Y-206331D01*
X860871Y-208081D01*
X861089Y-210122D01*
X860871Y-211873D01*
X859998Y-213623D01*
X858687Y-215081D01*
X857159Y-215664D01*
X855413Y-215081D01*
X853884Y-213331D01*
X853011Y-210706D01*
X852793Y-207789D01*
X853229Y-203998D01*
X853884Y-201955D01*
X854976Y-199914D01*
X856504Y-198456D01*
X858033Y-198164D01*
X859561Y-198747D01*
X860653Y-200206D01*
G01X869638Y-212164D02*
X870947Y-214206D01*
X872694Y-215372D01*
X874659Y-215664D01*
X876406Y-215372D01*
X878153Y-213914D01*
X879244Y-212164D01*
X879463Y-210414D01*
X879026Y-208373D01*
X877498Y-206914D01*
X875969Y-206331D01*
X874004D01*
G01X875969D02*
X877279Y-205456D01*
X878371Y-203998D01*
X878808Y-202248D01*
X878371Y-200497D01*
X877279Y-199039D01*
X875314Y-198164D01*
X873349Y-198456D01*
X871384Y-199623D01*
G01X891941Y-215664D02*
Y-198164D01*
X889321Y-201664D01*
G01Y-215664D02*
X894561D01*
G01X909004D02*
X909441Y-211873D01*
X910096Y-208664D01*
X910969Y-205747D01*
X912061Y-202539D01*
X913808Y-198164D01*
X905074D01*
G01X826324Y-170664D02*
Y-153164D01*
X831564D01*
X833311Y-154039D01*
X834621Y-156081D01*
X835058Y-158414D01*
X834621Y-160747D01*
X833529Y-162497D01*
X831564Y-163373D01*
X826324D01*
G01X852994Y-154623D02*
X851684Y-153747D01*
X850156Y-153164D01*
X848409D01*
X846444Y-154039D01*
X844916Y-155497D01*
X843824Y-157248D01*
X842951Y-160164D01*
X842732Y-162789D01*
X843169Y-165414D01*
X843824Y-167164D01*
X845134Y-168914D01*
X846663Y-170081D01*
X848191Y-170664D01*
X849719D01*
X851248Y-170081D01*
X852558Y-169206D01*
X853650Y-168040D01*
G01X867437Y-161331D02*
X868311Y-160456D01*
X868966Y-158998D01*
X869403Y-156955D01*
X868966Y-155206D01*
X868093Y-154039D01*
X866564Y-153164D01*
X860669D01*
Y-170664D01*
X867874D01*
X869403Y-169498D01*
X870276Y-167747D01*
X870713Y-165706D01*
X870276Y-163664D01*
X868966Y-161914D01*
X867437Y-161331D01*
X860669D01*
G01X876641Y-176497D02*
X889741D01*
G01X895669Y-170664D02*
Y-153164D01*
X905713Y-170664D01*
Y-153164D01*
G01X918191Y-170664D02*
X916444Y-170372D01*
X914916Y-169206D01*
X913606Y-167456D01*
X912732Y-165414D01*
X912296Y-163081D01*
Y-160747D01*
X912732Y-158414D01*
X913606Y-156372D01*
X914916Y-154623D01*
X916444Y-153456D01*
X918191Y-153164D01*
X919937Y-153456D01*
X921466Y-154623D01*
X922776Y-156372D01*
X923650Y-158414D01*
X924086Y-160747D01*
Y-163081D01*
X923650Y-165414D01*
X922776Y-167456D01*
X921466Y-169206D01*
X919937Y-170372D01*
X918191Y-170664D01*
G01X1000741Y-215664D02*
Y-198164D01*
X998121Y-201664D01*
G01Y-215664D02*
X1003361D01*
G01X969032Y-153164D02*
X974491Y-170664D01*
X979950Y-153164D01*
G01X996358Y-170664D02*
X987624D01*
Y-153164D01*
X996358D01*
G01X992864Y-161622D02*
X987624D01*
G01X1005124Y-170664D02*
Y-153164D01*
X1010583D01*
X1012329Y-154039D01*
X1013421Y-155206D01*
X1013858Y-157539D01*
X1013421Y-159873D01*
X1012111Y-161331D01*
X1010583Y-162206D01*
X1005124D01*
G01X1010583D02*
X1013858Y-170664D01*
G01X1026991Y-171247D02*
X1026554Y-170956D01*
Y-170372D01*
X1026991Y-170081D01*
X1027428Y-170372D01*
Y-170956D01*
X1026991Y-171247D01*
G01X1128824Y-198164D02*
Y-215664D01*
X1137558D01*
G01X1150691D02*
Y-198164D01*
X1148071Y-201664D01*
G01Y-215664D02*
X1153311D01*
G01X1102574Y-153164D02*
Y-170664D01*
X1111308D01*
G01X1128371D02*
Y-158998D01*
G01Y-161039D02*
X1127498Y-159873D01*
X1126187Y-159289D01*
X1124659Y-158998D01*
X1123131Y-159581D01*
X1121821Y-160747D01*
X1120947Y-162497D01*
X1120511Y-164831D01*
X1120947Y-167164D01*
X1121821Y-168914D01*
X1123131Y-170081D01*
X1124659Y-170664D01*
X1126187Y-170372D01*
X1127498Y-169498D01*
X1128371Y-168331D01*
G01X1137356Y-175914D02*
X1138666Y-176497D01*
X1140413Y-175914D01*
X1141504Y-174748D01*
X1142378Y-173289D01*
X1143687Y-168623D01*
X1146526Y-158998D01*
G01X1139539D02*
X1143687Y-168623D01*
G01X1156166Y-162789D02*
X1163153D01*
X1162498Y-160747D01*
X1161406Y-159581D01*
X1159878Y-158998D01*
X1158349Y-159289D01*
X1157039Y-160164D01*
X1156166Y-162206D01*
X1155729Y-163956D01*
Y-165706D01*
X1156166Y-167456D01*
X1157258Y-169206D01*
X1158568Y-170372D01*
X1160096Y-170664D01*
X1161624Y-170081D01*
X1163153Y-168331D01*
G01X1173884Y-170664D02*
Y-158998D01*
G01Y-161331D02*
X1174976Y-160164D01*
X1176068Y-159289D01*
X1177596Y-158998D01*
X1178687Y-159289D01*
X1179998Y-160164D01*
G01X1244688Y-170664D02*
Y-153164D01*
X1249054D01*
X1250801Y-154039D01*
X1252111Y-155206D01*
X1253203Y-156955D01*
X1254076Y-158998D01*
X1254294Y-161914D01*
X1254076Y-164831D01*
X1253203Y-166873D01*
X1252111Y-168623D01*
X1250801Y-169789D01*
X1249054Y-170664D01*
X1244688D01*
G01X1263716Y-162789D02*
X1270703D01*
X1270048Y-160747D01*
X1268956Y-159581D01*
X1267428Y-158998D01*
X1265899Y-159289D01*
X1264589Y-160164D01*
X1263716Y-162206D01*
X1263279Y-163956D01*
Y-165706D01*
X1263716Y-167456D01*
X1264808Y-169206D01*
X1266118Y-170372D01*
X1267646Y-170664D01*
X1269174Y-170081D01*
X1270703Y-168331D01*
G01X1281216Y-168623D02*
X1282308Y-169789D01*
X1283836Y-170664D01*
X1285146D01*
X1286456Y-170081D01*
X1287329Y-169206D01*
X1287766Y-168040D01*
X1287548Y-166289D01*
X1286674Y-165414D01*
X1282744Y-163664D01*
X1281871Y-161622D01*
X1282308Y-160164D01*
X1283181Y-159289D01*
X1284491Y-158998D01*
X1285801Y-159289D01*
X1287111Y-160164D01*
G01X1301991Y-158998D02*
Y-170664D01*
G01Y-154331D02*
X1301554Y-154039D01*
Y-153456D01*
X1301991Y-153164D01*
X1302428Y-153456D01*
Y-154039D01*
X1301991Y-154331D01*
G01X1316434Y-175039D02*
X1317963Y-176206D01*
X1319709Y-176497D01*
X1321237Y-176206D01*
X1322548Y-174748D01*
X1323421Y-172706D01*
Y-158998D01*
G01Y-161331D02*
X1322548Y-160164D01*
X1321237Y-159289D01*
X1319709Y-158998D01*
X1317963Y-159581D01*
X1316871Y-160747D01*
X1315997Y-162789D01*
X1315561Y-164831D01*
X1315779Y-166581D01*
X1316653Y-168623D01*
X1317963Y-170081D01*
X1319709Y-170664D01*
X1321019Y-170372D01*
X1322548Y-169206D01*
X1323421Y-168040D01*
G01X1333279Y-170664D02*
Y-158998D01*
G01Y-161914D02*
X1334153Y-160456D01*
X1335463Y-159289D01*
X1337209Y-158998D01*
X1338737Y-159289D01*
X1340048Y-160456D01*
X1340703Y-162497D01*
Y-170664D01*
G01X1351216Y-162789D02*
X1358203D01*
X1357548Y-160747D01*
X1356456Y-159581D01*
X1354928Y-158998D01*
X1353399Y-159289D01*
X1352089Y-160164D01*
X1351216Y-162206D01*
X1350779Y-163956D01*
Y-165706D01*
X1351216Y-167456D01*
X1352308Y-169206D01*
X1353618Y-170372D01*
X1355146Y-170664D01*
X1356674Y-170081D01*
X1358203Y-168331D01*
G01X1368934Y-170664D02*
Y-158998D01*
G01Y-161331D02*
X1370026Y-160164D01*
X1371118Y-159289D01*
X1372646Y-158998D01*
X1373737Y-159289D01*
X1375048Y-160164D01*
G01X1266991Y-215664D02*
X1265244Y-215372D01*
X1263716Y-214206D01*
X1262406Y-212456D01*
X1261532Y-210414D01*
X1261096Y-208081D01*
Y-205747D01*
X1261532Y-203414D01*
X1262406Y-201372D01*
X1263716Y-199623D01*
X1265244Y-198456D01*
X1266991Y-198164D01*
X1268737Y-198456D01*
X1270266Y-199623D01*
X1271576Y-201372D01*
X1272450Y-203414D01*
X1272886Y-205747D01*
Y-208081D01*
X1272450Y-210414D01*
X1271576Y-212456D01*
X1270266Y-214206D01*
X1268737Y-215372D01*
X1266991Y-215664D01*
G01X1268737Y-210997D02*
X1271358Y-215664D01*
G01X1279688Y-198164D02*
Y-210706D01*
X1280561Y-213331D01*
X1282308Y-215081D01*
X1284491Y-215664D01*
X1286674Y-215081D01*
X1288421Y-213331D01*
X1289294Y-210706D01*
Y-198164D01*
G01X1299371D02*
X1304611D01*
G01X1301991D02*
Y-215664D01*
G01X1299371D02*
X1304611D01*
G01X1314469D02*
Y-198164D01*
X1324513Y-215664D01*
Y-198164D01*
G01X1341794Y-199623D02*
X1340484Y-198747D01*
X1338956Y-198164D01*
X1337209D01*
X1335244Y-199039D01*
X1333716Y-200497D01*
X1332624Y-202248D01*
X1331751Y-205164D01*
X1331532Y-207789D01*
X1331969Y-210414D01*
X1332624Y-212164D01*
X1333934Y-213914D01*
X1335463Y-215081D01*
X1336991Y-215664D01*
X1338519D01*
X1340048Y-215081D01*
X1341358Y-214206D01*
X1342450Y-213040D01*
G01X1354491Y-215664D02*
Y-207789D01*
X1350124Y-198164D01*
G01X1358858D02*
X1354491Y-207789D01*
G01X1415691Y-198164D02*
X1413944Y-198747D01*
X1412634Y-200206D01*
X1411761Y-201955D01*
X1411106Y-204289D01*
X1410888Y-206914D01*
X1411106Y-209539D01*
X1411761Y-211873D01*
X1412634Y-213623D01*
X1413944Y-215081D01*
X1415691Y-215664D01*
X1417437Y-215081D01*
X1418748Y-213623D01*
X1419621Y-211873D01*
X1420276Y-209539D01*
X1420494Y-206914D01*
X1420276Y-204289D01*
X1419621Y-201955D01*
X1418748Y-200206D01*
X1417437Y-198747D01*
X1415691Y-198164D01*
G01X1429043Y-208373D02*
X1430571Y-206331D01*
X1431881Y-205164D01*
X1433628Y-204581D01*
X1435156Y-205164D01*
X1436248Y-206331D01*
X1437121Y-208081D01*
X1437339Y-210122D01*
X1437121Y-211873D01*
X1436248Y-213623D01*
X1434937Y-215081D01*
X1433409Y-215664D01*
X1431663Y-215081D01*
X1430134Y-213331D01*
X1429261Y-210706D01*
X1429043Y-207789D01*
X1429479Y-203998D01*
X1430134Y-201955D01*
X1431226Y-199914D01*
X1432754Y-198456D01*
X1434283Y-198164D01*
X1435811Y-198747D01*
X1436903Y-200206D01*
G01X1446761Y-216247D02*
X1454621Y-198164D01*
G01X1468191D02*
X1466444Y-198747D01*
X1465134Y-200206D01*
X1464261Y-201955D01*
X1463606Y-204289D01*
X1463388Y-206914D01*
X1463606Y-209539D01*
X1464261Y-211873D01*
X1465134Y-213623D01*
X1466444Y-215081D01*
X1468191Y-215664D01*
X1469937Y-215081D01*
X1471248Y-213623D01*
X1472121Y-211873D01*
X1472776Y-209539D01*
X1472994Y-206914D01*
X1472776Y-204289D01*
X1472121Y-201955D01*
X1471248Y-200206D01*
X1469937Y-198747D01*
X1468191Y-198164D01*
G01X1481979Y-213623D02*
X1483508Y-215081D01*
X1485254Y-215664D01*
X1487001Y-215081D01*
X1488529Y-213331D01*
X1489621Y-210706D01*
X1490058Y-208081D01*
Y-204873D01*
X1489621Y-202248D01*
X1488529Y-199914D01*
X1487219Y-198747D01*
X1485691Y-198164D01*
X1483944Y-198747D01*
X1482634Y-199914D01*
X1481761Y-201664D01*
X1481324Y-203998D01*
X1481761Y-206039D01*
X1482853Y-208081D01*
X1484163Y-209248D01*
X1485691Y-209539D01*
X1487437Y-208956D01*
X1488748Y-207497D01*
X1490058Y-204873D01*
G01X1499261Y-216247D02*
X1507121Y-198164D01*
G01X1516543Y-201081D02*
X1517853Y-199331D01*
X1519381Y-198456D01*
X1521128Y-198164D01*
X1523311Y-198747D01*
X1524839Y-200206D01*
X1525276Y-201955D01*
X1525058Y-203706D01*
X1524184Y-205164D01*
X1519818Y-208081D01*
X1517853Y-210122D01*
X1516543Y-213040D01*
X1516106Y-215664D01*
X1525276D01*
G01X1538191Y-198164D02*
X1536444Y-198747D01*
X1535134Y-200206D01*
X1534261Y-201955D01*
X1533606Y-204289D01*
X1533388Y-206914D01*
X1533606Y-209539D01*
X1534261Y-211873D01*
X1535134Y-213623D01*
X1536444Y-215081D01*
X1538191Y-215664D01*
X1539937Y-215081D01*
X1541248Y-213623D01*
X1542121Y-211873D01*
X1542776Y-209539D01*
X1542994Y-206914D01*
X1542776Y-204289D01*
X1542121Y-201955D01*
X1541248Y-200206D01*
X1539937Y-198747D01*
X1538191Y-198164D01*
G01X1555691Y-215664D02*
Y-198164D01*
X1553071Y-201664D01*
G01Y-215664D02*
X1558311D01*
G01X1572754D02*
X1573191Y-211873D01*
X1573846Y-208664D01*
X1574719Y-205747D01*
X1575811Y-202539D01*
X1577558Y-198164D01*
X1568824D01*
G01X1463388Y-170664D02*
Y-153164D01*
X1467754D01*
X1469501Y-154039D01*
X1470811Y-155206D01*
X1471903Y-156955D01*
X1472776Y-158998D01*
X1472994Y-161914D01*
X1472776Y-164831D01*
X1471903Y-166873D01*
X1470811Y-168623D01*
X1469501Y-169789D01*
X1467754Y-170664D01*
X1463388D01*
G01X1489621D02*
Y-158998D01*
G01Y-161039D02*
X1488748Y-159873D01*
X1487437Y-159289D01*
X1485909Y-158998D01*
X1484381Y-159581D01*
X1483071Y-160747D01*
X1482197Y-162497D01*
X1481761Y-164831D01*
X1482197Y-167164D01*
X1483071Y-168914D01*
X1484381Y-170081D01*
X1485909Y-170664D01*
X1487437Y-170372D01*
X1488748Y-169498D01*
X1489621Y-168331D01*
G01X1503191Y-153164D02*
Y-170664D01*
G01X1500134Y-158998D02*
X1506248D01*
G01X1517416Y-162789D02*
X1524403D01*
X1523748Y-160747D01*
X1522656Y-159581D01*
X1521128Y-158998D01*
X1519599Y-159289D01*
X1518289Y-160164D01*
X1517416Y-162206D01*
X1516979Y-163956D01*
Y-165706D01*
X1517416Y-167456D01*
X1518508Y-169206D01*
X1519818Y-170372D01*
X1521346Y-170664D01*
X1522874Y-170081D01*
X1524403Y-168331D01*
G54D12*
X67700Y91000D03*
X92200Y77000D03*
X60200Y65500D03*
X67700Y543500D03*
X92200Y529500D03*
X60200Y518000D03*
X89595Y905367D03*
X60200Y971000D03*
X92200Y982500D03*
X67700Y996500D03*
X187422Y467631D03*
X191700Y543500D03*
X184200Y518000D03*
X177008Y835918D03*
X184700Y971000D03*
X192200Y996500D03*
X188324Y1408800D03*
X117674Y1480400D03*
X129074Y1484200D03*
X218300Y57400D03*
X216200Y529500D03*
X216700Y982500D03*
X316200Y91000D03*
X340700Y77000D03*
X308700Y65500D03*
X316200Y543500D03*
X340700Y529500D03*
X308700Y518000D03*
Y971000D03*
X340700Y982500D03*
X316200Y996500D03*
X467200Y57500D03*
X440200Y543500D03*
X464700Y529500D03*
X432700Y518000D03*
Y971000D03*
X464700Y982500D03*
X440200Y996500D03*
X564700Y91000D03*
X557200Y65500D03*
X564700Y543500D03*
X557200Y518000D03*
Y971000D03*
X564700Y996500D03*
X510700Y1470500D03*
X528400Y1452100D03*
X528200Y1467000D03*
X589200Y77000D03*
Y529500D03*
Y982500D03*
X646895Y1425719D03*
X646995Y1441419D03*
X636200Y1464500D03*
X662000Y1468000D03*
X665200Y1444000D03*
X662000Y1464000D03*
Y1453500D03*
Y1457500D03*
X715700Y57400D03*
X688700Y543500D03*
X713200Y529500D03*
X681200Y518000D03*
Y971000D03*
X713200Y982500D03*
X688700Y996500D03*
X727200Y1453500D03*
X713700Y1443500D03*
X719700Y1458500D03*
Y1463000D03*
X684700Y1430000D03*
X692700D03*
X716700Y1438500D03*
X715800Y1475800D03*
X688200Y1476000D03*
X741432Y1466234D03*
X752932Y1465934D03*
X824690Y655190D03*
X818000Y772000D03*
Y781000D03*
X826200Y815000D03*
X827700Y893000D03*
X827587Y884453D03*
X946073Y556600D03*
X945788Y529107D03*
X946029Y551379D03*
X942927Y524023D03*
X874690Y647190D03*
Y655190D03*
X870500Y761000D03*
Y770000D03*
Y765500D03*
X878353Y807000D03*
X876200Y815000D03*
X912200Y782800D03*
X875700Y883000D03*
Y878500D03*
Y874000D03*
X933700Y875500D03*
X954438Y1412818D03*
Y1429318D03*
X963820Y770010D03*
Y774510D03*
X1029721Y830913D03*
X1004007Y903075D03*
X993597Y903465D03*
X1011481Y899075D03*
X1021739Y896965D03*
X1011200Y1117500D03*
X979200Y1201000D03*
Y1197000D03*
Y1209000D03*
Y1217000D03*
X1000143Y1417899D03*
X992143D03*
X1024143Y1426399D03*
X1021143Y1431399D03*
X1027143Y1451399D03*
Y1455899D03*
X1023950Y1496814D03*
X1045250Y1496914D03*
X972643Y1431899D03*
X968543Y1445399D03*
Y1441399D03*
X1057700Y824250D03*
Y814500D03*
Y837800D03*
Y828400D03*
X1078800Y1309495D03*
Y1304495D03*
Y1299375D03*
Y1292460D03*
X1105800Y1371200D03*
X1105812Y1391273D03*
X1105800Y1375200D03*
X1105812Y1383273D03*
X1196994Y918091D03*
X1196924Y912331D03*
X1210712Y1401814D03*
X1305000Y68900D03*
X1306800Y530000D03*
X1332700Y533500D03*
X1307800Y982200D03*
X1332700Y986000D03*
X1327350Y1408400D03*
X1263374Y1484900D03*
X1288074Y1480000D03*
X1274774Y1488600D03*
X1431300Y529900D03*
Y982400D03*
X1456700Y80500D03*
Y533500D03*
Y986000D03*
X1555400Y69300D03*
Y529800D03*
X1581200Y533500D03*
X1555700Y982600D03*
X1581200Y986000D03*
X1679600Y77000D03*
X1705200Y80500D03*
X1680000Y530100D03*
X1705200Y533500D03*
X1679600Y982300D03*
X1705200Y986000D03*
X1715576Y1408700D03*
X1656200Y1465000D03*
X1801100Y63200D03*
X1730191Y471049D03*
X1804000Y530100D03*
X1763200Y583500D03*
X1804595Y905367D03*
X1803700Y982200D03*
X1862500Y22300D03*
X1825600Y100800D03*
X1829200Y533500D03*
X1859200Y543500D03*
X1843200Y533500D03*
X1829200Y986000D03*
X1859200Y996500D03*
X1843200Y986500D03*
X1821226Y1470900D03*
G54D105*
X1328500Y554500D03*
Y549500D03*
Y544500D03*
Y539500D03*
X1308500D03*
Y544500D03*
Y549500D03*
Y554500D03*
X1328500Y1007000D03*
Y1002000D03*
Y997000D03*
Y992000D03*
X1308500D03*
Y997000D03*
Y1002000D03*
Y1007000D03*
X1432500Y86500D03*
Y91500D03*
Y96500D03*
Y101500D03*
Y539500D03*
Y544500D03*
Y549500D03*
Y554500D03*
Y992000D03*
Y997000D03*
Y1002000D03*
Y1007000D03*
X1452500Y91500D03*
Y86500D03*
Y101500D03*
Y96500D03*
Y554500D03*
Y549500D03*
Y544500D03*
Y539500D03*
Y1007000D03*
Y1002000D03*
Y997000D03*
Y992000D03*
X1570400Y126000D03*
Y131000D03*
Y136000D03*
Y141000D03*
X1590400D03*
Y136000D03*
Y131000D03*
Y126000D03*
X1577000Y554500D03*
Y549500D03*
Y544500D03*
Y539500D03*
X1557000D03*
Y544500D03*
Y549500D03*
Y554500D03*
X1577000Y1007000D03*
Y1002000D03*
Y997000D03*
Y992000D03*
X1557000D03*
Y997000D03*
Y1002000D03*
Y1007000D03*
X1701000Y91500D03*
Y86500D03*
X1681000D03*
Y91500D03*
X1701000Y101500D03*
Y96500D03*
X1681000D03*
Y101500D03*
X1701000Y554500D03*
Y549500D03*
Y544500D03*
Y539500D03*
X1681000D03*
Y544500D03*
Y549500D03*
Y554500D03*
X1701000Y1007000D03*
Y1002000D03*
Y997000D03*
Y992000D03*
X1681000D03*
Y997000D03*
Y1002000D03*
Y1007000D03*
X1805000Y539500D03*
Y544500D03*
Y549500D03*
Y554500D03*
Y992000D03*
Y997000D03*
Y1002000D03*
Y1007000D03*
X1825000Y554500D03*
Y549500D03*
Y544500D03*
Y539500D03*
Y1007000D03*
Y1002000D03*
Y997000D03*
Y992000D03*
G54D21*
X66500Y65000D03*
Y74000D03*
Y517500D03*
Y526500D03*
Y970500D03*
Y979500D03*
X190500Y517500D03*
Y526500D03*
X191000Y970500D03*
Y979500D03*
X174374Y1410900D03*
Y1401900D03*
X315000Y65000D03*
Y74000D03*
Y517500D03*
Y526500D03*
Y970500D03*
Y979500D03*
X439000Y517500D03*
Y526500D03*
Y970500D03*
Y979500D03*
X563500Y65000D03*
Y74000D03*
Y517500D03*
Y526500D03*
Y970500D03*
Y979500D03*
X687500Y517500D03*
Y526500D03*
Y970500D03*
Y979500D03*
X1317900Y59900D03*
Y68900D03*
X1313500Y1410900D03*
Y1401900D03*
X1570000Y60000D03*
Y69000D03*
X1701626Y1410900D03*
Y1401900D03*
X1868800Y22300D03*
Y31300D03*
X1849500Y533000D03*
Y542000D03*
Y986000D03*
Y995000D03*
G54D30*
X60300Y100500D03*
Y553000D03*
Y1006000D03*
X184300Y553000D03*
X140800Y579000D03*
X111256Y878062D03*
X140800Y1032000D03*
X184800Y1006000D03*
X198800Y82500D03*
X209083Y440326D03*
X264800Y579000D03*
X264500Y1032000D03*
X226955Y1434029D03*
X308800Y100500D03*
Y553000D03*
Y1006000D03*
X432800Y553000D03*
X389300Y579000D03*
Y1032000D03*
X432800Y1006000D03*
X557300Y100500D03*
Y553000D03*
X513300Y579000D03*
Y1032000D03*
X557300Y1006000D03*
X637800Y579000D03*
Y1032000D03*
X695800Y82500D03*
X751800Y126500D03*
X681300Y553000D03*
Y1006000D03*
X753100Y1032000D03*
X695800Y1476000D03*
X714300Y1449700D03*
X840790Y645690D03*
X838500Y804500D03*
X870600Y774500D03*
X931300Y763820D03*
X871300Y887500D03*
X877000Y1188400D03*
X900100Y1191700D03*
X981681Y559671D03*
X980247Y533383D03*
X1011641Y895045D03*
X1021933Y892965D03*
X968100Y1193500D03*
X1334300Y113500D03*
X1335300Y566500D03*
Y1019000D03*
X1435800Y81000D03*
X1374029Y1434045D03*
X1459300Y113500D03*
Y566500D03*
Y1019000D03*
X1604700Y133000D03*
X1583800Y566500D03*
Y1019000D03*
X1683200Y81000D03*
X1707800Y113500D03*
Y566500D03*
Y1019000D03*
X1751852Y443744D03*
X1754174Y1434109D03*
X1881800Y81500D03*
X1866300Y82000D03*
X1867500Y42100D03*
X1830800Y113500D03*
X1831800Y566500D03*
X1879700Y534600D03*
X1851800Y553000D03*
X1826256Y878062D03*
X1831800Y1019000D03*
X1851800Y1006000D03*
G54D115*
G01X126709Y59919D02*
X125405D01*
X124880Y59394D01*
X124463D01*
X123963Y59894D01*
Y60819D01*
X123463Y61319D01*
X118209D01*
G01X126709Y57719D02*
X125405D01*
X124880Y58244D01*
X124463D01*
X123963Y57744D01*
Y56819D01*
X123463Y56319D01*
X118209D01*
G01Y71319D02*
X123463D01*
X123963Y71819D01*
Y72744D01*
X124463Y73244D01*
X127488D01*
G02X127988Y72744I0J-500D01*
G01Y71319D01*
G01X118209Y76319D02*
X123463D01*
X123963Y75819D01*
Y74894D01*
X124463Y74394D01*
X127488D01*
G03X127988Y74894I0J500D01*
G01Y76319D01*
G01X128909Y59919D02*
X130406D01*
X130731Y59594D01*
X134357D01*
G03X134983Y60220I0J626D01*
G01Y61269D01*
G01X128909Y57719D02*
X130468D01*
X131193Y58444D01*
X134357D01*
G02X134983Y57818I0J-626D01*
G01Y56769D01*
G01X126709Y512675D02*
X125405D01*
X124880Y512150D01*
X124463D01*
X123963Y512650D01*
Y513575D01*
X123463Y514075D01*
X118209D01*
G01X126709Y510475D02*
X125405D01*
X124880Y511000D01*
X124463D01*
X123963Y510500D01*
Y509575D01*
X123463Y509075D01*
X118209D01*
G01Y524075D02*
X123463D01*
X123963Y524575D01*
Y525500D01*
X124463Y526000D01*
X127488D01*
G02X127988Y525500I0J-500D01*
G01Y524075D01*
G01X118209Y529075D02*
X123463D01*
X123963Y528575D01*
Y527650D01*
X124463Y527150D01*
X127488D01*
G03X127988Y527650I0J500D01*
G01Y529075D01*
G01X128909Y512675D02*
X130406D01*
X130731Y512350D01*
X134357D01*
G03X134983Y512976I0J626D01*
G01Y514025D01*
G01X128909Y510475D02*
X130468D01*
X131193Y511200D01*
X134357D01*
G02X134983Y510574I0J-626D01*
G01Y509525D01*
G01X126709Y965431D02*
X125405D01*
X124880Y964906D01*
X124463D01*
X123963Y965406D01*
Y966331D01*
X123463Y966831D01*
X118209D01*
G01X126709Y963231D02*
X125405D01*
X124880Y963756D01*
X124463D01*
X123963Y963256D01*
Y962331D01*
X123463Y961831D01*
X118209D01*
G01Y976831D02*
X123463D01*
X123963Y977331D01*
Y978256D01*
X124463Y978756D01*
X127488D01*
G02X127988Y978256I0J-500D01*
G01Y976831D01*
G01X118209Y981831D02*
X123463D01*
X123963Y981331D01*
Y980406D01*
X124463Y979906D01*
X127488D01*
G03X127988Y980406I0J500D01*
G01Y981831D01*
G01X128909Y965431D02*
X130406D01*
X130731Y965106D01*
X134357D01*
G03X134983Y965732I0J626D01*
G01Y966781D01*
G01X128909Y963231D02*
X130468D01*
X131193Y963956D01*
X134357D01*
G02X134983Y963330I0J-626D01*
G01Y962281D01*
G01X250921Y59919D02*
X249617D01*
X249092Y59394D01*
X248675D01*
X248175Y59894D01*
Y60819D01*
X247675Y61319D01*
X242421D01*
G01X250921Y57719D02*
X249617D01*
X249092Y58244D01*
X248675D01*
X248175Y57744D01*
Y56819D01*
X247675Y56319D01*
X242421D01*
G01Y71319D02*
X247675D01*
X248175Y71819D01*
Y72744D01*
X248675Y73244D01*
X251700D01*
G02X252200Y72744I0J-500D01*
G01Y71319D01*
G01X242421Y76319D02*
X247675D01*
X248175Y75819D01*
Y74894D01*
X248675Y74394D01*
X251700D01*
G03X252200Y74894I0J500D01*
G01Y76319D01*
G01X253121Y59919D02*
X254618D01*
X254943Y59594D01*
X258569D01*
G03X259195Y60220I0J626D01*
G01Y61269D01*
G01X253121Y57719D02*
X254680D01*
X255405Y58444D01*
X258569D01*
G02X259195Y57818I0J-626D01*
G01Y56769D01*
G01X250921Y512675D02*
X249617D01*
X249092Y512150D01*
X248675D01*
X248175Y512650D01*
Y513575D01*
X247675Y514075D01*
X242421D01*
G01X250921Y510475D02*
X249617D01*
X249092Y511000D01*
X248675D01*
X248175Y510500D01*
Y509575D01*
X247675Y509075D01*
X242421D01*
G01Y524075D02*
X247675D01*
X248175Y524575D01*
Y525500D01*
X248675Y526000D01*
X251700D01*
G02X252200Y525500I0J-500D01*
G01Y524075D01*
G01X242421Y529075D02*
X247675D01*
X248175Y528575D01*
Y527525D01*
X248550Y527150D01*
X251700D01*
G03X252200Y527650I0J500D01*
G01Y529075D01*
G01X253121Y512675D02*
X254618D01*
X254943Y512350D01*
X258569D01*
G03X259195Y512976I0J626D01*
G01Y514025D01*
G01X253121Y510475D02*
X254680D01*
X255405Y511200D01*
X258569D01*
G02X259195Y510574I0J-626D01*
G01Y509525D01*
G01X250921Y965431D02*
X249617D01*
X249092Y964906D01*
X248675D01*
X248175Y965406D01*
Y966331D01*
X247675Y966831D01*
X242421D01*
G01X250921Y963231D02*
X249617D01*
X249092Y963756D01*
X248675D01*
X248175Y963256D01*
Y962331D01*
X247675Y961831D01*
X242421D01*
G01Y976831D02*
X247675D01*
X248175Y977331D01*
Y978175D01*
X248756Y978756D01*
X251700D01*
G02X252200Y978256I0J-500D01*
G01Y976831D01*
G01X242421Y981831D02*
X247675D01*
X248175Y981331D01*
Y980406D01*
X248675Y979906D01*
X251700D01*
G03X252200Y980406I0J500D01*
G01Y981831D01*
G01X253121Y965431D02*
X254618D01*
X254943Y965106D01*
X258569D01*
G03X259195Y965732I0J626D01*
G01Y966781D01*
G01X253121Y963231D02*
X254680D01*
X255405Y963956D01*
X258569D01*
G02X259195Y963330I0J-626D01*
G01Y962281D01*
G01X375134Y59919D02*
X373830D01*
X373305Y59394D01*
X372888D01*
X372388Y59894D01*
Y60819D01*
X371888Y61319D01*
X366634D01*
G01X375134Y57719D02*
X373830D01*
X373305Y58244D01*
X372888D01*
X372388Y57744D01*
Y56819D01*
X371888Y56319D01*
X366634D01*
G01Y71319D02*
X371819D01*
X372388Y71888D01*
Y72744D01*
X372888Y73244D01*
X375913D01*
G02X376413Y72744I0J-500D01*
G01Y71319D01*
G01X366634Y76319D02*
X371981D01*
X372388Y75912D01*
Y74894D01*
X372888Y74394D01*
X375913D01*
G03X376413Y74894I0J500D01*
G01Y76319D01*
G01X377334Y59919D02*
X378831D01*
X379156Y59594D01*
X382782D01*
G03X383408Y60220I0J626D01*
G01Y61269D01*
G01X377334Y57719D02*
X378893D01*
X379618Y58444D01*
X382782D01*
G02X383408Y57818I0J-626D01*
G01Y56769D01*
G01X375134Y512675D02*
X373830D01*
X373305Y512150D01*
X372888D01*
X372388Y512650D01*
Y513575D01*
X371888Y514075D01*
X366634D01*
G01X375134Y510475D02*
X373830D01*
X373305Y511000D01*
X372888D01*
X372388Y510500D01*
Y509575D01*
X371888Y509075D01*
X366634D01*
G01Y524075D02*
X371888D01*
X372388Y524575D01*
Y525500D01*
X372888Y526000D01*
X375913D01*
G02X376413Y525500I0J-500D01*
G01Y524075D01*
G01X366634Y529075D02*
X371888D01*
X372388Y528575D01*
Y527650D01*
X372888Y527150D01*
X375913D01*
G03X376413Y527650I0J500D01*
G01Y529075D01*
G01X377334Y512675D02*
X378831D01*
X379156Y512350D01*
X382782D01*
G03X383408Y512976I0J626D01*
G01Y514025D01*
G01X377334Y510475D02*
X378893D01*
X379618Y511200D01*
X382782D01*
G02X383408Y510574I0J-626D01*
G01Y509525D01*
G01X375134Y965431D02*
X373830D01*
X373305Y964906D01*
X372888D01*
X372388Y965406D01*
Y966331D01*
X371888Y966831D01*
X366634D01*
G01X375134Y963231D02*
X373830D01*
X373305Y963756D01*
X372888D01*
X372388Y963256D01*
Y962331D01*
X371888Y961831D01*
X366634D01*
G01Y976831D02*
X371888D01*
X372388Y977331D01*
Y978256D01*
X372888Y978756D01*
X375913D01*
G02X376413Y978256I0J-500D01*
G01Y976831D01*
G01X366634Y981831D02*
X371888D01*
X372388Y981331D01*
Y980406D01*
X372888Y979906D01*
X375913D01*
G03X376413Y980406I0J500D01*
G01Y981831D01*
G01X377334Y965431D02*
X378831D01*
X379156Y965106D01*
X382782D01*
G03X383408Y965732I0J626D01*
G01Y966781D01*
G01X377334Y963231D02*
X378893D01*
X379618Y963956D01*
X382782D01*
G02X383408Y963330I0J-626D01*
G01Y962281D01*
G01X499346Y59919D02*
X498042D01*
X497517Y59394D01*
X497100D01*
X496600Y59894D01*
Y60819D01*
X496100Y61319D01*
X490846D01*
G01X499346Y57719D02*
X498042D01*
X497517Y58244D01*
X497100D01*
X496600Y57744D01*
Y56819D01*
X496100Y56319D01*
X490846D01*
G01Y71319D02*
X496100D01*
X496600Y71819D01*
Y72744D01*
X497100Y73244D01*
X500125D01*
G02X500625Y72744I0J-500D01*
G01Y71319D01*
G01X490846Y76319D02*
X496100D01*
X496600Y75819D01*
Y74894D01*
X497100Y74394D01*
X500125D01*
G03X500625Y74894I0J500D01*
G01Y76319D01*
G01X501546Y59919D02*
X503043D01*
X503368Y59594D01*
X506994D01*
G03X507620Y60220I0J626D01*
G01Y61269D01*
G01X501546Y57719D02*
X503105D01*
X503830Y58444D01*
X506994D01*
G02X507620Y57818I0J-626D01*
G01Y56769D01*
G01X499346Y512675D02*
X498042D01*
X497517Y512150D01*
X497100D01*
X496600Y512650D01*
Y513575D01*
X496100Y514075D01*
X490846D01*
G01X499346Y510475D02*
X498042D01*
X497517Y511000D01*
X497100D01*
X496600Y510500D01*
Y509575D01*
X496100Y509075D01*
X490846D01*
G01Y524075D02*
X496100D01*
X496600Y524575D01*
Y525500D01*
X497100Y526000D01*
X500125D01*
G02X500625Y525500I0J-500D01*
G01Y524075D01*
G01X490846Y529075D02*
X496100D01*
X496600Y528575D01*
Y527650D01*
X497100Y527150D01*
X500125D01*
G03X500625Y527650I0J500D01*
G01Y529075D01*
G01X501546Y512675D02*
X503043D01*
X503368Y512350D01*
X506994D01*
G03X507620Y512976I0J626D01*
G01Y514025D01*
G01X501546Y510475D02*
X503105D01*
X503830Y511200D01*
X506994D01*
G02X507620Y510574I0J-626D01*
G01Y509525D01*
G01X499346Y965431D02*
X498042D01*
X497517Y964906D01*
X497100D01*
X496600Y965406D01*
Y966331D01*
X496100Y966831D01*
X490846D01*
G01X499346Y963231D02*
X498042D01*
X497517Y963756D01*
X497100D01*
X496600Y963256D01*
Y962331D01*
X496100Y961831D01*
X490846D01*
G01Y976831D02*
X496100D01*
X496600Y977331D01*
Y978256D01*
X497100Y978756D01*
X500125D01*
G02X500625Y978256I0J-500D01*
G01Y976831D01*
G01X490846Y981831D02*
X496100D01*
X496600Y981331D01*
Y980406D01*
X497100Y979906D01*
X500125D01*
G03X500625Y980406I0J500D01*
G01Y981831D01*
G01X501546Y965431D02*
X503043D01*
X503368Y965106D01*
X506994D01*
G03X507620Y965732I0J626D01*
G01Y966781D01*
G01X501546Y963231D02*
X503105D01*
X503830Y963956D01*
X506994D01*
G02X507620Y963330I0J-626D01*
G01Y962281D01*
G01X623559Y59919D02*
X622255D01*
X621730Y59394D01*
X621313D01*
X620813Y59894D01*
Y60819D01*
X620313Y61319D01*
X615059D01*
G01X623559Y57719D02*
X622255D01*
X621730Y58244D01*
X621313D01*
X620813Y57744D01*
Y56819D01*
X620313Y56319D01*
X615059D01*
G01Y71319D02*
X620313D01*
X620813Y71819D01*
Y72744D01*
X621313Y73244D01*
X624338D01*
G02X624838Y72744I0J-500D01*
G01Y71319D01*
G01X615059Y76319D02*
X620313D01*
X620813Y75819D01*
Y74894D01*
X621313Y74394D01*
X624338D01*
G03X624838Y74894I0J500D01*
G01Y76319D01*
G01X625759Y59919D02*
X627256D01*
X627581Y59594D01*
X631207D01*
G03X631833Y60220I0J626D01*
G01Y61269D01*
G01X625759Y57719D02*
X627318D01*
X628043Y58444D01*
X631207D01*
G02X631833Y57818I0J-626D01*
G01Y56769D01*
G01X623559Y512675D02*
X622255D01*
X621730Y512150D01*
X621313D01*
X620813Y512650D01*
Y513575D01*
X620313Y514075D01*
X615059D01*
G01X623559Y510475D02*
X622255D01*
X621730Y511000D01*
X621313D01*
X620813Y510500D01*
Y509575D01*
X620313Y509075D01*
X615059D01*
G01Y524075D02*
X620313D01*
X620813Y524575D01*
Y525500D01*
X621313Y526000D01*
X624338D01*
G02X624838Y525500I0J-500D01*
G01Y524075D01*
G01X615059Y529075D02*
X620325D01*
X620800Y528600D01*
Y527600D01*
X621250Y527150D01*
X624338D01*
G03X624838Y527650I0J500D01*
G01Y529075D01*
G01X625759Y512675D02*
X627256D01*
X627581Y512350D01*
X631207D01*
G03X631833Y512976I0J626D01*
G01Y514025D01*
G01X625759Y510475D02*
X627318D01*
X628043Y511200D01*
X631207D01*
G02X631833Y510574I0J-626D01*
G01Y509525D01*
G01X623559Y965431D02*
X622255D01*
X621730Y964906D01*
X621313D01*
X620813Y965406D01*
Y966331D01*
X620313Y966831D01*
X615059D01*
G01X623559Y963231D02*
X622255D01*
X621730Y963756D01*
X621313D01*
X620813Y963256D01*
Y962331D01*
X620313Y961831D01*
X615059D01*
G01Y976831D02*
X620313D01*
X620813Y977331D01*
Y978256D01*
X621313Y978756D01*
X624338D01*
G02X624838Y978256I0J-500D01*
G01Y976831D01*
G01X615059Y981831D02*
X620313D01*
X620800Y981344D01*
Y980419D01*
X621313Y979906D01*
X624338D01*
G03X624838Y980406I0J500D01*
G01Y981831D01*
G01X625759Y965431D02*
X627256D01*
X627581Y965106D01*
X631207D01*
G03X631833Y965732I0J626D01*
G01Y966781D01*
G01X625759Y963231D02*
X627318D01*
X628043Y963956D01*
X631207D01*
G02X631833Y963330I0J-626D01*
G01Y962281D01*
G01X747772Y59919D02*
X746468D01*
X745943Y59394D01*
X745526D01*
X745026Y59894D01*
Y60819D01*
X744526Y61319D01*
X739272D01*
G01X747772Y57719D02*
X746468D01*
X745943Y58244D01*
X745526D01*
X745026Y57744D01*
Y56819D01*
X744526Y56319D01*
X739272D01*
G01Y71319D02*
X744526D01*
X745026Y71819D01*
Y72744D01*
X745526Y73244D01*
X748551D01*
G02X749051Y72744I0J-500D01*
G01Y71319D01*
G01X739272Y76319D02*
X744526D01*
X745026Y75819D01*
Y74774D01*
X745406Y74394D01*
X748551D01*
G03X749051Y74894I0J500D01*
G01Y76319D01*
G01X749972Y59919D02*
X751469D01*
X751794Y59594D01*
X755420D01*
G03X756046Y60220I0J626D01*
G01Y61269D01*
G01X749972Y57719D02*
X751531D01*
X752256Y58444D01*
X755420D01*
G02X756046Y57818I0J-626D01*
G01Y56769D01*
G01X747772Y512675D02*
X746468D01*
X745943Y512150D01*
X745526D01*
X745026Y512650D01*
Y513575D01*
X744526Y514075D01*
X739272D01*
G01X747772Y510475D02*
X746468D01*
X745943Y511000D01*
X745526D01*
X745026Y510500D01*
Y509575D01*
X744526Y509075D01*
X739272D01*
G01Y524075D02*
X744526D01*
X745026Y524575D01*
Y525500D01*
X745526Y526000D01*
X748551D01*
G02X749051Y525500I0J-500D01*
G01Y524075D01*
G01X739272Y529075D02*
X744526D01*
X745026Y528575D01*
Y527650D01*
X745526Y527150D01*
X748551D01*
G03X749051Y527650I0J500D01*
G01Y529075D01*
G01X749972Y512675D02*
X751469D01*
X751794Y512350D01*
X755420D01*
G03X756046Y512976I0J626D01*
G01Y514025D01*
G01X749972Y510475D02*
X751531D01*
X752256Y511200D01*
X755420D01*
G02X756046Y510574I0J-626D01*
G01Y509525D01*
G01X747772Y965431D02*
X746468D01*
X745943Y964906D01*
X745526D01*
X745026Y965406D01*
Y966331D01*
X744526Y966831D01*
X739272D01*
G01X747772Y963231D02*
X746468D01*
X745943Y963756D01*
X745526D01*
X745026Y963256D01*
Y962331D01*
X744526Y961831D01*
X739272D01*
G01Y976831D02*
X744526D01*
X745026Y977331D01*
Y978256D01*
X745526Y978756D01*
X748551D01*
G02X749051Y978256I0J-500D01*
G01Y976831D01*
G01X739272Y981831D02*
X744526D01*
X745026Y981331D01*
Y980274D01*
X745394Y979906D01*
X748551D01*
G03X749051Y980406I0J500D01*
G01Y981831D01*
G01X749972Y965431D02*
X751469D01*
X751794Y965106D01*
X755420D01*
G03X756046Y965732I0J626D01*
G01Y966781D01*
G01X749972Y963231D02*
X751531D01*
X752256Y963956D01*
X755420D01*
G02X756046Y963330I0J-626D01*
G01Y962281D01*
G01X1267378Y59919D02*
X1268825D01*
X1269350Y59394D01*
X1282624D01*
X1283124Y59894D01*
Y60819D01*
X1283624Y61319D01*
X1288878D01*
G01X1267378Y57719D02*
X1268793D01*
X1269318Y58244D01*
X1282624D01*
X1283124Y57744D01*
Y56819D01*
X1283624Y56319D01*
X1288878D01*
G01Y71319D02*
X1283624D01*
X1283124Y71819D01*
Y72744D01*
X1282764Y73104D01*
X1274454D01*
X1273475Y72125D01*
Y69325D01*
G03X1274150Y68650I675J0D01*
G01X1275400D01*
G01X1288878Y76319D02*
X1283624D01*
X1283124Y75819D01*
Y74894D01*
X1282484Y74254D01*
X1273977D01*
X1272325Y72602D01*
Y69325D01*
G02X1271650Y68650I-675J0D01*
G01X1270400D01*
G01X1265178Y59919D02*
X1263874D01*
X1263249Y59294D01*
X1260017D01*
X1258425Y57702D01*
Y54325D01*
G02X1257750Y53650I-675J0D01*
G01X1256750D01*
G01X1265178Y57719D02*
X1263874D01*
X1263449Y58144D01*
X1260494D01*
X1259575Y57225D01*
Y54325D01*
G03X1260250Y53650I675J0D01*
G01X1261250D01*
G01X1267378Y512675D02*
X1269722D01*
X1270253Y512144D01*
X1282618D01*
X1283124Y512650D01*
Y513575D01*
X1283624Y514075D01*
X1288878D01*
G01X1267378Y510475D02*
X1269900D01*
X1270419Y510994D01*
X1282630D01*
X1283124Y510500D01*
Y509575D01*
X1283624Y509075D01*
X1288878D01*
G01Y524075D02*
X1283624D01*
X1283124Y524575D01*
Y525376D01*
X1282500Y526000D01*
X1274594D01*
X1273475Y524881D01*
Y522125D01*
G03X1274194Y521406I719J0D01*
G01X1275400D01*
G01X1288878Y529075D02*
X1283575D01*
X1283124Y528624D01*
Y527650D01*
X1282624Y527150D01*
X1274117D01*
X1272325Y525358D01*
Y522125D01*
G02X1271606Y521406I-719J0D01*
G01X1270400D01*
G01X1265178Y512675D02*
X1263874D01*
X1263214Y512015D01*
X1259982D01*
X1258425Y510458D01*
Y507025D01*
G02X1257806Y506406I-619J0D01*
G01X1256750D01*
G01X1265178Y510475D02*
X1263874D01*
X1263484Y510865D01*
X1260459D01*
X1259575Y509981D01*
Y507025D01*
G03X1260194Y506406I619J0D01*
G01X1261250D01*
G01X1267378Y965431D02*
X1268869D01*
X1269394Y964906D01*
X1282624D01*
X1283124Y965406D01*
Y966331D01*
X1283624Y966831D01*
X1288878D01*
G01X1267378Y963231D02*
X1269031D01*
X1269556Y963756D01*
X1282624D01*
X1283124Y963256D01*
Y962331D01*
X1283624Y961831D01*
X1288878D01*
G01Y976831D02*
X1283624D01*
X1283124Y977331D01*
Y978256D01*
X1282624Y978756D01*
X1274475D01*
G03X1273975Y978256I0J-500D01*
G01Y976831D01*
G01X1288878Y981831D02*
X1283624D01*
X1283124Y981331D01*
Y980524D01*
X1282506Y979906D01*
X1274475D01*
G02X1273975Y980406I0J500D01*
G01Y981831D01*
G01X1265178Y965431D02*
X1263874D01*
X1263129Y964686D01*
X1258190D01*
G02X1257490Y965386I0J700D01*
G01Y966361D01*
G01X1265178Y963231D02*
X1263874D01*
X1263569Y963536D01*
X1258190D01*
G03X1257490Y962836I0J-700D01*
G01Y961861D01*
G01X1391591Y59919D02*
X1393025D01*
X1393550Y59394D01*
X1406837D01*
X1407337Y59894D01*
Y60819D01*
X1407837Y61319D01*
X1413091D01*
G01X1391591Y57719D02*
X1393097D01*
X1393622Y58244D01*
X1406837D01*
X1407337Y57744D01*
Y56819D01*
X1407837Y56319D01*
X1413091D01*
G01Y71319D02*
X1407837D01*
X1407337Y71819D01*
Y72744D01*
X1406937Y73144D01*
X1398707D01*
X1397688Y72125D01*
Y69338D01*
G03X1398376Y68650I688J0D01*
G01X1399613D01*
G01X1413091Y76319D02*
X1407837D01*
X1407337Y75819D01*
Y74894D01*
X1406737Y74294D01*
X1398230D01*
X1396538Y72602D01*
Y69338D01*
G02X1395850Y68650I-688J0D01*
G01X1394613D01*
G01X1389391Y59919D02*
X1388087D01*
X1387305Y59137D01*
X1384073D01*
X1382638Y57702D01*
Y54338D01*
G02X1381950Y53650I-688J0D01*
G01X1380963D01*
G01X1389391Y57719D02*
X1388087D01*
X1387819Y57987D01*
X1384550D01*
X1383788Y57225D01*
Y54338D01*
G03X1384476Y53650I688J0D01*
G01X1385463D01*
G01X1391591Y512675D02*
X1393275D01*
X1393800Y512150D01*
X1406837D01*
X1407337Y512650D01*
Y513575D01*
X1407837Y514075D01*
X1413091D01*
G01X1391591Y510475D02*
X1393500D01*
X1394025Y511000D01*
X1406837D01*
X1407337Y510500D01*
Y509575D01*
X1407837Y509075D01*
X1413091D01*
G01Y524075D02*
X1407837D01*
X1407337Y524575D01*
Y525500D01*
X1406849Y525988D01*
X1398795D01*
X1397688Y524881D01*
Y522138D01*
G03X1398420Y521406I732J0D01*
G01X1399613D01*
G01X1413091Y529075D02*
X1407837D01*
X1407337Y528575D01*
Y527537D01*
X1406938Y527138D01*
X1398318D01*
X1396538Y525358D01*
Y522138D01*
G02X1395806Y521406I-732J0D01*
G01X1394613D01*
G01X1389391Y512675D02*
X1388087D01*
X1387432Y512020D01*
X1384200D01*
X1382638Y510458D01*
Y507038D01*
G02X1382006Y506406I-632J0D01*
G01X1380963D01*
G01X1389391Y510475D02*
X1388087D01*
X1387692Y510870D01*
X1384677D01*
X1383788Y509981D01*
Y507038D01*
G03X1384420Y506406I632J0D01*
G01X1385463D01*
G01X1391591Y965431D02*
X1393069D01*
X1393594Y964906D01*
X1406837D01*
X1407337Y965406D01*
Y966331D01*
X1407837Y966831D01*
X1413091D01*
G01X1391591Y963231D02*
X1393031D01*
X1393556Y963756D01*
X1406837D01*
X1407337Y963256D01*
Y962331D01*
X1407837Y961831D01*
X1413091D01*
G01Y976831D02*
X1407837D01*
X1407337Y977331D01*
Y978256D01*
X1406837Y978756D01*
X1398688D01*
G03X1398188Y978256I0J-500D01*
G01Y976831D01*
G01X1413091Y981831D02*
X1407837D01*
X1407337Y981331D01*
Y980537D01*
X1406706Y979906D01*
X1398688D01*
G02X1398188Y980406I0J500D01*
G01Y981831D01*
G01X1389391Y965431D02*
X1388087D01*
X1387362Y964706D01*
X1382350D01*
G02X1381663Y965393I0J687D01*
G01Y966381D01*
G01X1389391Y963231D02*
X1388087D01*
X1387762Y963556D01*
X1382350D01*
G03X1381663Y962869I0J-687D01*
G01Y961881D01*
G01X1515803Y59919D02*
X1517350D01*
X1517875Y59394D01*
X1531049D01*
X1531549Y59894D01*
Y60819D01*
X1532049Y61319D01*
X1537303D01*
G01X1515803Y57719D02*
X1517252D01*
X1517777Y58244D01*
X1531049D01*
X1531549Y57744D01*
Y56819D01*
X1532049Y56319D01*
X1537303D01*
G01Y71319D02*
X1532049D01*
X1531549Y71819D01*
Y72744D01*
X1531049Y73244D01*
X1523019D01*
X1521900Y72125D01*
Y69288D01*
G03X1522538Y68650I638J0D01*
G01X1523825D01*
G01X1537303Y76319D02*
X1531919D01*
X1531549Y75949D01*
Y74849D01*
X1531094Y74394D01*
X1522542D01*
X1520750Y72602D01*
Y69288D01*
G02X1520112Y68650I-638J0D01*
G01X1518825D01*
G01X1513603Y59919D02*
X1512299D01*
X1511424Y59044D01*
X1508192D01*
X1506850Y57702D01*
Y54250D01*
G02X1506250Y53650I-600J0D01*
G01X1505175D01*
G01X1513603Y57719D02*
X1512299D01*
X1512124Y57894D01*
X1508669D01*
X1508000Y57225D01*
Y54250D01*
G03X1508600Y53650I600J0D01*
G01X1509675D01*
G01X1515803Y512675D02*
X1517236D01*
X1517761Y512150D01*
X1531049D01*
X1531549Y512650D01*
Y513575D01*
X1532049Y514075D01*
X1537303D01*
G01X1515803Y510475D02*
X1517265D01*
X1517790Y511000D01*
X1531049D01*
X1531549Y510500D01*
Y509575D01*
X1532049Y509075D01*
X1537303D01*
G01Y524075D02*
X1532049D01*
X1531549Y524575D01*
Y525500D01*
X1531139Y525910D01*
X1522929D01*
X1521900Y524881D01*
Y522050D01*
G03X1522544Y521406I644J0D01*
G01X1523825D01*
G01X1537303Y529075D02*
X1532049D01*
X1531549Y528575D01*
Y527650D01*
X1530959Y527060D01*
X1522452D01*
X1520750Y525358D01*
Y522050D01*
G02X1520106Y521406I-644J0D01*
G01X1518825D01*
G01X1513603Y512675D02*
X1512299D01*
X1511660Y512036D01*
X1508428D01*
X1506850Y510458D01*
Y507050D01*
G02X1506206Y506406I-644J0D01*
G01X1505175D01*
G01X1513603Y510475D02*
X1512299D01*
X1511888Y510886D01*
X1508905D01*
X1508000Y509981D01*
Y507050D01*
G03X1508644Y506406I644J0D01*
G01X1509675D01*
G01X1515803Y965431D02*
X1517269D01*
X1517794Y964906D01*
X1531049D01*
X1531549Y965406D01*
Y966331D01*
X1532049Y966831D01*
X1537303D01*
G01X1515803Y963231D02*
X1517331D01*
X1517856Y963756D01*
X1531049D01*
X1531549Y963256D01*
Y962331D01*
X1532049Y961831D01*
X1537303D01*
G01Y976831D02*
X1531969D01*
X1531549Y977251D01*
Y978256D01*
X1531049Y978756D01*
X1522900D01*
G03X1522400Y978256I0J-500D01*
G01Y976831D01*
G01X1537303Y981831D02*
X1532049D01*
X1531549Y981331D01*
Y980449D01*
X1531006Y979906D01*
X1522900D01*
G02X1522400Y980406I0J500D01*
G01Y981831D01*
G01X1513603Y965431D02*
X1512299D01*
X1511514Y964646D01*
X1506650D01*
G02X1505875Y965421I0J775D01*
G01Y966321D01*
G01X1513603Y963231D02*
X1512299D01*
X1512034Y963496D01*
X1506650D01*
G03X1505875Y962721I0J-775D01*
G01Y961821D01*
G01X1640016Y59919D02*
X1641481D01*
X1642006Y59394D01*
X1655262D01*
X1655762Y59894D01*
Y60819D01*
X1656262Y61319D01*
X1661516D01*
G01X1640016Y57719D02*
X1641419D01*
X1641944Y58244D01*
X1655262D01*
X1655762Y57744D01*
Y56819D01*
X1656262Y56319D01*
X1661516D01*
G01Y71319D02*
X1656262D01*
X1655762Y71819D01*
Y72744D01*
X1655362Y73144D01*
X1647344D01*
X1646113Y71913D01*
Y69288D01*
G03X1646751Y68650I638J0D01*
G01X1648038D01*
G01X1661516Y76319D02*
X1656262D01*
X1655762Y75819D01*
Y74894D01*
X1655162Y74294D01*
X1646867D01*
X1644963Y72390D01*
Y69288D01*
G02X1644325Y68650I-638J0D01*
G01X1643038D01*
G01X1637816Y59919D02*
X1636512D01*
X1635787Y59194D01*
X1632555D01*
X1631063Y57702D01*
Y54263D01*
G02X1630450Y53650I-613J0D01*
G01X1629388D01*
G01X1637816Y57719D02*
X1636512D01*
X1636187Y58044D01*
X1633032D01*
X1632213Y57225D01*
Y54263D01*
G03X1632826Y53650I613J0D01*
G01X1633888D01*
G01X1640016Y512675D02*
X1641454D01*
X1641979Y512150D01*
X1655262D01*
X1655762Y512650D01*
Y513575D01*
X1656262Y514075D01*
X1661516D01*
G01X1640016Y510475D02*
X1641447D01*
X1641972Y511000D01*
X1655262D01*
X1655762Y510500D01*
Y509575D01*
X1656262Y509075D01*
X1661516D01*
G01Y524075D02*
X1656262D01*
X1655762Y524575D01*
Y525500D01*
X1655372Y525890D01*
X1647122D01*
X1646113Y524881D01*
Y522000D01*
G03X1646707Y521406I594J0D01*
G01X1648038D01*
G01X1661516Y529075D02*
X1656262D01*
X1655762Y528575D01*
Y527562D01*
X1655240Y527040D01*
X1646645D01*
X1644963Y525358D01*
Y522000D01*
G02X1644369Y521406I-594J0D01*
G01X1643038D01*
G01X1637816Y512675D02*
X1636512D01*
X1635857Y512020D01*
X1632625D01*
X1631063Y510458D01*
Y506963D01*
G02X1630506Y506406I-557J0D01*
G01X1629388D01*
G01X1637816Y510475D02*
X1636512D01*
X1636117Y510870D01*
X1633102D01*
X1632213Y509981D01*
Y506963D01*
G03X1632770Y506406I557J0D01*
G01X1633888D01*
G01X1640016Y965431D02*
X1641469D01*
X1641994Y964906D01*
X1655262D01*
X1655762Y965406D01*
Y966331D01*
X1656262Y966831D01*
X1661516D01*
G01X1640016Y963231D02*
X1641531D01*
X1642056Y963756D01*
X1655262D01*
X1655762Y963256D01*
Y962331D01*
X1656262Y961831D01*
X1661516D01*
G01Y976831D02*
X1656262D01*
X1655762Y977331D01*
Y978338D01*
X1655344Y978756D01*
X1647113D01*
G03X1646613Y978256I0J-500D01*
G01Y976831D01*
G01X1661516Y981831D02*
X1656262D01*
X1655762Y981331D01*
Y980462D01*
X1655206Y979906D01*
X1647113D01*
G02X1646613Y980406I0J500D01*
G01Y981831D01*
G01X1637816Y965431D02*
X1636363D01*
X1636138Y965206D01*
X1630744D01*
G02X1630088Y965862I0J656D01*
G01Y966881D01*
G01X1637816Y963231D02*
X1636301D01*
X1635476Y964056D01*
X1630744D01*
G03X1630088Y963400I0J-656D01*
G01Y962381D01*
G01X1764228Y59919D02*
X1765929D01*
X1766454Y59394D01*
X1779474D01*
X1779974Y59894D01*
Y60819D01*
X1780474Y61319D01*
X1785728D01*
G01X1764228Y57719D02*
X1765847D01*
X1766372Y58244D01*
X1779474D01*
X1779974Y57744D01*
Y56819D01*
X1780474Y56319D01*
X1785728D01*
G01Y71319D02*
X1780474D01*
X1779974Y71819D01*
Y72744D01*
X1779574Y73144D01*
X1771344D01*
X1770325Y72125D01*
Y69288D01*
G03X1770963Y68650I638J0D01*
G01X1772250D01*
G01X1785728Y76319D02*
X1780474D01*
X1779974Y75819D01*
Y74774D01*
X1779494Y74294D01*
X1770867D01*
X1769175Y72602D01*
Y69288D01*
G02X1768537Y68650I-638J0D01*
G01X1767250D01*
G01X1762028Y59919D02*
X1760724D01*
X1759899Y59094D01*
X1756667D01*
X1755275Y57702D01*
Y54275D01*
G02X1754650Y53650I-625J0D01*
G01X1753600D01*
G01X1762028Y57719D02*
X1760724D01*
X1760499Y57944D01*
X1757144D01*
X1756425Y57225D01*
Y54275D01*
G03X1757050Y53650I625J0D01*
G01X1758100D01*
G01X1764228Y512675D02*
X1765717D01*
X1766242Y512150D01*
X1779474D01*
X1779974Y512650D01*
Y513575D01*
X1780474Y514075D01*
X1785728D01*
G01X1764228Y510475D02*
X1765631D01*
X1766156Y511000D01*
X1779474D01*
X1779974Y510500D01*
Y509575D01*
X1780474Y509075D01*
X1785728D01*
G01Y524075D02*
X1780474D01*
X1779974Y524575D01*
Y525500D01*
X1779564Y525910D01*
X1771354D01*
X1770325Y524881D01*
Y522075D01*
G03X1770994Y521406I669J0D01*
G01X1772250D01*
G01X1785728Y529075D02*
X1780474D01*
X1779974Y528575D01*
Y527650D01*
X1779384Y527060D01*
X1770877D01*
X1769175Y525358D01*
Y522075D01*
G02X1768506Y521406I-669J0D01*
G01X1767250D01*
G01X1762028Y512675D02*
X1760724D01*
X1760019Y511970D01*
X1756787D01*
X1755275Y510458D01*
Y507075D01*
G02X1754606Y506406I-669J0D01*
G01X1753600D01*
G01X1762028Y510475D02*
X1760724D01*
X1760379Y510820D01*
X1757264D01*
X1756425Y509981D01*
Y507075D01*
G03X1757094Y506406I669J0D01*
G01X1758100D01*
G01X1764228Y965431D02*
X1765669D01*
X1766194Y964906D01*
X1779474D01*
X1779974Y965406D01*
Y966331D01*
X1780474Y966831D01*
X1785728D01*
G01X1764228Y963231D02*
X1765631D01*
X1766156Y963756D01*
X1779474D01*
X1779974Y963256D01*
Y962331D01*
X1780474Y961831D01*
X1785728D01*
G01Y976831D02*
X1780474D01*
X1779974Y977331D01*
Y978426D01*
X1779644Y978756D01*
X1771325D01*
G03X1770825Y978256I0J-500D01*
G01Y976831D01*
G01X1785728Y981831D02*
X1780531D01*
X1779974Y981274D01*
Y980406D01*
X1779474Y979906D01*
X1771325D01*
G02X1770825Y980406I0J500D01*
G01Y981831D01*
G01X1762028Y965431D02*
X1760587D01*
X1759842Y964686D01*
X1755090D01*
G02X1754340Y965436I0J750D01*
G01Y966361D01*
G01X1762028Y963231D02*
X1760605D01*
X1760300Y963536D01*
X1755090D01*
G03X1754340Y962786I0J-750D01*
G01Y961861D01*
G01X1888441Y59919D02*
X1890049D01*
X1890574Y59394D01*
X1903687D01*
X1904187Y59894D01*
Y60819D01*
X1904687Y61319D01*
X1909941D01*
G01X1888441Y57719D02*
X1890047D01*
X1890572Y58244D01*
X1903687D01*
X1904187Y57744D01*
Y56819D01*
X1904687Y56319D01*
X1909941D01*
G01Y71319D02*
X1904687D01*
X1904187Y71819D01*
Y72744D01*
X1903887Y73044D01*
X1895457D01*
X1894538Y72125D01*
Y69362D01*
G03X1895250Y68650I712J0D01*
G01X1896463D01*
G01X1909941Y76319D02*
X1904687D01*
X1904187Y75819D01*
Y74894D01*
X1903487Y74194D01*
X1894980D01*
X1893388Y72602D01*
Y69288D01*
G02X1892750Y68650I-638J0D01*
G01X1891463D01*
G01X1886241Y59919D02*
X1884937D01*
X1884202Y59184D01*
X1880970D01*
X1879488Y57702D01*
Y54300D01*
G02X1878838Y53650I-650J0D01*
G01X1877813D01*
G01X1886241Y57719D02*
X1884937D01*
X1884622Y58034D01*
X1881447D01*
X1880638Y57225D01*
Y54300D01*
G03X1881288Y53650I650J0D01*
G01X1882313D01*
G01X1888441Y512675D02*
X1890066D01*
X1890591Y512150D01*
X1903687D01*
X1904187Y512650D01*
Y513575D01*
X1904687Y514075D01*
X1909941D01*
G01X1888441Y510475D02*
X1889867D01*
X1890392Y511000D01*
X1903687D01*
X1904187Y510500D01*
Y509575D01*
X1904687Y509075D01*
X1909941D01*
G01Y524075D02*
X1904687D01*
X1904187Y524575D01*
Y525500D01*
X1903807Y525880D01*
X1895537D01*
X1894538Y524881D01*
Y522044D01*
G03X1895176Y521406I638J0D01*
G01X1896463D01*
G01X1909941Y529075D02*
X1904687D01*
X1904187Y528575D01*
Y527587D01*
X1903630Y527030D01*
X1895060D01*
X1893388Y525358D01*
Y522044D01*
G02X1892750Y521406I-638J0D01*
G01X1891463D01*
G01X1886241Y512675D02*
X1884937D01*
X1884348Y512086D01*
X1881369D01*
X1879488Y510205D01*
Y507056D01*
G02X1878838Y506406I-650J0D01*
G01X1877813D01*
G01X1886241Y510475D02*
X1884937D01*
X1884476Y510936D01*
X1881846D01*
X1880638Y509728D01*
Y507056D01*
G03X1881288Y506406I650J0D01*
G01X1882313D01*
G01X1888441Y965431D02*
X1890169D01*
X1890694Y964906D01*
X1903687D01*
X1904187Y965406D01*
Y966331D01*
X1904687Y966831D01*
X1909941D01*
G01X1888441Y963231D02*
X1890031D01*
X1890556Y963756D01*
X1903687D01*
X1904187Y963256D01*
Y962331D01*
X1904687Y961831D01*
X1909941D01*
G01Y976831D02*
X1904687D01*
X1904187Y977331D01*
Y978256D01*
X1903687Y978756D01*
X1895700D01*
G03X1895038Y978094I0J-662D01*
G01Y976831D01*
G01X1909941Y981831D02*
X1904831D01*
X1904187Y981187D01*
Y980406D01*
X1903687Y979906D01*
X1895700D01*
G02X1895038Y980568I0J662D01*
G01Y981831D01*
G01X1886241Y965431D02*
X1884937D01*
X1884192Y964686D01*
X1879284D01*
G02X1878553Y965417I0J731D01*
G01Y966361D01*
G01X1886241Y963231D02*
X1884937D01*
X1884632Y963536D01*
X1879284D01*
G03X1878553Y962805I0J-731D01*
G01Y961861D01*
G54D13*
X64300Y91000D03*
X88800Y77000D03*
X56800Y65500D03*
X64300Y543500D03*
X88800Y529500D03*
X56800Y518000D03*
X86195Y905367D03*
X56800Y971000D03*
X88800Y982500D03*
X64300Y996500D03*
X184022Y467631D03*
X188300Y543500D03*
X180800Y518000D03*
X173608Y835918D03*
X181300Y971000D03*
X188800Y996500D03*
X184924Y1408800D03*
X114274Y1480400D03*
X125674Y1484200D03*
X214900Y57400D03*
X212800Y529500D03*
X213300Y982500D03*
X312800Y91000D03*
X337300Y77000D03*
X305300Y65500D03*
X312800Y543500D03*
X337300Y529500D03*
X305300Y518000D03*
Y971000D03*
X337300Y982500D03*
X312800Y996500D03*
X463800Y57500D03*
X436800Y543500D03*
X461300Y529500D03*
X429300Y518000D03*
Y971000D03*
X461300Y982500D03*
X436800Y996500D03*
X561300Y91000D03*
X553800Y65500D03*
X561300Y543500D03*
X553800Y518000D03*
Y971000D03*
X561300Y996500D03*
X507300Y1470500D03*
X525000Y1452100D03*
X524800Y1467000D03*
X585800Y77000D03*
Y529500D03*
Y982500D03*
X643495Y1425719D03*
X643595Y1441419D03*
X632800Y1464500D03*
X658600Y1468000D03*
X661800Y1444000D03*
X658600Y1464000D03*
Y1453500D03*
Y1457500D03*
X712300Y57400D03*
X685300Y543500D03*
X709800Y529500D03*
X677800Y518000D03*
Y971000D03*
X709800Y982500D03*
X685300Y996500D03*
X723800Y1453500D03*
X710300Y1443500D03*
X716300Y1458500D03*
Y1463000D03*
X681300Y1430000D03*
X689300D03*
X713300Y1438500D03*
X712400Y1475800D03*
X684800Y1476000D03*
X738032Y1466234D03*
X749532Y1465934D03*
X821290Y655190D03*
X814600Y772000D03*
Y781000D03*
X822800Y815000D03*
X824300Y893000D03*
X824187Y884453D03*
X942673Y556600D03*
X942388Y529107D03*
X942629Y551379D03*
X939527Y524023D03*
X871290Y647190D03*
Y655190D03*
X867100Y761000D03*
Y770000D03*
Y765500D03*
X874953Y807000D03*
X872800Y815000D03*
X908800Y782800D03*
X872300Y883000D03*
Y878500D03*
Y874000D03*
X930300Y875500D03*
X951038Y1412818D03*
Y1429318D03*
X960420Y770010D03*
Y774510D03*
X1054300Y824250D03*
Y814500D03*
Y837800D03*
Y828400D03*
X1026321Y830913D03*
X1000607Y903075D03*
X990197Y903465D03*
X1008081Y899075D03*
X1018339Y896965D03*
X1007800Y1117500D03*
X975800Y1201000D03*
Y1197000D03*
Y1209000D03*
Y1217000D03*
X996743Y1417899D03*
X988743D03*
X1020743Y1426399D03*
X1017743Y1431399D03*
X1023743Y1451399D03*
Y1455899D03*
X1020550Y1496814D03*
X1041850Y1496914D03*
X969243Y1431899D03*
X965143Y1445399D03*
Y1441399D03*
X1075400Y1309495D03*
Y1304495D03*
Y1299375D03*
Y1292460D03*
X1102400Y1371200D03*
X1102412Y1391273D03*
X1102400Y1375200D03*
X1102412Y1383273D03*
X1193594Y918091D03*
X1193524Y912331D03*
X1207312Y1401814D03*
X1301600Y68900D03*
X1303400Y530000D03*
X1329300Y533500D03*
X1304400Y982200D03*
X1329300Y986000D03*
X1323950Y1408400D03*
X1259974Y1484900D03*
X1284674Y1480000D03*
X1271374Y1488600D03*
X1427900Y529900D03*
Y982400D03*
X1453300Y80500D03*
Y533500D03*
Y986000D03*
X1552000Y69300D03*
Y529800D03*
X1577800Y533500D03*
X1552300Y982600D03*
X1577800Y986000D03*
X1676200Y77000D03*
X1701800Y80500D03*
X1676600Y530100D03*
X1701800Y533500D03*
X1676200Y982300D03*
X1701800Y986000D03*
X1712176Y1408700D03*
X1652800Y1465000D03*
X1797700Y63200D03*
X1726791Y471049D03*
X1800600Y530100D03*
X1759800Y583500D03*
X1801195Y905367D03*
X1800300Y982200D03*
X1859100Y22300D03*
X1822200Y100800D03*
X1825800Y533500D03*
X1855800Y543500D03*
X1839800Y533500D03*
X1825800Y986000D03*
X1855800Y996500D03*
X1839800Y986500D03*
X1817826Y1470900D03*
G54D31*
X76700Y133000D03*
X76600Y585500D03*
X94463Y903525D03*
X76500Y1038400D03*
X192290Y465789D03*
X139074Y1438500D03*
X201000Y133000D03*
Y585500D03*
X201100Y1038500D03*
X325300Y133000D03*
Y585500D03*
X325100Y1038500D03*
X449300Y133000D03*
X449600Y585500D03*
X449100Y1038500D03*
X573800Y133000D03*
X573700Y585500D03*
Y1038500D03*
X662200Y1448500D03*
X698000Y133000D03*
Y585500D03*
X697900Y1038500D03*
X861800Y779100D03*
X939200Y894000D03*
X966318Y534117D03*
X1010150Y842360D03*
X1026934Y1391632D03*
X969643Y1436399D03*
X1107200Y1327500D03*
X1109200Y1354000D03*
X1286074Y1438500D03*
X1666326D03*
X1735059Y469207D03*
X1757200Y595000D03*
X1809463Y903525D03*
X1872498Y68922D03*
X1868600Y132500D03*
X1868700Y585500D03*
X1868400Y1038500D03*
G54D106*
X1388500Y1334000D03*
Y1301000D03*
G54D22*
X83060Y80700D03*
X80500D03*
X77940D03*
Y73300D03*
X80500D03*
X83060D03*
Y533200D03*
X80500D03*
X77940D03*
Y525800D03*
X80500D03*
X83060D03*
Y986200D03*
X80500D03*
X77940D03*
Y978800D03*
X80500D03*
X83060D03*
X207060Y533200D03*
X204500D03*
X201940D03*
Y525800D03*
X204500D03*
X207060D03*
X207560Y986200D03*
X205000D03*
X202440D03*
Y978800D03*
X205000D03*
X207560D03*
X331560Y80700D03*
X329000D03*
X326440D03*
Y73300D03*
X329000D03*
X331560D03*
Y533200D03*
X329000D03*
X326440D03*
Y525800D03*
X329000D03*
X331560D03*
Y986200D03*
X329000D03*
X326440D03*
Y978800D03*
X329000D03*
X331560D03*
X455560Y533200D03*
X453000D03*
X450440D03*
Y525800D03*
X453000D03*
X455560D03*
Y986200D03*
X453000D03*
X450440D03*
Y978800D03*
X453000D03*
X455560D03*
X574940Y80700D03*
Y73300D03*
Y533200D03*
Y525800D03*
Y986200D03*
Y978800D03*
X580060Y80700D03*
X577500D03*
Y73300D03*
X580060D03*
Y533200D03*
X577500D03*
Y525800D03*
X580060D03*
Y986200D03*
X577500D03*
Y978800D03*
X580060D03*
X704060Y533200D03*
X701500D03*
X698940D03*
Y525800D03*
X701500D03*
X704060D03*
Y986200D03*
X701500D03*
X698940D03*
Y978800D03*
X701500D03*
X704060D03*
X1801796Y1484390D03*
X1799236D03*
X1796676D03*
Y1476990D03*
X1799236D03*
X1801796D03*
X1886060Y36700D03*
X1883500D03*
X1880940D03*
Y29300D03*
X1883500D03*
X1886060D03*
G54D40*
X79567Y388546D03*
X84567D03*
X73500Y840700D03*
X68500D03*
X95263Y880325D03*
X193090Y442589D03*
X191000Y840700D03*
X196000D03*
X213200Y388200D03*
X218200D03*
X315500D03*
X320500D03*
X315500Y840700D03*
X320500D03*
X440000Y388200D03*
X445000D03*
Y840700D03*
X440000D03*
X564000Y388200D03*
X569000D03*
X564000Y840700D03*
X569000D03*
X651295Y1435619D03*
X680500Y388200D03*
X685500D03*
X680500Y840700D03*
X685500D03*
X676500Y1423700D03*
X958738Y1423518D03*
X998000Y1114200D03*
X983943Y1411599D03*
X1040127Y1426700D03*
X1243500Y383700D03*
X1238462Y836388D03*
X1243462D03*
X1248500Y383700D03*
X1362500Y387700D03*
X1367500D03*
X1377100Y573400D03*
X1362500Y841200D03*
X1367500D03*
X1376900Y1026000D03*
X1487000Y387700D03*
X1492000D03*
X1500800Y573000D03*
X1487000Y840700D03*
X1492000D03*
X1500700Y1026000D03*
X1611000Y387700D03*
X1616000D03*
X1625500Y573200D03*
X1611000Y840700D03*
X1616000D03*
X1625400Y1026100D03*
X1735859Y446007D03*
X1735000Y387700D03*
X1740000D03*
X1735000Y840700D03*
X1740000D03*
X1810263Y880325D03*
X1749300Y1026100D03*
X1832100Y388500D03*
X1827100D03*
X1876100Y515400D03*
X1859500Y840700D03*
X1864500D03*
X1867500Y982400D03*
G54D116*
G01X949000Y1212224D02*
Y1214798D01*
X948298Y1215500D01*
G01X952276D02*
X948298D01*
G01X960150Y1199500D02*
Y1196813D01*
X960475Y1196488D01*
Y1192875D01*
G01X958575Y1199500D02*
Y1195275D01*
X955000Y1191700D01*
G01X952276Y1199500D02*
X948500D01*
G01X949000Y1207500D02*
X944000D01*
X943000Y1208500D01*
G01X957000Y1199500D02*
Y1196581D01*
X954119Y1193700D01*
X954112D01*
X953712Y1193300D01*
X952500D01*
G01X955425Y1199500D02*
Y1197552D01*
X953373Y1195500D01*
X952500D01*
G01X949000Y1204350D02*
X943650D01*
X943000Y1205000D01*
G01X949000Y1210650D02*
X944850D01*
X944500Y1211000D01*
G01X961724Y1199500D02*
X963100D01*
X964500Y1198100D01*
Y1193550D01*
X964550Y1193500D01*
G01X1132612Y1384049D02*
Y1381273D01*
X1132112Y1380773D01*
G01X1129336D02*
X1132112D01*
G01X1119888Y1396773D02*
Y1397797D01*
X1117362Y1400323D01*
Y1402773D01*
G01X1121462Y1396773D02*
Y1403723D01*
G01X1123037Y1396773D02*
Y1399801D01*
X1123262Y1400026D01*
Y1401893D01*
X1125242Y1403873D01*
X1128612D01*
G01X1129336Y1396773D02*
X1133112D01*
G01X1132612Y1388773D02*
X1137612D01*
X1138612Y1387773D01*
G01X1124612Y1396773D02*
Y1400273D01*
X1126112Y1401773D01*
G01X1126187Y1396773D02*
Y1398721D01*
X1128239Y1400773D01*
X1129112D01*
G01X1132612Y1391923D02*
X1137962D01*
X1138612Y1391273D01*
G01X1132612Y1385623D02*
X1136162D01*
X1137112Y1384673D01*
G54D107*
X1813566Y1484735D03*
X1816126D03*
Y1476665D03*
X1813566D03*
X1818686Y1484735D03*
Y1476665D03*
G54D41*
X79567Y394146D03*
X84567D03*
X73500Y846300D03*
X68500D03*
X95263Y885925D03*
X193090Y448189D03*
X191000Y846300D03*
X196000D03*
X213200Y393800D03*
X218200D03*
X315500D03*
X320500D03*
X315500Y846300D03*
X320500D03*
X440000Y393800D03*
X445000D03*
Y846300D03*
X440000D03*
X564000Y393800D03*
X569000D03*
X564000Y846300D03*
X569000D03*
X651295Y1441219D03*
X680500Y393800D03*
X685500D03*
X680500Y846300D03*
X685500D03*
X676500Y1429300D03*
X958738Y1429118D03*
X998000Y1119800D03*
X983943Y1417199D03*
X1040127Y1432300D03*
X1243500Y389300D03*
X1238462Y841988D03*
X1243462D03*
X1248500Y389300D03*
X1362500Y393300D03*
X1367500D03*
X1377100Y579000D03*
X1362500Y846800D03*
X1367500D03*
X1376900Y1031600D03*
X1487000Y393300D03*
X1492000D03*
X1500800Y578600D03*
X1487000Y846300D03*
X1492000D03*
X1500700Y1031600D03*
X1611000Y393300D03*
X1616000D03*
X1625500Y578800D03*
X1611000Y846300D03*
X1616000D03*
X1625400Y1031700D03*
X1735859Y451607D03*
X1735000Y393300D03*
X1740000D03*
X1735000Y846300D03*
X1740000D03*
X1810263Y885925D03*
X1749300Y1031700D03*
X1832100Y394100D03*
X1827100D03*
X1876100Y521000D03*
X1859500Y846300D03*
X1864500D03*
X1867500Y988000D03*
G54D50*
X144900Y29300D03*
X137700Y594500D03*
Y1047500D03*
X139074Y1457000D03*
X261700Y594500D03*
X261400Y1047500D03*
X222574Y1430000D03*
X386200Y594500D03*
Y1047500D03*
X510200Y594500D03*
Y1047500D03*
X504700Y1465500D03*
X634700Y594500D03*
Y1047500D03*
X836690Y641690D03*
X834400Y800500D03*
X857058Y1392892D03*
X927200Y759320D03*
X866700Y892000D03*
X928700Y880000D03*
X978541Y563811D03*
X1004600Y1129300D03*
X1044900Y1417000D03*
X1037750Y1480314D03*
X1286074Y1457000D03*
X1369574Y1430000D03*
X1666326Y1457000D03*
X1811700Y28900D03*
X1749826Y1430000D03*
G54D14*
X88800Y72400D03*
X85600Y62800D03*
X56800Y96500D03*
X55259Y383528D03*
X69992Y403305D03*
X88600Y525300D03*
X86900Y516800D03*
X56800Y549000D03*
X42992Y836182D03*
X57725Y855959D03*
X94563Y908025D03*
X93655Y899023D03*
X86197Y901301D03*
X71363Y909325D03*
X70063Y892025D03*
X56800Y1002000D03*
X88800Y968000D03*
Y972500D03*
X195300Y78500D03*
X160800Y25100D03*
X157100Y32100D03*
X172200Y25100D03*
X160800Y21100D03*
X172200Y20900D03*
X168400Y29200D03*
X144100Y44400D03*
Y48500D03*
X192390Y470289D03*
X191482Y461287D03*
X184024Y463565D03*
X169190Y471589D03*
X167890Y454289D03*
X189392Y383182D03*
X180800Y549000D03*
X137300Y583000D03*
X180725Y855659D03*
X106363Y911925D03*
X106322Y903550D03*
X137300Y1036000D03*
X181300Y1002000D03*
X137774Y1472900D03*
X138674Y1452500D03*
Y1434000D03*
X124874Y1479100D03*
X203800Y45100D03*
X204190Y474189D03*
X204149Y465814D03*
X204125Y402959D03*
X212700Y525200D03*
X211200Y516600D03*
X261300Y583000D03*
X210900Y969700D03*
X213300Y978100D03*
X261000Y1036000D03*
X337200Y72600D03*
X335000Y63700D03*
X305300Y96500D03*
X291092Y383482D03*
X305825Y403259D03*
X337300Y525300D03*
X335100Y516800D03*
X305300Y549000D03*
X385800Y583000D03*
X291092Y836182D03*
X305825Y855959D03*
X305300Y1002000D03*
X334800Y969400D03*
X337200Y978200D03*
X385800Y1036000D03*
X452000Y44500D03*
X415592Y383182D03*
X430325Y402959D03*
X461300Y525300D03*
X459400Y516900D03*
X429300Y549000D03*
X415292Y835876D03*
X430025Y855659D03*
X429300Y1002000D03*
X459200Y969200D03*
X461200Y978000D03*
X553800Y96500D03*
X539792Y383482D03*
X554525Y403259D03*
X553800Y549000D03*
X509800Y583000D03*
Y1036000D03*
X553800Y1002000D03*
X585700Y72800D03*
X583800Y64300D03*
X650792Y383182D03*
X665525Y402959D03*
X585700Y525400D03*
X634300Y583000D03*
X656192Y835882D03*
X670925Y855659D03*
X579198Y836405D03*
X594105Y856859D03*
X583100Y969500D03*
X585800Y978100D03*
X634300Y1036000D03*
X668300Y1430000D03*
X692300Y78500D03*
X701300Y45050D03*
X748300Y130500D03*
X709700Y525300D03*
X677800Y549000D03*
Y1002000D03*
X707500Y969600D03*
X709900Y978300D03*
X749700Y1036000D03*
X710800Y1453500D03*
X712100Y1467300D03*
X723800Y1449000D03*
X712200Y1471600D03*
X821290Y659190D03*
Y647190D03*
Y651190D03*
X814600Y776500D03*
X814500Y785500D03*
X814600Y767500D03*
X822800Y819000D03*
Y807000D03*
Y811000D03*
X824300Y897500D03*
Y888500D03*
X824187Y880256D03*
X871290Y643190D03*
Y651190D03*
X867100Y756500D03*
X874953Y811000D03*
X872800Y803000D03*
X916100Y764800D03*
X908800Y774000D03*
Y778000D03*
X872300Y869500D03*
X954800Y898500D03*
X940800D03*
X955350Y1403400D03*
Y1399400D03*
X989548Y539555D03*
X991738Y517437D03*
X996141Y552081D03*
X991763Y526457D03*
X960420Y761010D03*
Y779010D03*
Y765510D03*
X1034181Y855984D03*
X1020300Y842500D03*
X1034184Y851705D03*
X1026462Y849214D03*
X1029642Y825127D03*
X1000607Y899075D03*
X990197Y895065D03*
X1008081Y903075D03*
X1018339Y900965D03*
X1024074Y939306D03*
X975800Y1225000D03*
Y1205000D03*
Y1221000D03*
Y1213000D03*
X975743Y1418699D03*
X1034150Y1496914D03*
X1020550Y1492814D03*
X1041850D03*
X1034150D03*
X1126800Y1291700D03*
Y1296700D03*
X1102412Y1379273D03*
Y1399273D03*
Y1395273D03*
Y1387273D03*
X1111800Y1358500D03*
X1213661Y836182D03*
X1228394Y855959D03*
X1184800Y892600D03*
Y886000D03*
Y906100D03*
Y899500D03*
X1330800Y109500D03*
X1337874Y383426D03*
X1259495Y383269D03*
X1274228Y403046D03*
X1331800Y562500D03*
X1337874Y836182D03*
X1331800Y1015000D03*
X1284674Y1471500D03*
X1285674Y1452500D03*
Y1434000D03*
X1271389Y1483400D03*
X1432300Y77000D03*
X1352607Y403203D03*
Y855959D03*
X1455800Y109500D03*
X1462086Y383426D03*
X1476819Y403203D03*
X1455800Y562500D03*
X1462086Y836182D03*
X1476819Y855959D03*
X1455800Y1015000D03*
X1601200Y129000D03*
X1586299Y383426D03*
X1601032Y403203D03*
X1580300Y562500D03*
X1586299Y836182D03*
X1601032Y855959D03*
X1580300Y1015000D03*
X1704300Y109500D03*
X1711959Y475007D03*
X1710659Y457707D03*
X1704300Y562500D03*
X1710511Y836182D03*
X1704300Y1015000D03*
X1665926Y1452500D03*
Y1434000D03*
X1812800Y64400D03*
X1735159Y473707D03*
X1746918Y469232D03*
X1734251Y464705D03*
X1726793Y466983D03*
X1801692Y383782D03*
X1816425Y403559D03*
X1749992Y402630D03*
X1764201Y402301D03*
X1746959Y477607D03*
X1725244Y855959D03*
X1809563Y908025D03*
X1808655Y899023D03*
X1801197Y901301D03*
X1786363Y909325D03*
X1785063Y892025D03*
X1803441Y1490100D03*
X1806411Y1471000D03*
X1818978Y85039D03*
Y80939D03*
X1878300Y77500D03*
X1862800Y78000D03*
X1864000Y38100D03*
X1821900Y32000D03*
X1827500Y25100D03*
Y20900D03*
X1835000Y29300D03*
X1838900Y25200D03*
Y21100D03*
X1827300Y109500D03*
X1828300Y562500D03*
X1876200Y530600D03*
X1848300Y549000D03*
X1849800Y527000D03*
X1834724Y836182D03*
X1849457Y855959D03*
X1821363Y911925D03*
X1821322Y903550D03*
X1828300Y1015000D03*
X1848300Y1002000D03*
X1849800Y980000D03*
G54D23*
G01X72049Y260355D02*
Y349667D01*
G01X68109Y260355D02*
X67504Y260960D01*
Y360804D01*
X72600Y365900D01*
G01X72049Y254605D02*
Y251749D01*
X70800Y250500D01*
X62100D01*
X57300Y255300D01*
Y364044D01*
X53713Y367631D01*
G01X68109Y254605D02*
X63395D01*
X61060Y256940D01*
Y363151D01*
X69567Y371658D01*
Y380781D01*
G01X84567Y388346D02*
Y369366D01*
X72049Y356848D01*
Y349667D01*
G01X79567Y388346D02*
Y372867D01*
X72600Y365900D01*
G01X51209Y393253D02*
Y370135D01*
X53713Y367631D01*
G01X207640Y474189D02*
Y480051D01*
X203727Y483964D01*
X145869D01*
X121505Y459600D01*
X63287D01*
X18887Y504000D01*
Y917113D01*
X23974Y922200D01*
X107400D01*
X109813Y919787D01*
Y911925D01*
G01X69567Y380781D02*
Y389096D01*
G01X72049Y713111D02*
Y808105D01*
G01X68109Y713111D02*
Y785607D01*
G01X72049Y707361D02*
Y702949D01*
X70200Y701100D01*
X63300D01*
X53540Y710860D01*
Y809960D01*
X44000Y819500D01*
G01X68109Y707361D02*
X62439D01*
X57300Y712500D01*
Y751562D01*
G01D02*
Y841750D01*
G01X73500Y840500D02*
Y822805D01*
X72049Y821354D01*
Y808105D01*
G01X68500Y840500D02*
Y824016D01*
X68109Y823625D01*
Y785607D01*
G01X38942Y845907D02*
Y824558D01*
X44000Y819500D01*
G01X97263Y913025D02*
Y910275D01*
X98013Y909525D01*
Y908025D01*
G01X97263Y913025D02*
X101513D01*
X102263Y912275D01*
G01X98013Y908025D02*
Y905775D01*
X100263Y903525D01*
G01X68900Y897700D02*
X67663Y898937D01*
Y911025D01*
X70663Y914025D01*
X85263D01*
X86263Y913025D01*
G01X89647Y901301D02*
Y905365D01*
X89645Y905367D01*
G01D02*
Y906309D01*
X87614Y908340D01*
Y911674D01*
X86263Y913025D01*
G01X106263Y900025D02*
X102963Y896725D01*
X99403D01*
X97105Y899023D01*
G01X86147Y901301D02*
X91006Y896442D01*
X94524D01*
X97105Y899023D01*
G01X73513Y892025D02*
X74863D01*
X77263Y894425D01*
G01Y898225D02*
Y894425D01*
G01X77563Y901775D02*
Y898525D01*
X77263Y898225D01*
G01X81700Y901830D02*
Y900462D01*
X83500Y898662D01*
G01X71313Y909325D02*
Y904525D01*
G01X73430Y898509D02*
Y900408D01*
X71313Y902525D01*
Y904525D01*
G01X70013Y892025D02*
Y888085D01*
X70603Y887495D01*
G01X94324Y1473650D02*
X97174Y1476500D01*
Y1489100D01*
X105174Y1497100D01*
X116374D01*
G01X90709Y1485118D02*
X86724Y1481133D01*
Y1473650D01*
G01X70709Y1485118D02*
Y1477265D01*
X82124Y1465850D01*
X86624D01*
G01X94224D02*
X100924Y1472550D01*
Y1481150D01*
X104974Y1485200D01*
G01X192321Y260355D02*
Y339321D01*
X204300Y351300D01*
G01X196261Y254605D02*
Y251761D01*
X194850Y250350D01*
X185250D01*
X180300Y255300D01*
Y330300D01*
G01X192321Y254605D02*
X186395D01*
X184060Y256940D01*
Y300300D01*
G01X185342Y392907D02*
Y348542D01*
X180300Y343500D01*
Y330300D01*
G01X203700Y388850D02*
Y361200D01*
X184060Y341560D01*
Y300300D01*
G01X195090Y475289D02*
Y472539D01*
X195840Y471789D01*
Y470289D01*
G01X166727Y459964D02*
X165490Y461201D01*
Y473289D01*
X168490Y476289D01*
X183090D01*
X184090Y475289D01*
G01X187474Y463565D02*
Y467629D01*
X187472Y467631D01*
G01D02*
Y468573D01*
X185441Y470604D01*
Y473938D01*
X184090Y475289D01*
G01X204090Y462289D02*
X200265Y458464D01*
X197251D01*
X195090Y460625D01*
Y461129D01*
X194932Y461287D01*
G01X183974Y463565D02*
X188833Y458706D01*
X192351D01*
X194932Y461287D01*
G01X175090Y460489D02*
Y456689D01*
G01X171340Y454289D02*
X172690D01*
X175090Y456689D01*
G01X175390Y464039D02*
Y460789D01*
X175090Y460489D01*
G01X179527Y464094D02*
Y462726D01*
X181327Y460926D01*
G01X171257Y460773D02*
Y462672D01*
X169140Y464789D01*
Y466789D01*
G01Y471589D02*
Y466789D01*
G01X167840Y454289D02*
Y450349D01*
X168430Y449759D01*
G01X192321Y713111D02*
Y785355D01*
G01X196261Y707361D02*
Y704161D01*
X194100Y702000D01*
X185100D01*
X176540Y710560D01*
Y811018D01*
X165500Y822058D01*
G01X192321Y707361D02*
X185139D01*
X180300Y712200D01*
Y769500D01*
G01X191000Y840500D02*
X192321Y839179D01*
Y785355D01*
G01X160342Y840907D02*
Y827216D01*
X165500Y822058D01*
G01X180300Y841750D02*
X181200Y840850D01*
Y770400D01*
X180300Y769500D01*
G01X106313Y911925D02*
X105963Y912275D01*
X102263D01*
G01X100263Y903525D02*
Y899604D01*
X100310Y899557D01*
G01X116263Y911525D02*
X112263Y907525D01*
X107863D01*
X106272Y905934D01*
Y903550D01*
G01D02*
Y900034D01*
X106263Y900025D01*
G01X145445Y1420640D02*
X139814D01*
X139774Y1420600D01*
G01X175249Y1434075D02*
Y1429250D01*
G01X151945Y1420640D02*
Y1413450D01*
X154295Y1411100D01*
X160074D01*
X162274Y1413300D01*
Y1419350D01*
G01X175249Y1429250D02*
Y1427275D01*
X173974Y1426000D01*
X169674D01*
X168374Y1424700D01*
Y1420600D01*
X167124Y1419350D01*
X162274D01*
G01X145445Y1425760D02*
X139084D01*
X138974Y1425650D01*
G01X130601Y1411700D02*
Y1418627D01*
X137624Y1425650D01*
X138974D01*
G01X145445Y1423200D02*
X139156D01*
X136531Y1420575D01*
Y1417879D01*
X137634Y1416776D01*
G01D02*
Y1411860D01*
X136774Y1411000D01*
G01X151945Y1425760D02*
X155087D01*
X156459Y1424388D01*
G01X184252Y1466929D02*
X175681Y1475500D01*
X152217D01*
X149617Y1472900D01*
X141224D01*
G01X184252Y1445275D02*
Y1466929D01*
G01X144874Y1457000D02*
X145124Y1457250D01*
X149374D01*
G01D02*
X153374D01*
G01D02*
X153524Y1457400D01*
Y1464000D01*
G01X167716Y1466929D02*
X156453D01*
X153524Y1464000D01*
G01X144874Y1438500D02*
X145124Y1438750D01*
X149374D01*
G01D02*
X153374D01*
G01D02*
X153524Y1438900D01*
Y1445500D01*
G01X167716Y1445275D02*
X167491Y1445500D01*
X153524D01*
G01X137724Y1472900D02*
X137624Y1472800D01*
Y1469000D01*
G01X162374Y1431450D02*
X157324D01*
X156374Y1430500D01*
G01X116374Y1497100D02*
X118702Y1494772D01*
Y1491167D01*
X118709Y1491160D01*
G01X110639Y1488600D02*
X113674D01*
X115174Y1487100D01*
Y1484400D01*
X114224Y1483450D01*
Y1480400D01*
G01D02*
X109874D01*
X109774Y1480300D01*
G01X105474Y1476735D02*
Y1478200D01*
X107574Y1480300D01*
X109774D01*
G01X118434Y1458950D02*
X121924D01*
X124174Y1461200D01*
Y1466600D01*
G01X118574Y1472000D02*
X120474D01*
X124174Y1468300D01*
Y1466600D01*
G01X138874Y1438500D02*
X138624Y1438250D01*
Y1434000D01*
G01X130322Y1434014D02*
X130336Y1434000D01*
X138624D01*
G01Y1452500D02*
X135274D01*
X135174Y1452400D01*
G01X138874Y1457000D02*
Y1452750D01*
X138624Y1452500D01*
G01X110639Y1486040D02*
X105814D01*
X104974Y1485200D01*
G01X125624Y1484200D02*
Y1487150D01*
X124574Y1488200D01*
G01X125624Y1484200D02*
Y1482450D01*
X128324Y1479750D01*
Y1479100D01*
G01X118709Y1488600D02*
X124174D01*
X124574Y1488200D01*
G01X119074Y1442100D02*
X123974Y1437200D01*
X124074D01*
G01X115874Y1452450D02*
Y1448900D01*
X116582Y1448192D01*
Y1444592D01*
X119074Y1442100D01*
G01X113314Y1445840D02*
Y1441700D01*
G01Y1452450D02*
Y1445840D01*
G01X111174Y1469440D02*
X114214D01*
X115082Y1470308D01*
Y1471292D01*
X114374Y1472000D01*
X111174D01*
G01X105474Y1473235D02*
Y1470000D01*
X105974Y1469500D01*
G01X111174Y1469440D02*
X106034D01*
X105974Y1469500D01*
G01X124824Y1479100D02*
Y1475590D01*
X124134Y1474900D01*
G01X118574Y1474560D02*
X123794D01*
X124134Y1474900D01*
G01X196261Y260355D02*
Y337261D01*
X218200Y359200D01*
Y360600D01*
G01Y388000D02*
Y360600D01*
G01X213200Y388000D02*
Y360200D01*
X204300Y351300D01*
G01X287042Y393207D02*
Y373258D01*
X294000Y366300D01*
G01X714600Y498100D02*
X686180Y469680D01*
X490257D01*
X469602Y449025D01*
X321241D01*
X297817Y472449D01*
X221351D01*
X215546Y478254D01*
X213797D01*
X209732Y474189D01*
X207640D01*
G01X195090Y475289D02*
X199340D01*
X200090Y474539D01*
G01X204140Y474189D02*
X203790Y474539D01*
X200090D01*
G01X195840Y470289D02*
Y468039D01*
X198090Y465789D01*
G01D02*
Y461868D01*
X198137Y461821D01*
G01X214090Y473789D02*
X210090Y469789D01*
X205690D01*
X204099Y468198D01*
Y465814D01*
G01D02*
Y462298D01*
X204090Y462289D01*
G01X196261Y713111D02*
Y807853D01*
G01X196000Y840500D02*
X196261Y840239D01*
Y807853D01*
G01X287042Y845907D02*
Y825958D01*
X294000Y819000D01*
G01X320474Y260355D02*
Y364117D01*
G01X316534Y260355D02*
Y341619D01*
G01X320474Y254605D02*
Y251174D01*
X319500Y250200D01*
X309600D01*
X301640Y258160D01*
Y358660D01*
X294000Y366300D01*
G01X316534Y254605D02*
X310595D01*
X305400Y259800D01*
Y317825D01*
G01X320500Y388000D02*
Y375792D01*
X320474Y375766D01*
Y364117D01*
G01X315500Y388000D02*
Y377449D01*
X316534Y376415D01*
Y341619D01*
G01X305400Y389050D02*
Y317825D01*
G01X320474Y713111D02*
Y812669D01*
G01X316534Y713111D02*
Y790171D01*
G01X320474Y707361D02*
Y703274D01*
X318300Y701100D01*
X311400D01*
X301640Y710860D01*
Y811360D01*
X294000Y819000D01*
G01X316534Y707361D02*
X310539D01*
X305400Y712500D01*
Y764768D01*
G01X320500Y840500D02*
Y824879D01*
X320474Y824853D01*
Y812669D01*
G01X315500Y840500D02*
Y824740D01*
X316534Y823706D01*
Y790171D01*
G01X305400Y764768D02*
Y841750D01*
G01X444687Y260355D02*
Y358540D01*
G01X440747Y260355D02*
Y336042D01*
G01X444687Y254605D02*
Y251187D01*
X443400Y249900D01*
X434100D01*
X426140Y257860D01*
Y358360D01*
X418500Y366000D01*
G01X429900Y278468D02*
Y388850D01*
G01X440747Y254605D02*
X434795D01*
X429900Y259500D01*
Y278468D01*
G01X445000Y388000D02*
Y381937D01*
X444687Y381624D01*
Y358540D01*
G01X440000Y388000D02*
Y381854D01*
X440747Y381107D01*
Y336042D01*
G01X411542Y392907D02*
Y372958D01*
X418500Y366000D01*
G01X444687Y807662D02*
Y713111D01*
G01X440747Y785164D02*
Y713111D01*
G01X444687Y707361D02*
Y703587D01*
X442500Y701400D01*
X435000D01*
X425840Y710560D01*
Y808160D01*
X415000Y819000D01*
G01X429600Y761281D02*
Y841550D01*
G01X440747Y707361D02*
X434439D01*
X429600Y712200D01*
Y761281D01*
G01X445000Y840500D02*
Y836700D01*
X444687Y836387D01*
Y807662D01*
G01X440000Y840500D02*
Y836745D01*
X440747Y835998D01*
Y785164D01*
G01X411242Y845607D02*
Y822758D01*
X415000Y819000D01*
G01X568899Y260355D02*
Y355752D01*
G01X564959Y260355D02*
Y333254D01*
G01X568899Y254605D02*
Y251799D01*
X567000Y249900D01*
X558600D01*
X536715Y271785D01*
G01X535742Y393207D02*
Y272758D01*
X536715Y271785D01*
G01X564959Y254605D02*
X564903Y254661D01*
X559239D01*
X554100Y259800D01*
Y294300D01*
G01X569000Y388000D02*
Y378393D01*
X568899Y378292D01*
Y355752D01*
G01X564000Y388000D02*
Y378764D01*
X564959Y377805D01*
Y333254D01*
G01X554100Y294300D02*
Y389050D01*
G01X568899Y713111D02*
X569000Y713212D01*
Y814761D01*
G01X564959Y791755D02*
Y713111D01*
G01X575148Y827910D02*
Y704218D01*
X573608Y702678D01*
X570031D01*
X568899Y703810D01*
Y707361D01*
G01X593680Y827400D02*
Y810979D01*
X579474Y796773D01*
Y702309D01*
X575439Y698274D01*
X567239D01*
X564959Y700554D01*
Y707361D01*
G01X569000Y814761D02*
Y840500D01*
G01X564000D02*
Y827876D01*
X564959Y826917D01*
Y791755D01*
G01X575148Y846130D02*
Y827910D01*
G01X632750Y1464500D02*
Y1469250D01*
X616472Y1485528D01*
X579082D01*
X564567Y1471013D01*
Y1466929D01*
G01Y1445275D02*
Y1466929D01*
G01X510750Y1470500D02*
Y1465750D01*
X510500Y1465500D01*
G01X510750Y1474500D02*
Y1470500D01*
G01Y1474500D02*
X512500D01*
X515076Y1471924D01*
X517500D01*
G01X548031Y1466929D02*
X538897Y1476063D01*
X525063D01*
X520924Y1471924D01*
X517500D01*
G01X528200Y1456600D02*
X528450Y1456350D01*
Y1452100D01*
G01D02*
Y1448100D01*
G01D02*
X535050D01*
X535200Y1447950D01*
G01D02*
X545356D01*
X548031Y1445275D01*
G01X528250Y1467000D02*
Y1470900D01*
G01X528200Y1462600D02*
X528250Y1462650D01*
Y1467000D01*
G01X496500Y1476000D02*
Y1468000D01*
X499250Y1465250D01*
X500000D01*
G01X504500Y1465500D02*
X504250Y1465250D01*
X500000D01*
G01X693112Y254605D02*
Y251512D01*
X691500Y249900D01*
X669300D01*
X661340Y257860D01*
Y358360D01*
X653700Y366000D01*
G01X665100Y275593D02*
Y388850D01*
G01X689172Y254605D02*
X688928Y254361D01*
X670239D01*
X665100Y259500D01*
Y275593D01*
G01X646742Y392907D02*
Y372958D01*
X653700Y366000D01*
G01X693112Y707361D02*
Y705712D01*
X690450Y703050D01*
X674250D01*
X669300Y708000D01*
Y799700D01*
X652142Y816858D01*
Y822416D01*
G01Y845607D02*
Y822416D01*
G01X593680Y827400D02*
Y842750D01*
G01X670500Y841550D02*
Y829616D01*
G01X689172Y707361D02*
X675339D01*
X673060Y709640D01*
Y818943D01*
X670500Y821503D01*
Y829616D01*
G01X659901Y1290524D02*
X645700D01*
X644700Y1291524D01*
Y1320348D01*
X646102Y1321750D01*
G01X627499Y1290524D02*
X641700D01*
X642700Y1291524D01*
Y1320152D01*
X641102Y1321750D01*
G01X668000Y1422250D02*
Y1418900D01*
G01X672000Y1422250D02*
Y1419000D01*
G01X655795Y1426169D02*
X659196D01*
X660836Y1427809D01*
Y1431276D01*
X663109Y1433549D01*
G01X655795Y1426169D02*
X652545D01*
X651295Y1424919D01*
G01D02*
X647745D01*
X646945Y1425719D01*
G01X646200Y1420576D02*
X644700Y1419076D01*
Y1416176D01*
X645700Y1415176D01*
X659901D01*
G01X641200Y1420576D02*
X642700Y1419076D01*
Y1416176D01*
X641700Y1415176D01*
X627499D01*
G01X672000Y1425750D02*
X668000D01*
G01D02*
X664172D01*
X663263Y1426659D01*
Y1427653D01*
G01X668250Y1430000D02*
X664135D01*
X663263Y1429128D01*
Y1427653D01*
G01X662000Y1448500D02*
X661300Y1449200D01*
X658000D01*
G01X679950Y1446610D02*
Y1444869D01*
X674504Y1439423D01*
X668983D01*
X663109Y1433549D01*
G01X662050Y1464000D02*
X663050Y1465000D01*
X664200D01*
X665700Y1463500D01*
G01X662050Y1468000D02*
X663050Y1467000D01*
X664200D01*
X665700Y1468500D01*
G01X658550Y1457500D02*
X657550Y1456500D01*
X650948D01*
X650000Y1457448D01*
G01D02*
X649052Y1456500D01*
X646213D01*
X645213Y1457500D01*
Y1470513D01*
X646900Y1472200D01*
X651200D01*
X652992Y1470408D01*
Y1467071D01*
X655063Y1465000D01*
X657550D01*
X658550Y1464000D01*
G01Y1453500D02*
X657550Y1454500D01*
X650948D01*
X650000Y1453552D01*
G01D02*
X649052Y1454500D01*
X645384D01*
X643213Y1456671D01*
Y1471342D01*
X646071Y1474200D01*
X652029D01*
X654992Y1471237D01*
Y1467900D01*
X655892Y1467000D01*
X657550D01*
X658550Y1468000D01*
G01X680250Y1448579D02*
X677933D01*
X670990Y1441636D01*
X666429D01*
X663726Y1438933D01*
G01X647045Y1441419D02*
X651295D01*
G01X663726Y1438933D02*
X661754D01*
X660518Y1440169D01*
X655795D01*
G01X651295Y1441419D02*
X654545D01*
X655795Y1440169D01*
G01X683110Y1443450D02*
X681950D01*
X675786Y1437286D01*
X670714D01*
X668250Y1434822D01*
Y1430000D01*
G01X671750D02*
Y1434078D01*
X672520Y1434848D01*
X673964D01*
G01X636250Y1464500D02*
Y1468500D01*
G01X662050Y1457500D02*
X663050Y1456500D01*
X664200D01*
X665700Y1458000D01*
G01X680250Y1456453D02*
X676458D01*
X676442Y1456469D01*
X670542D01*
X669761Y1457250D01*
G01X665700Y1458000D02*
X667200Y1456500D01*
X669011D01*
X669761Y1457250D01*
G01X662050Y1453500D02*
X663050Y1454500D01*
X664200D01*
X665700Y1453000D01*
G01X680250Y1454484D02*
X676457D01*
X676442Y1454469D01*
X670480D01*
X669761Y1453750D01*
G01X665700Y1453000D02*
X667200Y1454500D01*
X669011D01*
X669761Y1453750D01*
G01X666250Y1485000D02*
X662375Y1488875D01*
X658750D01*
G01X672500Y1485000D02*
X666250D01*
G01X667500Y1476250D02*
X672500D01*
G01X653000Y1481250D02*
X658625D01*
X658750Y1481125D01*
G01D02*
X663625Y1476250D01*
X667500D01*
G01X693112Y342443D02*
Y260355D01*
G01X689172Y319945D02*
Y260355D01*
G01X685500Y388000D02*
Y354000D01*
X693112Y346388D01*
Y342443D01*
G01X680500Y388000D02*
Y353427D01*
X689172Y344755D01*
Y319945D01*
G01X693112Y713111D02*
Y755888D01*
X685500Y763500D01*
Y773631D01*
G01X689172Y713111D02*
Y754255D01*
X680500Y762927D01*
Y790616D01*
G01X685500Y773631D02*
Y840500D01*
G01X680500Y790616D02*
Y840500D01*
G01X698500Y1422250D02*
Y1418900D01*
G01X693000Y1422250D02*
Y1418800D01*
G01X689000Y1422250D02*
Y1419000D01*
G01X681000Y1422250D02*
Y1419100D01*
G01X685000Y1422250D02*
Y1418900D01*
G01X703500Y1429250D02*
Y1426000D01*
G01X676500Y1423500D02*
Y1419500D01*
G01X685000Y1425750D02*
X681000D01*
G01X684750Y1430000D02*
Y1426000D01*
X685000Y1425750D01*
G01X693000D02*
X689000D01*
G01X692750Y1430000D02*
Y1426000D01*
X693000Y1425750D01*
G01X698500D02*
Y1431000D01*
G01X681250Y1430000D02*
X679220D01*
X678720Y1429500D01*
X676500D01*
G01X744132Y1426834D02*
Y1423884D01*
X742880Y1422632D01*
G01X744132Y1438184D02*
Y1426834D01*
G01X739532Y1425934D02*
Y1430734D01*
G01X719000Y1453500D02*
X714250D01*
G01X719000D02*
X723750D01*
G01D02*
Y1449000D01*
G01X716750Y1438500D02*
X720455D01*
G01X718000Y1443500D02*
Y1441596D01*
X716750Y1440346D01*
Y1438500D01*
G01X713750Y1443500D02*
X718000D01*
G01X684000Y1482000D02*
Y1481500D01*
X688250Y1477250D01*
Y1476000D01*
G01X695750D02*
X699500D01*
G01X687047Y1463250D02*
Y1456453D01*
X690000Y1453500D01*
G01X703500Y1432750D02*
Y1435500D01*
X701000Y1438000D01*
G01X694921Y1443750D02*
Y1441579D01*
X698500Y1438000D01*
X701000D01*
G01X713250Y1438500D02*
X708500D01*
G01X696890Y1443450D02*
X699550D01*
X704500Y1438500D01*
X708500D01*
G01X680250Y1458421D02*
X675850D01*
X675550Y1458721D01*
G01X680250Y1452516D02*
X675850D01*
X675550Y1452216D01*
G01X690984Y1463250D02*
Y1465484D01*
X692000Y1466500D01*
Y1471156D01*
G01X692250Y1476000D02*
Y1471406D01*
X692000Y1471156D01*
G01X710750Y1453500D02*
Y1449700D01*
G01X699750Y1452516D02*
X705016D01*
X706000Y1453500D01*
G01D02*
X710750D01*
G01X687047Y1443750D02*
Y1439547D01*
X684750Y1437250D01*
Y1435250D01*
G01D02*
Y1430000D01*
G01X689016Y1443750D02*
Y1439234D01*
X692750Y1435500D01*
G01D02*
Y1430000D01*
G01X689016Y1463250D02*
Y1470684D01*
X687900Y1471800D01*
G01X684750Y1476000D02*
Y1474950D01*
X687900Y1471800D01*
G01X680500Y1476250D02*
X684500D01*
X684750Y1476000D01*
G01X712050Y1467300D02*
X707100D01*
X704600Y1469800D01*
X704000D01*
G01D02*
X701800D01*
X696890Y1464890D01*
Y1463550D01*
G01X710250Y1443500D02*
X708390D01*
X705890Y1446000D01*
G01X700050Y1446610D02*
X705280D01*
X705890Y1446000D01*
G01X676500Y1476250D02*
Y1472150D01*
G01X679950Y1460390D02*
X678110D01*
X676500Y1462000D01*
Y1472150D01*
G01X690984Y1443750D02*
Y1441516D01*
X698500Y1434000D01*
Y1431000D01*
G01X689250Y1430000D02*
Y1433500D01*
G01X685079Y1443750D02*
Y1441579D01*
X681250Y1437750D01*
Y1433500D01*
G01D02*
Y1430000D01*
G01X676500Y1429500D02*
Y1433847D01*
X675499Y1434848D01*
X673964D01*
G01X736597Y1474534D02*
X738732D01*
X740132Y1473134D01*
Y1470734D01*
X737982Y1468584D01*
Y1466234D01*
G01X730232Y1464769D02*
X733167D01*
X734032Y1465634D01*
G01D02*
X734532Y1466134D01*
X737882D01*
X737982Y1466234D01*
G01X731350Y1494250D02*
X720313D01*
X711181Y1485118D01*
G01X694921Y1463250D02*
Y1467821D01*
X702900Y1475800D01*
X712350D01*
G01X708600Y1469900D02*
X710450D01*
X712150Y1471600D01*
G01D02*
X712500Y1471950D01*
Y1475650D01*
X712350Y1475800D01*
G01X738950Y1494250D02*
X746064D01*
G01X744667Y1477094D02*
X747674D01*
X752726Y1482146D01*
Y1490967D01*
X749443Y1494250D01*
X746064D01*
G01X746692Y1444684D02*
X750382D01*
X752132Y1446434D01*
Y1450534D01*
G01D02*
Y1452029D01*
X747027Y1457134D01*
X745368D01*
X745268Y1457234D01*
X743332D01*
G01X676500Y1479750D02*
X672500D01*
G01D02*
Y1485000D01*
G01X691181Y1485118D02*
X695099Y1481200D01*
X715200D01*
X720450Y1486450D01*
X731350D01*
G01X738950D02*
X745406D01*
G01X736597Y1471974D02*
X731526D01*
X728653Y1474847D01*
Y1479425D01*
X731228Y1482000D01*
X747820D01*
X749304Y1483484D01*
Y1485244D01*
X748098Y1486450D01*
X745406D01*
G01X749482Y1465934D02*
Y1467184D01*
X750232Y1467934D01*
Y1472534D01*
G01X749482Y1465934D02*
Y1465119D01*
X752832Y1461769D01*
G01X744667Y1474534D02*
X748232D01*
X750232Y1472534D01*
G01X741572Y1438184D02*
Y1436874D01*
X739532Y1434834D01*
Y1430734D01*
G01X735932Y1454674D02*
X738472D01*
X739240Y1455442D01*
Y1456526D01*
X738532Y1457234D01*
X735932D01*
G01X730232Y1461269D02*
Y1457634D01*
X730332Y1457534D01*
G01X735932Y1457234D02*
X730632D01*
X730332Y1457534D01*
G01X748732Y1460134D02*
X746572D01*
X746232Y1459794D01*
X743332D01*
G01X752832Y1458269D02*
X751097D01*
X749232Y1460134D01*
X748732D01*
G01X824618Y614617D02*
Y610430D01*
X887871Y547177D01*
Y376515D01*
X871192Y359836D01*
Y322500D01*
G01X827750Y611798D02*
X891692Y547856D01*
Y376093D01*
X874562Y358963D01*
Y321680D01*
G01X855400Y744920D02*
X851420D01*
X850900Y744400D01*
X845500D01*
X837900Y752000D01*
Y774300D01*
X822900Y789300D01*
X807959D01*
X804200Y793059D01*
Y798200D01*
G01X855400Y747480D02*
X848220D01*
X841200Y754500D01*
Y775800D01*
X824400Y792600D01*
X814672D01*
X811372Y795900D01*
G01X855400Y750040D02*
X850260D01*
X844800Y755500D01*
Y777088D01*
X823077Y798811D01*
X809283D01*
X808372Y797900D01*
G01X855400Y752600D02*
X852300D01*
X848400Y756500D01*
Y777900D01*
X824489Y801811D01*
X805483D01*
X805372Y801700D01*
G01X1072900Y1204500D02*
X1071643D01*
X1071542Y1204601D01*
X1012558D01*
X995157Y1187200D01*
X980457D01*
X957457Y1164200D01*
X790057D01*
X785457Y1159600D01*
X773400D01*
X773300Y1159700D01*
G01X1084571Y1200129D02*
X1071771D01*
X1070300Y1201600D01*
X1013800D01*
X996400Y1184200D01*
X981700D01*
X958700Y1161200D01*
X791300D01*
X786600Y1156500D01*
X769800D01*
G01X1072600Y1211400D02*
X1071801Y1210601D01*
X1010072D01*
X992671Y1193200D01*
X977971D01*
X954971Y1170200D01*
X787571D01*
X783728Y1166357D01*
X780722D01*
G01X1084400Y1204200D02*
X1080999Y1207601D01*
X1011315D01*
X993914Y1190200D01*
X979214D01*
X956214Y1167200D01*
X788814D01*
X784414Y1162800D01*
X780000D01*
G01X890552Y268504D02*
X887296D01*
X884770Y271030D01*
Y316476D01*
X926000Y357706D01*
Y364100D01*
X913500Y376600D01*
Y562800D01*
X875007Y601293D01*
G01X890552Y277165D02*
X886770Y280947D01*
Y315241D01*
X947608Y376079D01*
Y381208D01*
X980100Y413700D01*
G01X893052Y317932D02*
Y317933D01*
X902632Y327513D01*
X906658D01*
X1005047Y425902D01*
Y428635D01*
X1005846Y429434D01*
G01X875007Y601293D02*
X874567D01*
X867260Y608600D01*
G01X927750Y763820D02*
Y760070D01*
X927000Y759320D01*
G01D02*
X925220D01*
X923150Y757250D01*
X922100D01*
G01D02*
X916951D01*
G01D02*
X912475D01*
X910875Y758850D01*
G01X925400Y769720D02*
Y766170D01*
X927750Y763820D01*
G01X898400Y1201100D02*
X890600D01*
X890500Y1201200D01*
G01X898400Y1206220D02*
X894915D01*
X894591Y1205896D01*
X886975D01*
X885930Y1206941D01*
Y1210537D01*
G01X898400Y1211340D02*
X892460D01*
G01X898400Y1216460D02*
X887200D01*
G01X898400Y1203660D02*
X893200D01*
G01X898400Y1208780D02*
X889342D01*
X888825Y1208263D01*
G01X898400Y1213900D02*
X890036D01*
X890000Y1213936D01*
X889965D01*
G01X898400Y1219020D02*
X884686D01*
X884677Y1219029D01*
G01X960475Y1192875D02*
X956600Y1189000D01*
X935900D01*
X934200Y1190700D01*
G01X920600Y1198540D02*
X923660D01*
X926800Y1195400D01*
X929500D01*
X934200Y1190700D01*
G01X920600Y1203660D02*
X928640D01*
X934271Y1198029D01*
G01X955000Y1191700D02*
X954400Y1191100D01*
X941200D01*
X934271Y1198029D01*
G01X920600Y1208780D02*
X935120D01*
X942955Y1200945D01*
G01X948500Y1199500D02*
X944400D01*
X942955Y1200945D01*
G01X920600Y1213900D02*
X937600D01*
X940168Y1211332D01*
G01X943000Y1208500D02*
X940168Y1211332D01*
G01X870125Y1198150D02*
X868900Y1196925D01*
Y1192600D01*
G01D02*
Y1188250D01*
G01D02*
X873300D01*
X873450Y1188400D01*
G01X874000Y1205650D02*
X881650D01*
X885118Y1202182D01*
G01X898400Y1198540D02*
X891640D01*
X891500Y1198400D01*
X891395D01*
X890345Y1197350D01*
X888000D01*
G01D02*
Y1199300D01*
X885118Y1202182D01*
G01X920600Y1201100D02*
X924600D01*
X926700Y1199000D01*
G01X920600Y1206220D02*
X931900D01*
G01X952500Y1195500D02*
X943200D01*
X932480Y1206220D01*
X931900D01*
G01X943000Y1205000D02*
X936660Y1211340D01*
X927500D01*
G01D02*
X920600D01*
G01Y1216460D02*
X933200D01*
G01X944500Y1211000D02*
X939040Y1216460D01*
X933200D01*
G01X869937Y1390379D02*
Y1395977D01*
G01D02*
Y1400312D01*
G01X954488Y1412818D02*
X958738D01*
G01X941559Y1408198D02*
X943150Y1406607D01*
X945822D01*
X949997Y1402432D01*
X950819D01*
X951569Y1403182D01*
G01X955300Y1403400D02*
X953542D01*
X953324Y1403182D01*
X951569D01*
G01X941559Y1403198D02*
X942968Y1404607D01*
X944993D01*
X949168Y1400432D01*
X950668D01*
X951418Y1399682D01*
X951569D01*
G01X955300Y1399400D02*
X953411D01*
X953129Y1399682D01*
X951569D01*
G01X948099Y1356976D02*
X959153D01*
X963421Y1361244D01*
Y1392336D01*
X961857Y1393900D01*
G01X954488Y1429318D02*
X958738D01*
G01X957266Y1449272D02*
X954418D01*
X950543Y1453147D01*
X949766D01*
G01X966465Y1454578D02*
X963413D01*
X958107Y1449272D01*
X957266D01*
G01X944016Y1445522D02*
X944141Y1445397D01*
X949766D01*
G01X966438Y1450158D02*
X962863D01*
X958102Y1445397D01*
X949766D01*
G01X980100Y413700D02*
X1008058Y441658D01*
X1019949D01*
X1021539Y440068D01*
X1021890D01*
Y439717D01*
G01X1005846Y429434D02*
X1010791Y434379D01*
X1025357D01*
X1043278Y452300D01*
X1098100D01*
X1103100Y457300D01*
G01X993647Y903465D02*
Y901500D01*
X993483Y901336D01*
Y899206D01*
G01D02*
Y896539D01*
X993547Y896475D01*
Y895165D01*
X993647Y895065D01*
G01X1002940Y878330D02*
Y886560D01*
X998335Y891165D01*
X993674D01*
G01X993647Y895065D02*
Y891192D01*
X993674Y891165D01*
G01X1005500Y878330D02*
Y888075D01*
X1004300Y889275D01*
G01X1004057Y903075D02*
Y899075D01*
G01Y895075D02*
Y889518D01*
X1004300Y889275D01*
G01X1004057Y899075D02*
Y895075D01*
G01X1008031Y903075D02*
Y899075D01*
G01X1008060Y878330D02*
Y883460D01*
X1009800Y885200D01*
Y887100D01*
G01D02*
Y889400D01*
X1008091Y891109D01*
Y895045D01*
G01X1008031Y899075D02*
Y895105D01*
X1008091Y895045D01*
G01X1018289Y900965D02*
Y896965D01*
G01X1010620Y878330D02*
Y882620D01*
X1014500Y886500D01*
X1016400D01*
G01D02*
X1018383Y888483D01*
Y892965D01*
G01X1018289Y896965D02*
X1018383Y896871D01*
Y892965D01*
G01X1013180Y878330D02*
Y882180D01*
X1014500Y883500D01*
X1018700D01*
X1021500Y886300D01*
Y886500D01*
G01X1033315Y890831D02*
X1033000Y890516D01*
Y887600D01*
X1032131Y886731D01*
X1030515D01*
G01X1026515D02*
X1021731D01*
X1021500Y886500D01*
G01X1030515Y886731D02*
X1026515D01*
G01X1017007Y933625D02*
Y939030D01*
X1024129Y946152D01*
G01X1008739Y1096000D02*
X1010910D01*
X1031610Y1075300D01*
X1154800D01*
X1155600Y1074500D01*
G01X1029500Y1104900D02*
X1027200Y1107200D01*
Y1116900D01*
X1028500Y1118200D01*
Y1118601D01*
G01X1011250Y1117500D02*
Y1120550D01*
X1012800Y1122100D01*
G01X1007750Y1117500D02*
X1007684Y1117566D01*
Y1122647D01*
X1007431Y1122900D01*
G01X1025443Y1431399D02*
Y1427649D01*
X1024193Y1426399D01*
G01D02*
Y1422899D01*
G01X1010943Y1417149D02*
Y1413899D01*
G01X1005943Y1410149D02*
Y1406700D01*
G01X975443Y1411149D02*
Y1407700D01*
G01X992443Y1410149D02*
Y1406700D01*
G01X1000443Y1410149D02*
Y1406700D01*
G01X988443Y1410149D02*
Y1406700D01*
G01X996443Y1410149D02*
Y1406800D01*
G01X983943Y1411399D02*
Y1407399D01*
G01X979443Y1411149D02*
Y1406999D01*
G01X1002364Y1431649D02*
Y1429478D01*
X1005943Y1425899D01*
X1008443D01*
G01X1010943Y1420649D02*
Y1423399D01*
X1008443Y1425899D01*
G01X1004333Y1431349D02*
X1006993D01*
X1011943Y1426399D01*
X1015943D01*
G01X1020693D02*
X1015943D01*
G01X987393Y1434509D02*
Y1432768D01*
X984311Y1429686D01*
X978790D01*
X970552Y1421448D01*
G01X963238Y1414068D02*
X965196D01*
X967821Y1416693D01*
Y1418717D01*
X970552Y1421448D01*
G01X958738Y1412818D02*
X959988Y1414068D01*
X963238D01*
G01X958800Y1403400D02*
X960000Y1402200D01*
X963229D01*
X965421Y1400008D01*
Y1395464D01*
X966985Y1393900D01*
G01X980501Y1356976D02*
X969424D01*
X965421Y1360979D01*
Y1392336D01*
X966985Y1393900D01*
G01X958800Y1399400D02*
X959600Y1400200D01*
X962400D01*
X963421Y1399179D01*
Y1395464D01*
X961857Y1393900D01*
G01X987693Y1436478D02*
X985478D01*
X982135Y1433135D01*
X979163D01*
X972860Y1426832D01*
X971169D01*
G01X963238Y1428068D02*
X967961D01*
X969197Y1426832D01*
X971169D01*
G01X958738Y1429318D02*
X961988D01*
X963238Y1428068D01*
G01X992800Y1422300D02*
Y1426100D01*
X993300Y1426600D01*
G01X994490Y1431649D02*
Y1427790D01*
X993300Y1426600D01*
G01X992800Y1422300D02*
X992193Y1421693D01*
Y1417899D01*
G01X992443Y1413649D02*
X988443D01*
G01X992193Y1417899D02*
Y1413899D01*
X992443Y1413649D01*
G01X1000193Y1423399D02*
Y1417899D01*
G01X996459Y1431649D02*
Y1427133D01*
X1000193Y1423399D01*
G01X1000443Y1413649D02*
X996443D01*
G01X1000193Y1417899D02*
Y1413899D01*
X1000443Y1413649D01*
G01X990553Y1431349D02*
X989305D01*
X984984Y1427028D01*
X980128D01*
X979900Y1426800D01*
G01X975443Y1414649D02*
X979443D01*
G01X975443D02*
Y1418449D01*
X975693Y1418699D01*
G01D02*
Y1422593D01*
X979900Y1426800D01*
G01X998427Y1431649D02*
Y1429415D01*
X1005943Y1421899D01*
Y1418899D01*
G01Y1413649D02*
Y1418899D01*
G01X996693Y1417899D02*
Y1421399D01*
G01X988693Y1417899D02*
Y1421399D01*
G01X987600Y1425200D02*
Y1422492D01*
X988693Y1421399D01*
G01X989922Y1426878D02*
X989278D01*
X987600Y1425200D01*
G01X992522Y1431649D02*
Y1429478D01*
X989922Y1426878D01*
G01X988693Y1417899D02*
X986931D01*
X986431Y1417399D01*
X983943D01*
G01D02*
X980493D01*
X979193Y1418699D01*
G01X1021193Y1431399D02*
X1025443D01*
G01X1002118Y1467615D02*
Y1471365D01*
G01X998325Y1467684D02*
Y1471434D01*
G01X994490Y1451149D02*
Y1444352D01*
X997443Y1441399D01*
G01X969443Y1436399D02*
X965443D01*
G01X987693Y1446320D02*
X982643D01*
X982343Y1446620D01*
G01X987693Y1440415D02*
X982643D01*
X982343Y1440115D01*
G01X961877Y1445347D02*
X962824Y1444400D01*
X964094D01*
X965093Y1445399D01*
G01X961877Y1441451D02*
X962826Y1442400D01*
X964092D01*
X965093Y1441399D01*
G01X998427Y1451149D02*
Y1453383D01*
X999443Y1454399D01*
Y1458006D01*
G01X1002118Y1464115D02*
X999443Y1461440D01*
Y1458006D01*
G01X1007193Y1440415D02*
X1017427D01*
X1018943Y1438899D01*
G01X1024883Y1438149D02*
X1019693D01*
X1018943Y1438899D01*
G01X987693Y1438446D02*
X985063D01*
X983016Y1436399D01*
X982052D01*
G01X996459Y1451149D02*
Y1458674D01*
X995617Y1459516D01*
G01D02*
X994271Y1460862D01*
Y1464167D01*
G01D02*
X998308D01*
X998325Y1464184D01*
G01X1004333Y1451449D02*
X1006549D01*
X1011249Y1456149D01*
X1018402D01*
X1021618Y1459365D01*
Y1460000D01*
G01D02*
Y1464115D01*
G01X1007493Y1434509D02*
X1012723D01*
X1013333Y1433899D01*
G01X1017693Y1431399D02*
X1015833D01*
X1013333Y1433899D01*
G01X979179Y1450158D02*
X975438D01*
G01X987393Y1448289D02*
X984661D01*
X982792Y1450158D01*
X979179D01*
G01X1017618Y1460865D02*
Y1464115D01*
G01X1007618Y1465065D02*
X1012668D01*
X1013618Y1464115D01*
G01X1017618D02*
X1013618D01*
G01X1002364Y1451149D02*
Y1454820D01*
X1007618Y1460074D01*
Y1465065D01*
G01X1030003Y1444649D02*
X1033253D01*
G01X1015550Y1496214D02*
Y1494614D01*
X1017350Y1492814D01*
X1020500D01*
G01X1045300Y1496914D02*
Y1503364D01*
X1043650Y1505014D01*
X1020050D01*
X1015550Y1500514D01*
Y1496214D01*
G01X1035038Y1471891D02*
X1031190Y1475739D01*
X1025325D01*
X1020500Y1480564D01*
Y1492814D01*
G01X1024000Y1496814D02*
X1027750D01*
X1028650Y1495914D01*
Y1494714D01*
G01X1028050Y1479564D02*
Y1488114D01*
X1024000Y1492164D01*
Y1492814D01*
G01D02*
X1027950D01*
X1028650Y1493514D01*
Y1494714D01*
G01X1039450Y1501914D02*
X1041250D01*
X1041800Y1501364D01*
Y1496914D01*
G01X1039450Y1501914D02*
X1038500D01*
X1037600Y1501014D01*
Y1496914D01*
G01D02*
Y1492814D01*
G01X1041800Y1496914D02*
Y1492814D01*
G01X1034100D02*
X1037350Y1489564D01*
Y1487714D01*
G01X1031925Y1487064D02*
X1036700D01*
X1037350Y1487714D01*
G01X966465Y1454578D02*
X970518D01*
X971438Y1453658D01*
G01D02*
X975438D01*
G01X971438Y1450158D02*
X966438D01*
G01X987693Y1444352D02*
X979240D01*
X978443Y1445149D01*
G01X973617Y1445912D02*
X972117Y1444412D01*
X969580D01*
X968593Y1445399D01*
G01X978443Y1445149D02*
X977043D01*
X976306Y1444412D01*
X975117D01*
X973617Y1445912D01*
G01X987693Y1442383D02*
X984179D01*
X984148Y1442352D01*
X979146D01*
X978443Y1441649D01*
G01X973617Y1440912D02*
X972117Y1442412D01*
X969606D01*
X968593Y1441399D01*
G01X978443Y1441649D02*
X977002D01*
X976239Y1442412D01*
X975117D01*
X973617Y1440912D01*
G01X1112682Y681223D02*
X1131844D01*
X1137651Y687030D01*
X1184654D01*
X1207265Y709641D01*
G01X1179129Y672187D02*
X1142868D01*
X1141230Y673825D01*
G01X1207265Y709641D02*
X1215541Y717917D01*
Y800189D01*
X1193029Y822701D01*
Y854030D01*
X1215541Y876542D01*
Y918567D01*
X1215542Y918568D01*
Y920918D01*
X1204963Y931497D01*
X1165713D01*
X1125210Y972000D01*
X1093588D01*
G01X1110600Y964200D02*
X1108086D01*
X1103586Y959700D01*
X1098911D01*
X1070638Y931427D01*
Y899840D01*
X1083578Y886900D01*
X1111869D01*
X1115105Y890136D01*
G01X1108500Y960600D02*
Y959400D01*
X1105800Y956700D01*
X1100154D01*
X1073638Y930184D01*
Y901083D01*
X1081056Y893665D01*
X1106064D01*
X1109593Y890136D01*
G01X1075706Y941261D02*
X1067337Y932892D01*
Y893418D01*
X1081170Y879585D01*
X1112260D01*
X1113530Y880855D01*
Y883049D01*
G01X1093900Y1304820D02*
X1087100D01*
G01X1083100Y1305600D02*
X1079955D01*
X1078850Y1304495D01*
G01D02*
X1080345Y1303000D01*
X1085280D01*
X1087100Y1304820D01*
G01X1093900Y1299700D02*
X1085925D01*
X1083125Y1296900D01*
X1081325D01*
X1078850Y1299375D01*
G01D02*
X1082080D01*
G01X1116100Y1292025D02*
X1126425D01*
X1126750Y1291700D01*
G01D02*
Y1288570D01*
X1126820Y1288500D01*
G01X1086062Y1294580D02*
X1093900D01*
G01X1086062D02*
X1085237Y1293755D01*
X1080145D01*
X1078850Y1292460D01*
G01D02*
Y1287900D01*
G01X1082080Y1309495D02*
X1078850D01*
G01X1082080D02*
X1085962D01*
G01X1093900Y1302260D02*
X1098060D01*
X1099200Y1303400D01*
Y1306000D01*
X1097825Y1307375D01*
X1093900D01*
G01D02*
X1090725D01*
X1088605Y1309495D01*
X1085962D01*
G01X1123000Y1297600D02*
X1125850D01*
X1126750Y1296700D01*
G01X1116100Y1294580D02*
X1119180D01*
X1119700Y1295100D01*
X1125150D01*
X1126750Y1296700D01*
G01X1093900Y1297140D02*
X1109060D01*
X1111620Y1294580D01*
X1116100D01*
G01X1060118Y1384839D02*
X1060283Y1385004D01*
X1063935D01*
X1063920Y1385019D01*
G01D02*
X1067459D01*
X1067712Y1384766D01*
G01X1104760Y1343815D02*
Y1346740D01*
X1100300Y1351200D01*
Y1359247D01*
G01X1111750Y1358500D02*
X1108750Y1361500D01*
X1102553D01*
X1100300Y1359247D01*
G01X1121462Y1403723D02*
X1124912Y1407173D01*
X1133412D01*
G01D02*
X1162224D01*
X1171964Y1397433D01*
X1178712D01*
G01Y1392313D02*
X1148860D01*
X1145212Y1395961D01*
Y1396002D01*
X1141554Y1399660D01*
G01X1128612Y1403873D02*
X1137341D01*
X1141554Y1399660D01*
G01X1147312Y1387193D02*
X1178712D01*
G01X1133112Y1396773D02*
X1136712D01*
X1146292Y1387193D01*
X1147312D01*
G01X1147512Y1382073D02*
X1178712D01*
G01X1138612Y1387773D02*
X1144312Y1382073D01*
X1147512D01*
G01X1178712Y1389753D02*
X1147632D01*
X1144564Y1392821D01*
G01X1129112Y1400773D02*
X1136612D01*
X1144564Y1392821D01*
G01X1178712Y1384633D02*
X1145252D01*
X1140175Y1389710D01*
G01X1138612Y1391273D02*
X1140175Y1389710D01*
G01X1178712Y1379513D02*
X1142272D01*
X1140512Y1381273D01*
G01X1137112Y1384673D02*
X1140512Y1381273D01*
G01X1242718Y335091D02*
Y260355D01*
G01X1238778Y312593D02*
Y260355D01*
G01X1242718Y254605D02*
X1252705D01*
X1257000Y258900D01*
Y355500D01*
G01X1238778Y254605D02*
Y252322D01*
X1243300Y247800D01*
X1253700D01*
X1261060Y255160D01*
Y300000D01*
G01X1248500Y383500D02*
Y362427D01*
X1242718Y356645D01*
Y335091D01*
G01X1243500Y383500D02*
Y363000D01*
X1238778Y358278D01*
Y312593D01*
G01X1242718Y713111D02*
Y820846D01*
G01X1238778Y713111D02*
Y798348D01*
G01X1242718Y707361D02*
Y702949D01*
X1240869Y701100D01*
X1233969D01*
X1229675Y705394D01*
Y805894D01*
X1216569Y819000D01*
G01X1227969Y841750D02*
Y839131D01*
X1232675Y834425D01*
Y738300D01*
G01X1238778Y707361D02*
X1234239D01*
X1232675Y708925D01*
Y738300D01*
G01X1243462Y836188D02*
X1242718Y835444D01*
Y820846D01*
G01X1238462Y836188D02*
X1238778Y835872D01*
Y798348D01*
G01X1209611Y845907D02*
Y825958D01*
X1216569Y819000D01*
G01X1197394Y1298415D02*
Y1306733D01*
G01X1193894Y1292533D02*
X1197394D01*
G01D02*
Y1298415D01*
G01X1230600Y1306733D02*
Y1298415D01*
G01X1227100Y1292533D02*
X1230600D01*
G01D02*
Y1298415D01*
G01X1202394D02*
Y1306733D01*
G01X1205624Y1292533D02*
X1202394D01*
G01D02*
Y1298415D01*
G01X1235600Y1306733D02*
Y1298415D01*
G01X1238830Y1292533D02*
X1235600D01*
G01D02*
Y1298415D01*
G01X1192394Y1335151D02*
Y1326833D01*
G01X1225600D02*
Y1335151D01*
G01X1185324Y1286563D02*
Y1289124D01*
X1188733Y1292533D01*
X1190524D01*
G01X1192394Y1306733D02*
Y1298415D01*
G01D02*
X1192100Y1298121D01*
Y1294109D01*
X1190524Y1292533D01*
G01X1225600Y1306733D02*
Y1298415D01*
G01D02*
X1225400Y1298215D01*
Y1294203D01*
X1223730Y1292533D01*
G01D02*
X1220450D01*
G01X1187394Y1335151D02*
Y1326833D01*
G01X1220600Y1335151D02*
Y1326833D01*
G01X1188894Y1343533D02*
Y1346763D01*
G01Y1340033D02*
X1192394Y1336533D01*
Y1335151D01*
G01X1222100Y1343533D02*
Y1346600D01*
X1222000Y1346700D01*
G01X1222100Y1340033D02*
X1225600Y1336533D01*
Y1335151D01*
G01X1180614Y1340033D02*
X1183894D01*
G01D02*
X1187394Y1336533D01*
Y1335151D01*
G01X1213820Y1340033D02*
X1217100D01*
G01D02*
X1220600Y1336533D01*
Y1335151D01*
G01X1200912Y1394873D02*
X1266914D01*
G01X1200912Y1389753D02*
X1258187D01*
G01X1200912Y1384633D02*
X1253165D01*
G01X1200912Y1379513D02*
X1246949D01*
G01X1200912Y1392313D02*
X1263642D01*
G01X1200912Y1387193D02*
X1261224D01*
G01X1200912Y1382073D02*
X1250347D01*
G01X1200912Y1376953D02*
X1243768D01*
G01X1213721Y1415053D02*
Y1421564D01*
X1212460Y1422825D01*
G01D02*
X1210681Y1424604D01*
X1207440D01*
G01X1203487Y1424691D02*
X1203574Y1424604D01*
X1207440D01*
G01X1209846Y1407553D02*
X1210762Y1406637D01*
Y1401814D01*
G01D02*
Y1398695D01*
X1209500Y1397433D01*
G01D02*
X1200912D01*
G01X1169412Y1396873D02*
X1171412Y1394873D01*
X1178712D01*
G01X1237953Y1485118D02*
X1234874Y1482039D01*
Y1473200D01*
G01X1259374Y1501400D02*
X1252400D01*
X1243274Y1492274D01*
Y1474000D01*
X1242474Y1473200D01*
G01X1217953Y1485118D02*
Y1473821D01*
X1226274Y1465500D01*
X1234874D01*
G01X1242474D02*
X1246874Y1469900D01*
Y1486270D01*
X1251404Y1490800D01*
X1251574D01*
G01X1255445Y392994D02*
Y368155D01*
X1257000Y366600D01*
Y355500D01*
G01X1333824Y393151D02*
Y372987D01*
X1342880Y363931D01*
G01X1273803Y388837D02*
Y348015D01*
X1261060Y335272D01*
Y300000D01*
G01X1333824Y845907D02*
Y825958D01*
X1350982Y808800D01*
Y737700D01*
G01X1279484Y1471500D02*
X1277274D01*
X1273874Y1468100D01*
Y1423000D01*
G01X1314375Y1429250D02*
Y1424375D01*
G01X1281624Y1425618D02*
Y1430000D01*
X1285624Y1434000D01*
G01X1281624Y1409209D02*
Y1425618D01*
G01X1277624Y1416318D02*
Y1444500D01*
X1285624Y1452500D01*
G01X1277624Y1409209D02*
Y1416318D01*
G01X1279484Y1471500D02*
X1284624D01*
G01X1256939Y1493400D02*
X1259575D01*
X1260374Y1492601D01*
Y1485350D01*
X1259924Y1484900D01*
G01X1255974Y1484800D02*
X1255609Y1484435D01*
X1251874D01*
G01X1255974Y1484800D02*
X1259824D01*
X1259924Y1484900D01*
G01X1331496Y1466929D02*
X1322625Y1475800D01*
X1292424D01*
X1288124Y1471500D01*
G01X1331496Y1445275D02*
Y1466929D01*
G01X1291874Y1457000D02*
X1292124Y1457250D01*
X1296374D01*
G01D02*
X1300374D01*
G01D02*
X1300524Y1457400D01*
Y1464000D01*
G01X1314960Y1466929D02*
X1314789Y1467100D01*
X1303624D01*
X1300524Y1464000D01*
G01X1291874Y1438500D02*
X1292124Y1438750D01*
X1296374D01*
G01D02*
X1300374D01*
G01D02*
X1300524Y1438900D01*
Y1445500D01*
G01X1314960Y1445275D02*
X1314735Y1445500D01*
X1300524D01*
G01X1265009Y1495960D02*
Y1498165D01*
X1261774Y1501400D01*
X1259374D01*
G01X1264734Y1464050D02*
X1267524D01*
X1269974Y1466500D01*
Y1469300D01*
G01X1264774Y1476400D02*
X1268074D01*
X1269974Y1474500D01*
Y1469300D01*
G01X1285874Y1438500D02*
X1285624Y1438250D01*
Y1434000D01*
G01X1285874Y1457000D02*
X1285624Y1456750D01*
Y1452500D01*
G01X1256939Y1490840D02*
X1251614D01*
X1251574Y1490800D01*
G01X1271324Y1488600D02*
Y1492550D01*
X1270574Y1493300D01*
G01X1271324Y1488600D02*
Y1487450D01*
X1274839Y1483935D01*
Y1483400D01*
G01X1265009Y1493400D02*
X1266574D01*
X1267074Y1493900D01*
X1269974D01*
X1270574Y1493300D01*
G01X1262174Y1457550D02*
Y1454200D01*
X1262774Y1453600D01*
Y1449300D01*
G01D02*
Y1447800D01*
X1260574Y1445600D01*
G01X1259614Y1457550D02*
Y1454340D01*
X1257874Y1452600D01*
Y1450500D01*
G01D02*
Y1447400D01*
X1256474Y1446000D01*
G01X1257374Y1473840D02*
X1260214D01*
X1260882Y1474508D01*
Y1475692D01*
X1260174Y1476400D01*
X1257374D01*
G01X1251874Y1480935D02*
Y1477400D01*
X1252274Y1477000D01*
G01X1257374Y1476400D02*
X1252874D01*
X1252274Y1477000D01*
G01X1271339Y1483400D02*
Y1480165D01*
X1270674Y1479500D01*
G01X1264774Y1478960D02*
X1270134D01*
X1270674Y1479500D01*
G01X1366931Y260355D02*
Y359435D01*
G01X1362991Y260355D02*
Y336937D01*
G01X1366931Y254605D02*
Y250193D01*
X1365082Y248344D01*
X1358756D01*
X1355498Y251602D01*
Y351313D01*
X1342880Y363931D01*
G01X1362991Y254605D02*
X1359235D01*
X1358498Y255342D01*
Y307500D01*
G01X1367500Y387500D02*
Y375764D01*
X1366931Y375195D01*
Y359435D01*
G01X1362500Y387500D02*
Y375212D01*
X1362991Y374721D01*
Y336937D01*
G01X1352182Y388994D02*
Y368925D01*
X1358498Y362609D01*
Y307500D01*
G01X1366931Y713111D02*
Y820844D01*
G01X1362991Y713111D02*
Y798346D01*
G01X1366931Y707361D02*
Y702949D01*
X1365082Y701100D01*
X1358182D01*
X1350982Y708300D01*
Y737700D01*
G01X1362991Y707361D02*
X1357321D01*
X1354742Y709940D01*
Y764100D01*
G01X1367500Y841000D02*
Y830084D01*
X1366931Y829515D01*
Y820844D01*
G01X1362500Y841000D02*
Y830419D01*
X1362991Y829928D01*
Y798346D01*
G01X1352182Y841750D02*
Y815788D01*
X1354742Y813228D01*
Y764100D01*
G01X1491143Y260355D02*
Y364938D01*
G01X1487203Y260355D02*
Y342440D01*
G01X1491143Y254605D02*
Y250193D01*
X1489294Y248344D01*
X1482394D01*
X1475194Y255544D01*
Y356044D01*
X1464994Y366244D01*
G01X1487203Y254605D02*
X1481533D01*
X1478954Y257184D01*
Y299400D01*
G01X1492000Y387500D02*
Y375486D01*
X1491143Y374629D01*
Y364938D01*
G01X1487000Y387500D02*
Y374860D01*
X1487203Y374657D01*
Y342440D01*
G01X1458036Y393151D02*
Y373202D01*
X1464994Y366244D01*
G01X1476394Y388994D02*
Y383692D01*
X1478954Y381132D01*
Y299400D01*
G01X1491143Y713111D02*
Y821350D01*
G01X1487203Y713111D02*
Y798852D01*
G01X1491143Y707361D02*
Y702949D01*
X1489294Y701100D01*
X1482394D01*
X1473394Y710100D01*
Y810600D01*
X1464994Y819000D01*
G01X1487203Y707361D02*
X1481533D01*
X1476394Y712500D01*
Y827894D01*
X1476400Y827900D01*
G01X1492000Y840500D02*
Y830627D01*
X1491143Y829770D01*
Y821350D01*
G01X1487000Y840500D02*
Y830382D01*
X1487203Y830179D01*
Y798852D01*
G01X1458036Y845907D02*
Y825732D01*
X1458262D01*
X1464994Y819000D01*
G01X1476394Y841750D02*
Y827906D01*
X1476400Y827900D01*
G01X1615356Y260355D02*
Y363164D01*
G01X1611416Y260355D02*
Y340666D01*
G01X1615356Y254605D02*
Y250193D01*
X1613507Y248344D01*
X1606607D01*
X1599407Y255544D01*
Y356044D01*
X1589207Y366244D01*
G01X1611416Y254605D02*
X1605746D01*
X1603167Y257184D01*
Y304800D01*
G01X1616000Y387500D02*
Y373499D01*
X1615356Y372855D01*
Y363164D01*
G01X1611000Y387500D02*
Y373613D01*
X1611416Y373197D01*
Y340666D01*
G01X1582249Y393151D02*
Y373202D01*
X1589207Y366244D01*
G01X1600607Y388994D02*
Y376957D01*
X1603167Y374397D01*
Y304800D01*
G01X1615356Y713111D02*
Y822490D01*
G01X1611416Y713111D02*
Y799992D01*
G01X1615356Y707361D02*
Y702949D01*
X1614107Y701700D01*
X1606007D01*
X1597607Y710100D01*
Y763144D01*
G01X1611416Y707361D02*
X1605746D01*
X1600607Y712500D01*
Y824639D01*
G01X1616000Y840500D02*
Y835051D01*
X1615356Y834407D01*
Y822490D01*
G01X1611000Y840500D02*
Y834972D01*
X1611416Y834556D01*
Y799992D01*
G01X1582249Y845907D02*
Y825958D01*
X1597607Y810600D01*
Y763144D01*
G01X1600607Y824639D02*
Y841750D01*
G01X1726859Y478707D02*
X1725859Y479707D01*
X1711259D01*
X1708259Y476707D01*
Y464619D01*
X1709496Y463382D01*
G01X1714109Y457707D02*
X1715459D01*
X1717859Y460107D01*
G01D02*
Y463907D01*
G01X1718159Y467457D02*
Y464207D01*
X1717859Y463907D01*
G01X1711909Y470207D02*
Y468207D01*
X1714026Y466090D01*
Y464191D01*
G01X1711909Y470207D02*
Y475007D01*
G01X1710609Y457707D02*
Y453767D01*
X1711199Y453177D01*
G01X1706461Y845907D02*
Y825958D01*
X1723619Y808800D01*
Y777600D01*
G01X1651906Y1428973D02*
Y1447500D01*
G01X1702501Y1429250D02*
Y1434000D01*
G01X1663906Y1428973D02*
X1665876Y1430943D01*
Y1434000D01*
G01X1659906Y1428973D02*
Y1435500D01*
G01X1652510Y1453250D02*
Y1448104D01*
X1651906Y1447500D01*
G01X1711811Y1445275D02*
Y1466929D01*
G01X1652510Y1456750D02*
X1656250D01*
X1659500Y1460000D01*
Y1467000D01*
X1668000Y1475500D01*
X1703240D01*
X1711811Y1466929D01*
G01X1672126Y1457000D02*
X1672376Y1457250D01*
X1676626D01*
G01D02*
X1680626D01*
G01D02*
X1680776Y1457400D01*
Y1464000D01*
G01X1695275Y1466929D02*
X1692346Y1464000D01*
X1680776D01*
G01X1672126Y1438500D02*
X1672376Y1438750D01*
X1676626D01*
G01D02*
X1680626D01*
G01D02*
Y1445350D01*
X1680776Y1445500D01*
G01X1695275Y1445275D02*
X1695050Y1445500D01*
X1680776D01*
G01X1666126Y1438500D02*
X1665876Y1438250D01*
Y1434000D01*
G01X1666126Y1457000D02*
Y1452750D01*
X1665876Y1452500D01*
G01X1659906Y1435500D02*
Y1446530D01*
X1665876Y1452500D01*
G01X1739568Y260355D02*
Y361896D01*
G01X1735628Y260355D02*
Y339398D01*
G01X1749650Y376854D02*
Y367084D01*
X1744229Y361663D01*
Y256081D01*
X1742753Y254605D01*
X1739568D01*
G01X1735628D02*
Y252168D01*
X1737808Y249988D01*
X1743562D01*
X1748246Y254672D01*
Y359346D01*
X1763791Y374891D01*
G01X1740000Y387500D02*
Y374747D01*
X1739568Y374315D01*
Y361896D01*
G01X1735000Y387500D02*
Y374393D01*
X1735628Y373765D01*
Y339398D01*
G01X1749650Y376854D02*
Y377153D01*
X1749634Y377169D01*
Y388793D01*
G01X1863781Y254605D02*
Y251881D01*
X1862100Y250200D01*
X1855200D01*
X1847700Y257700D01*
Y322500D01*
X1804600Y365600D01*
G01X1797642Y393507D02*
Y372558D01*
X1804600Y365600D01*
G01X1763791Y374891D02*
Y388797D01*
G01X1816000Y389350D02*
Y361170D01*
X1852223Y324947D01*
Y303000D01*
G01X1922400Y470400D02*
X1920445Y468445D01*
X1860526D01*
X1852579Y460498D01*
X1818902D01*
X1814100Y465300D01*
X1767365D01*
X1761761Y470904D01*
Y479256D01*
X1760321Y480696D01*
X1751615D01*
X1750409Y479490D01*
Y477607D01*
G01X1740906Y465239D02*
X1740859Y465286D01*
Y469207D01*
G01X1738609Y473707D02*
Y475207D01*
X1737859Y475957D01*
Y478707D01*
G01X1740859Y469207D02*
X1738609Y471457D01*
Y473707D01*
G01X1726859Y478707D02*
X1728210Y477356D01*
Y474022D01*
X1730241Y471991D01*
Y471049D01*
G01D02*
X1730243Y471047D01*
Y466983D01*
G01X1726743D02*
X1731602Y462124D01*
X1735120D01*
X1737701Y464705D01*
G01X1746859Y465707D02*
X1746868Y465716D01*
Y469232D01*
G01X1737701Y464705D02*
X1739999Y462407D01*
X1743559D01*
X1746859Y465707D01*
G01X1756859Y477207D02*
X1752859Y473207D01*
X1748459D01*
X1746868Y471616D01*
Y469232D01*
G01X1722296Y467512D02*
Y466144D01*
X1724096Y464344D01*
G01X1746909Y477607D02*
X1746559Y477957D01*
X1742859D01*
G01D02*
X1742109Y478707D01*
X1737859D01*
G01X1739568Y828517D02*
Y713111D01*
G01X1735628D02*
Y802019D01*
G01X1739568Y707361D02*
Y702949D01*
X1737719Y701100D01*
X1727100D01*
X1723619Y704581D01*
Y777600D01*
G01X1735628Y707361D02*
X1729239D01*
X1727379Y709221D01*
Y764235D01*
G01X1740000Y840500D02*
Y835601D01*
X1739568Y835169D01*
Y828517D01*
G01X1735000Y840500D02*
Y835056D01*
X1735628Y834428D01*
Y802019D01*
G01X1724819Y841750D02*
Y833741D01*
X1727379Y831181D01*
Y764235D01*
G01X1812263Y913025D02*
Y910275D01*
X1813013Y909525D01*
Y908025D01*
G01X1812263Y913025D02*
X1816513D01*
X1817263Y912275D01*
G01X1813013Y908025D02*
Y905775D01*
X1815263Y903525D01*
G01D02*
Y899604D01*
X1815310Y899557D01*
G01X1783900Y897700D02*
X1782663Y898937D01*
Y911025D01*
X1785663Y914025D01*
X1800263D01*
X1801263Y913025D01*
G01X1804647Y901301D02*
Y905365D01*
X1804645Y905367D01*
G01D02*
Y906309D01*
X1802614Y908340D01*
Y911674D01*
X1801263Y913025D01*
G01X1821263Y900025D02*
X1817804Y896566D01*
X1814562D01*
X1812105Y899023D01*
G01X1801147Y901301D02*
X1806006Y896442D01*
X1809524D01*
X1812105Y899023D01*
G01X1792263Y898225D02*
Y894425D01*
G01X1788513Y892025D02*
X1789863D01*
X1792263Y894425D01*
G01X1792563Y901775D02*
Y898525D01*
X1792263Y898225D01*
G01X1796700Y901830D02*
Y900462D01*
X1798500Y898662D01*
G01X1788430Y898509D02*
Y900408D01*
X1786313Y902525D01*
Y904525D01*
G01Y909325D02*
Y904525D01*
G01X1785013Y892025D02*
Y888085D01*
X1785603Y887495D01*
G01X1816126Y1484735D02*
Y1482000D01*
X1815026Y1480900D01*
X1812226D01*
X1811316Y1481810D01*
X1807676D01*
G01X1807626Y1485700D02*
Y1489365D01*
X1806891Y1490100D01*
G01X1807626Y1485700D02*
X1807676Y1485650D01*
Y1481810D01*
G01X1801786Y1463450D02*
Y1466640D01*
X1799926Y1468500D01*
X1798826D01*
X1797426Y1469900D01*
Y1470400D01*
G01D02*
Y1471600D01*
X1799236Y1473410D01*
Y1476990D01*
G01X1813566Y1484735D02*
Y1487440D01*
X1815218Y1489092D01*
X1823484D01*
X1825826Y1486750D01*
G01X1809861Y1471000D02*
X1813826D01*
G01D02*
X1813926Y1470900D01*
X1817776D01*
G01X1816126Y1476665D02*
Y1475000D01*
X1817776Y1473350D01*
Y1470900D01*
G01X1799226Y1456950D02*
Y1450700D01*
X1800326Y1449600D01*
G01Y1445800D02*
Y1449600D01*
G01X1796666Y1456950D02*
Y1454240D01*
X1794426Y1452000D01*
Y1450328D01*
G01Y1446400D02*
Y1450328D01*
G01X1803391Y1490100D02*
X1799926D01*
X1799626Y1489800D01*
G01X1799236Y1484390D02*
Y1489410D01*
X1799626Y1489800D01*
G01X1799236Y1484390D02*
Y1481610D01*
X1798468Y1480842D01*
X1797384D01*
X1796676Y1481550D01*
Y1484390D01*
G01X1801796Y1476990D02*
Y1472030D01*
X1802526Y1471300D01*
G01X1806361Y1471000D02*
X1802826D01*
X1802526Y1471300D01*
G01X1863781Y260355D02*
Y328636D01*
X1836769Y355648D01*
G01X1859841Y260355D02*
Y298829D01*
X1859796Y298874D01*
Y325366D01*
X1839077Y346085D01*
G01X1859841Y254605D02*
X1855295D01*
X1852223Y257677D01*
Y303000D01*
G01X1832100Y388300D02*
Y360317D01*
X1836769Y355648D01*
G01X1827100Y388300D02*
Y358062D01*
X1839077Y346085D01*
G01X1863781Y713111D02*
Y821477D01*
G01X1859841Y713111D02*
Y798979D01*
G01X1863781Y707361D02*
Y702949D01*
X1861932Y701100D01*
X1855032D01*
X1846032Y710100D01*
Y746970D01*
G01X1830674Y845907D02*
Y825958D01*
X1846032Y810600D01*
Y746970D01*
G01X1859841Y707361D02*
X1854171D01*
X1849032Y712500D01*
Y827393D01*
G01X1864500Y840500D02*
Y831510D01*
X1863781Y830791D01*
Y821477D01*
G01X1859500Y840500D02*
Y831529D01*
X1859841Y831188D01*
Y798979D01*
G01X1849032Y827393D02*
Y841750D01*
G01X1824813Y911925D02*
X1828588Y915700D01*
X1836600D01*
X1838775Y913525D01*
X1923600D01*
G01X1821313Y911925D02*
X1820963Y912275D01*
X1817263D01*
G01X1831263Y911525D02*
X1827263Y907525D01*
X1822863D01*
X1821272Y905934D01*
Y903550D01*
G01D02*
Y900034D01*
X1821263Y900025D01*
G01X1858425Y1485118D02*
Y1475699D01*
X1848326Y1465600D01*
X1842126D01*
G01X1818686Y1476665D02*
X1825059D01*
G01D02*
X1826661D01*
X1829526Y1473800D01*
Y1467100D01*
X1831026Y1465600D01*
X1834526D01*
G01X1838425Y1485118D02*
Y1484401D01*
X1843026Y1479800D01*
Y1474350D01*
X1842026Y1473350D01*
G01X1834426D02*
Y1476800D01*
X1829426Y1481800D01*
Y1484000D01*
X1826676Y1486750D01*
X1825826D01*
X59400Y32600D03*
X63374Y1454500D03*
X111024Y39508D03*
Y188130D03*
X173228Y122047D03*
X111024Y492264D03*
Y640886D03*
Y945020D03*
Y1093642D03*
X167716Y1495669D03*
X235236Y39508D03*
Y188130D03*
Y492264D03*
Y640886D03*
Y945020D03*
Y1093642D03*
X246535Y1320472D03*
X266535D03*
X233858Y1495669D03*
X359449Y39508D03*
Y188130D03*
Y492264D03*
Y640886D03*
Y945020D03*
Y1093642D03*
X390757Y1511515D03*
X483661Y39508D03*
Y188130D03*
Y492264D03*
Y640886D03*
Y945020D03*
Y1093642D03*
X503248Y715748D03*
X531535Y1320472D03*
X511535D03*
X548031Y1495669D03*
X607874Y39508D03*
Y188130D03*
X670079Y122047D03*
X607874Y492264D03*
Y640886D03*
Y945020D03*
Y1093642D03*
X614173Y1495669D03*
X732087Y39508D03*
Y188130D03*
Y492264D03*
Y640886D03*
Y945020D03*
Y1093642D03*
X812347Y17406D03*
X885639Y1511515D03*
X1104528Y1162257D03*
X1187163Y158305D03*
X1281693Y39508D03*
Y188130D03*
X1343701Y122046D03*
X1281693Y492264D03*
Y640886D03*
Y945020D03*
Y1093642D03*
X1314960Y1495669D03*
X1405906Y39508D03*
Y188130D03*
Y492264D03*
Y640886D03*
Y945020D03*
Y1093642D03*
X1381102Y1495669D03*
X1530118Y39508D03*
Y188130D03*
Y492264D03*
Y640886D03*
Y945020D03*
Y1093642D03*
X1538001Y1511515D03*
X1654331Y39508D03*
Y188130D03*
X1673917Y262992D03*
X1654331Y492264D03*
Y640886D03*
Y945020D03*
Y1093642D03*
X1695275Y1495669D03*
X1778543Y39508D03*
Y188130D03*
Y492264D03*
Y640886D03*
Y945020D03*
Y1093642D03*
X1761417Y1495669D03*
X1902756Y39508D03*
Y188130D03*
X1840551Y122046D03*
X1902756Y492264D03*
Y640886D03*
Y945020D03*
Y1093642D03*
X1869500Y1461500D03*
G54D32*
X82300Y133000D03*
X82200Y585500D03*
X100063Y903525D03*
X82100Y1038400D03*
X144674Y1438500D03*
X206600Y133000D03*
X197890Y465789D03*
X206600Y585500D03*
X206700Y1038500D03*
X330900Y133000D03*
Y585500D03*
X330700Y1038500D03*
X454900Y133000D03*
X455200Y585500D03*
X454700Y1038500D03*
X579400Y133000D03*
X579300Y585500D03*
Y1038500D03*
X667800Y1448500D03*
X703600Y133000D03*
Y585500D03*
X703500Y1038500D03*
X867400Y779100D03*
X944800Y894000D03*
X971918Y534117D03*
X1015750Y842360D03*
X1032534Y1391632D03*
X975243Y1436399D03*
X1112800Y1327500D03*
X1114800Y1354000D03*
X1291674Y1438500D03*
X1671926D03*
X1740659Y469207D03*
X1762800Y595000D03*
X1815063Y903525D03*
X1878098Y68922D03*
X1874200Y132500D03*
X1874300Y585500D03*
X1874000Y1038500D03*
G54D117*
G01X77300Y67250D02*
X72500D01*
G01X80500Y73300D02*
Y70450D01*
X77300Y67250D01*
G01X66500Y74000D02*
X65750Y73250D01*
X60000D01*
G01Y80000D02*
Y81250D01*
X60250Y81500D01*
Y96500D01*
G01X60000Y73250D02*
Y80000D01*
G01X77940Y80700D02*
X71550D01*
X67750Y84500D01*
G01D02*
Y91000D01*
G01D02*
Y95000D01*
G01X83060Y73300D02*
Y66160D01*
X79700Y62800D01*
X77100D01*
G01D02*
X73450D01*
X72500Y63750D01*
G01X60000Y69750D02*
X60250Y69500D01*
Y65500D01*
G01X72500Y63750D02*
X70250D01*
X69000Y65000D01*
X66500D01*
G01D02*
X60750D01*
X60250Y65500D01*
G01X85550Y62800D02*
Y67650D01*
X85600Y67700D01*
G01X80500Y80700D02*
Y78500D01*
X82000Y77000D01*
X88750D01*
G01X85600Y67700D02*
X88750Y70850D01*
Y72400D01*
G01Y77000D02*
Y72400D01*
G01X89050Y62800D02*
X92500D01*
G01X66000Y111500D02*
Y106250D01*
X60250Y100500D01*
G01Y96500D02*
Y100500D01*
G01X74000Y113500D02*
Y107500D01*
X67750Y101250D01*
Y95000D01*
G01X493899Y320895D02*
Y271700D01*
X440533Y218334D01*
X111066D01*
X93300Y236100D01*
Y394500D01*
X84495Y403305D01*
X73442D01*
G01X58709Y376696D02*
Y372346D01*
G01Y383528D02*
Y376696D01*
G01Y389378D02*
Y383528D01*
G01X73442Y403305D02*
Y396596D01*
G01X77300Y519750D02*
X72500D01*
G01X80500Y525800D02*
Y522950D01*
X77300Y519750D01*
G01X66500Y526500D02*
X65750Y525750D01*
X60000D01*
G01Y532500D02*
Y533750D01*
X60250Y534000D01*
Y549000D01*
G01X66000Y564000D02*
Y558750D01*
X60250Y553000D01*
G01Y549000D02*
Y553000D01*
G01X60000Y525750D02*
Y532500D01*
G01X67750Y543500D02*
Y537350D01*
X68100Y537000D01*
G01X77940Y533200D02*
X71900D01*
X68100Y537000D01*
G01X74000Y566000D02*
Y560000D01*
X67750Y553750D01*
Y547500D01*
G01D02*
Y543500D01*
G01X83060Y525800D02*
Y517810D01*
X80350Y515100D01*
X77200D01*
G01X72500Y516250D02*
X75100D01*
X76250Y515100D01*
X77200D01*
G01X60000Y522250D02*
Y518250D01*
X60250Y518000D01*
G01X72500Y516250D02*
X70250D01*
X69000Y517500D01*
X66500D01*
G01D02*
X60750D01*
X60250Y518000D01*
G01X86850Y516800D02*
Y520600D01*
G01X88750Y529500D02*
Y527300D01*
X88550Y527100D01*
Y525300D01*
G01D02*
X86850Y523600D01*
Y520600D01*
G01X80500Y533200D02*
Y531000D01*
X82000Y529500D01*
X88750D01*
G01X90350Y516800D02*
X93800D01*
G01X758562Y925283D02*
X755389Y922110D01*
X245399D01*
X244214Y920925D01*
Y920924D01*
X195468Y872178D01*
X146321D01*
X134218Y860075D01*
X107425D01*
X102000Y865500D01*
X40842D01*
X26680Y851338D01*
Y816564D01*
X43865Y799379D01*
Y678643D01*
X59993Y662515D01*
X125500D01*
X143500Y644515D01*
Y594500D01*
G01X768449Y929466D02*
X759068Y920085D01*
X246239D01*
X196307Y870153D01*
X147160D01*
X134057Y857050D01*
X100950D01*
X94525Y863475D01*
X41682D01*
X28707Y850500D01*
Y817401D01*
X45890Y800218D01*
Y679482D01*
X60357Y665015D01*
X252000D01*
X267500Y649515D01*
Y594500D01*
G01X392000D02*
Y646475D01*
X371000Y667475D01*
X60761D01*
X47915Y680321D01*
Y801057D01*
X30732Y818240D01*
Y849661D01*
X42521Y861450D01*
X91050D01*
X98475Y854025D01*
X133896D01*
X147999Y868128D01*
X197146D01*
X246793Y917775D01*
X448289D01*
G01X46442Y829350D02*
Y825000D01*
G01Y829350D02*
Y836182D01*
G01D02*
Y842032D01*
G01X796396Y879084D02*
X794067Y881413D01*
X216159D01*
X198824Y864078D01*
X149677D01*
X133099Y847500D01*
X95000D01*
X86541Y855959D01*
X61175D01*
G01D02*
Y849250D01*
G01X92250Y968000D02*
X95500D01*
G01X77300Y972750D02*
X72500D01*
G01X80500Y978800D02*
Y975950D01*
X77300Y972750D01*
G01X66500Y979500D02*
X65750Y978750D01*
X60000D01*
G01Y985500D02*
Y986750D01*
X60250Y987000D01*
Y1002000D01*
G01X66000Y1017000D02*
Y1011750D01*
X60250Y1006000D01*
G01Y1002000D02*
Y1006000D01*
G01X60000Y978750D02*
Y985500D01*
G01X77940Y986200D02*
X71800D01*
X69000Y989000D01*
G01D02*
X67750Y990250D01*
Y996500D01*
G01X74000Y1019000D02*
Y1013000D01*
X67750Y1006750D01*
Y1000500D01*
G01Y996500D02*
Y1000500D01*
G01X60250Y971000D02*
Y965750D01*
X61500Y964500D01*
X63000D01*
G01X66500Y970500D02*
Y965500D01*
X65500Y964500D01*
X63000D01*
G01X60000Y975250D02*
Y971250D01*
X60250Y971000D01*
G01X66500Y970500D02*
X69000D01*
X70250Y969250D01*
X72500D01*
G01X83060Y978800D02*
Y974500D01*
X77810Y969250D01*
X72500D01*
G01X88750Y968000D02*
X84500D01*
X83000Y969500D01*
Y970000D01*
G01X80500Y986200D02*
Y984000D01*
X82000Y982500D01*
X88750D01*
G01Y972500D02*
X83924D01*
X83000Y971576D01*
Y970000D01*
G01X88750Y982500D02*
Y972500D01*
G01X188500Y86000D02*
Y81500D01*
X188841Y81159D01*
Y79022D01*
G01D02*
Y72259D01*
X198800Y62300D01*
Y40950D01*
G01X198000Y113500D02*
X196500D01*
X193500Y110500D01*
Y84250D01*
X195250Y82500D01*
G01X134941Y24706D02*
Y20334D01*
X137750Y17525D01*
X150000D01*
X151160Y18685D01*
Y18699D01*
G01X168350Y29200D02*
X163450D01*
X160550Y32100D01*
G01D02*
X158413Y29963D01*
X156185D01*
X151160Y24938D01*
Y18699D01*
G01X172150Y25100D02*
X171950Y25300D01*
X168100D01*
G01X132381Y24706D02*
Y20019D01*
X136900Y15500D01*
X151827D01*
X153500Y17173D01*
Y24414D01*
X157024Y27938D01*
X161427D01*
X164250Y25115D01*
Y25100D01*
G01D02*
X167900D01*
X168100Y25300D01*
G01X172150Y20900D02*
X171750Y20500D01*
X168200D01*
G01X129821Y24706D02*
Y18894D01*
X135240Y13475D01*
X160075D01*
X164250Y17650D01*
Y21100D01*
G01D02*
X167600D01*
X168200Y20500D01*
G01X132381Y40886D02*
Y37019D01*
X133981Y35419D01*
X138936D01*
X140428Y36911D01*
X148911D01*
X149300Y37300D01*
G01X144050Y48500D02*
X140300D01*
X140200Y48400D01*
G01X134941Y40886D02*
Y44941D01*
X138400Y48400D01*
X140200D01*
G01X144050Y44400D02*
X144700Y43750D01*
Y40800D01*
X144400Y40500D01*
G01X137501Y40886D02*
X140714D01*
X141200Y40400D01*
X144300D01*
X144400Y40500D01*
G01X147550Y48500D02*
X151200D01*
G01X147550Y44400D02*
X151200D01*
G01X136866Y156319D02*
X118209D01*
G01X140500Y126100D02*
X140450Y126150D01*
X136200D01*
G01D02*
X131600D01*
G01X127600D02*
X125469D01*
X125300Y126319D01*
X118209D01*
G01X131600Y126150D02*
X127600D01*
G01X140500Y132100D02*
Y194607D01*
X162202Y216309D01*
X446366D01*
X498968Y268911D01*
Y296814D01*
G01X192842Y376350D02*
Y372000D01*
G01Y383182D02*
Y376350D01*
G01Y389032D02*
Y383182D01*
G01X190500Y526500D02*
X189750Y525750D01*
X184000D01*
G01Y532500D02*
Y533750D01*
X184250Y534000D01*
Y549000D01*
G01X190000Y564000D02*
Y558750D01*
X184250Y553000D01*
G01Y549000D02*
Y553000D01*
G01X184000Y525750D02*
Y532500D01*
G01X201940Y533200D02*
X195948D01*
X192499Y536649D01*
G01D02*
X191750Y537398D01*
Y543500D01*
G01X198000Y566000D02*
Y560000D01*
X191750Y553750D01*
Y547500D01*
G01Y543500D02*
Y547500D01*
G01X184000Y522250D02*
Y518250D01*
X184250Y518000D01*
G01X196500Y516250D02*
X194250D01*
X193000Y517500D01*
X190500D01*
G01D02*
X184750D01*
X184250Y518000D01*
G01X118209Y609075D02*
X136866D01*
G01X137250Y583000D02*
Y588500D01*
G01Y579000D02*
Y583000D01*
G01X137500Y594500D02*
Y588750D01*
X137250Y588500D01*
G01Y579000D02*
X137175Y579075D01*
X118209D01*
G01X169442Y829050D02*
Y824700D01*
G01X167842Y837032D02*
X172444D01*
X173558Y835918D01*
G01D02*
Y833166D01*
X169442Y829050D01*
G01X785560Y876549D02*
X782721Y879388D01*
X216998D01*
X199663Y862053D01*
X186248D01*
X184175Y859980D01*
Y855659D01*
G01D02*
Y849250D01*
G01X191000Y979500D02*
X190250Y978750D01*
X184500D01*
G01Y985500D02*
Y986750D01*
X184750Y987000D01*
Y1002000D01*
G01X190500Y1017000D02*
Y1011750D01*
X184750Y1006000D01*
G01Y1002000D02*
Y1006000D01*
G01X184500Y978750D02*
Y985500D01*
G01X202440Y986200D02*
X196846D01*
X193949Y989097D01*
G01D02*
X192250Y990796D01*
Y996500D01*
G01X198500Y1019000D02*
Y1013000D01*
X192250Y1006750D01*
Y1000500D01*
G01Y996500D02*
Y1000500D01*
G01X184500Y975250D02*
Y971250D01*
X184750Y971000D01*
G01X197000Y969250D02*
X194750D01*
X193500Y970500D01*
X191000D01*
G01D02*
X185250D01*
X184750Y971000D01*
G01X137500Y1047500D02*
Y1041750D01*
X137250Y1041500D01*
G01Y1036000D02*
Y1041500D01*
G01Y1032000D02*
Y1036000D01*
G01Y1032000D02*
X137081Y1031831D01*
X118209D01*
G01Y1061831D02*
X136866D01*
G01X143500Y1047500D02*
Y1111740D01*
X159500Y1127740D01*
X768086D01*
X779222Y1116604D01*
G01X200787Y1466929D02*
X187854Y1479862D01*
X152565D01*
X150953Y1478250D01*
X150807D01*
X149202Y1476645D01*
X141266D01*
X139661Y1478250D01*
X139374D01*
G01X124874Y1442600D02*
X131036Y1448762D01*
Y1474576D01*
X134710Y1478250D01*
X139374D01*
G01X210700Y65500D02*
X208500D01*
X207100Y64100D01*
Y58500D01*
X208200Y57400D01*
X211000D01*
G01D02*
X214850D01*
G01X208500Y51200D02*
X206367D01*
X203750Y48583D01*
Y45100D01*
G01X198800Y40950D02*
X202800D01*
G01X203750Y45100D02*
Y41900D01*
X202800Y40950D01*
G01X203300Y62940D02*
X201560D01*
X200000Y64500D01*
Y67750D01*
X195250Y72500D01*
Y73500D01*
G01D02*
Y78500D01*
G01D02*
Y82500D01*
G01X207250Y45100D02*
X211162D01*
G01X210700Y68060D02*
X214700D01*
X218350Y64410D01*
Y57400D01*
G01X211162Y45100D02*
X213845D01*
X213995Y45250D01*
X217000D01*
G01X218350Y57400D02*
Y54850D01*
X217500Y54000D01*
Y51200D01*
G01D02*
Y48532D01*
X217000Y48032D01*
Y45250D01*
G01X220000Y73750D02*
X215500D01*
G01X211086D02*
X215500D01*
G01X203300Y65500D02*
X205500D01*
X207000Y67000D01*
Y73750D01*
G01D02*
X211086D01*
G01X220000Y77250D02*
Y80500D01*
G01X242421Y156319D02*
X261078D01*
G01X265000Y126200D02*
X264850Y126350D01*
X260400D01*
G01D02*
X254900D01*
G01X250900D02*
X247867D01*
X247836Y126319D01*
X242421D01*
G01X254900Y126350D02*
X250900D01*
G01X265000Y132200D02*
Y143553D01*
X267279Y145832D01*
Y212130D01*
X269432Y214283D01*
X451058D01*
X505052Y268277D01*
Y368552D01*
G01X488448Y338766D02*
Y274108D01*
X434699Y220359D01*
X240141D01*
X230700Y229800D01*
Y395244D01*
X222985Y402959D01*
X207575D01*
G01D02*
Y396350D01*
G01X201300Y519750D02*
X196500D01*
G01X204500Y525800D02*
Y522950D01*
X201300Y519750D01*
G01X207060Y525800D02*
Y519160D01*
X203200Y515300D01*
X201000D01*
G01X196500Y516250D02*
X197450Y515300D01*
X201000D01*
G01X211150Y520500D02*
Y516600D01*
G01X212750Y529500D02*
Y526900D01*
X212650Y526800D01*
Y525200D01*
G01D02*
X211150Y523700D01*
Y520500D01*
G01X204500Y533200D02*
Y531000D01*
X206000Y529500D01*
X212750D01*
G01X218000Y516600D02*
X214650D01*
G01X261078Y609075D02*
X242421D01*
G01X261250Y579000D02*
Y583000D01*
G01Y588500D02*
Y583000D01*
G01X261500Y594500D02*
Y588750D01*
X261250Y588500D01*
G01Y579000D02*
X261175Y579075D01*
X242421D01*
G01X261200Y1047500D02*
Y1042300D01*
X261500Y1042000D01*
G01X260950Y1036000D02*
Y1041450D01*
X261500Y1042000D01*
G01X260950Y1032000D02*
Y1036000D01*
G01Y1032000D02*
X260781Y1031831D01*
X242421D01*
G01X201800Y972750D02*
X197000D01*
G01X205000Y978800D02*
Y975950D01*
X201800Y972750D01*
G01X207560Y978800D02*
Y972560D01*
X203400Y968400D01*
X201600D01*
G01X197000Y969250D02*
X197850Y968400D01*
X201600D01*
G01X213250Y978100D02*
X210850Y975700D01*
Y973800D01*
G01D02*
Y969700D01*
G01X205000Y986200D02*
Y984000D01*
X206500Y982500D01*
X213250D01*
G01D02*
Y978100D01*
G01X267200Y1047500D02*
X269085Y1049385D01*
Y1121765D01*
X272896Y1125576D01*
X764039D01*
X814330Y1075285D01*
Y1026361D01*
G01X218100Y969700D02*
X214350D01*
G01X242421Y1061831D02*
X261078D01*
G01X325800Y67250D02*
X321000D01*
G01X329000Y73300D02*
Y70450D01*
X325800Y67250D01*
G01X315000Y74000D02*
X314250Y73250D01*
X308500D01*
G01Y80000D02*
Y81250D01*
X308750Y81500D01*
Y96500D01*
G01X308500Y73250D02*
Y80000D01*
G01X326440Y80700D02*
X320100D01*
X316800Y84000D01*
G01D02*
X316250Y84550D01*
Y91000D01*
G01D02*
Y95000D01*
G01X331560Y73300D02*
Y69700D01*
X329700Y67840D01*
Y64200D01*
X328400Y62900D01*
X325900D01*
G01D02*
X321850D01*
X321000Y63750D01*
G01X308500Y69750D02*
Y65750D01*
X308750Y65500D01*
G01X321000Y63750D02*
X318750D01*
X317500Y65000D01*
X315000D01*
G01D02*
X309250D01*
X308750Y65500D01*
G01X329000Y80700D02*
Y78500D01*
X330500Y77000D01*
X337250D01*
G01X334950Y63700D02*
Y65281D01*
X335100Y65431D01*
Y67800D01*
G01D02*
Y69174D01*
X337150Y71224D01*
Y72600D01*
G01X337250Y77000D02*
Y74709D01*
X337150Y74609D01*
Y72600D01*
G01X338450Y63700D02*
X341800D01*
G01X366634Y156319D02*
X385291D01*
G01X384549Y126350D02*
X379500D01*
G01X389000Y126400D02*
X388950Y126350D01*
X384549D01*
G01X375500D02*
X372226D01*
X372195Y126319D01*
X366634D01*
G01X379500Y126350D02*
X375500D01*
G01X314500Y111500D02*
Y106250D01*
X308750Y100500D01*
G01Y96500D02*
Y100500D01*
G01X322500Y113500D02*
Y107500D01*
X316250Y101250D01*
Y95000D01*
G01X482745Y351821D02*
Y275502D01*
X429627Y222384D01*
X353616D01*
X339300Y236700D01*
Y393729D01*
X329770Y403259D01*
X309275D01*
G01X294542Y376650D02*
Y372300D01*
G01Y383482D02*
Y376650D01*
G01Y389332D02*
Y383482D01*
G01X309275Y403259D02*
Y396550D01*
G01X325800Y519750D02*
X321000D01*
G01X329000Y525800D02*
Y522950D01*
X325800Y519750D01*
G01X315000Y526500D02*
X314250Y525750D01*
X308500D01*
G01Y532500D02*
Y533750D01*
X308750Y534000D01*
Y549000D01*
G01X314500Y564000D02*
Y558750D01*
X308750Y553000D01*
G01Y549000D02*
Y553000D01*
G01X308500Y525750D02*
Y532500D01*
G01X320958Y533200D02*
X326440D01*
G01X320958D02*
X319100D01*
X316250Y536050D01*
Y543500D01*
G01X322500Y566000D02*
Y560000D01*
X316250Y553750D01*
Y547500D01*
G01Y543500D02*
Y547500D01*
G01X331560Y525800D02*
Y517810D01*
X328450Y514700D01*
X325800D01*
G01X308500Y522250D02*
Y518250D01*
X308750Y518000D01*
G01X321000Y516250D02*
X322150D01*
X323700Y514700D01*
X325800D01*
G01X321000Y516250D02*
X318750D01*
X317500Y517500D01*
X315000D01*
G01D02*
X309250D01*
X308750Y518000D01*
G01X337250Y525300D02*
X335050Y523100D01*
Y520700D01*
G01D02*
Y516800D01*
G01X329000Y533200D02*
Y531000D01*
X330500Y529500D01*
X337250D01*
G01D02*
Y525300D01*
G01X341800Y516800D02*
X338550D01*
G01X366634Y609075D02*
X385291D01*
G01X386000Y594500D02*
Y588750D01*
X385750Y588500D01*
G01Y579000D02*
X385675Y579075D01*
X366634D01*
G01X294542Y829350D02*
Y825000D01*
G01Y829350D02*
Y836182D01*
G01D02*
Y842032D01*
G01X312418Y868254D02*
X309275Y865111D01*
Y855959D01*
G01D02*
Y849250D01*
G01X838400Y872280D02*
X782509D01*
X777426Y877363D01*
X321527D01*
X312418Y868254D01*
G01X386000Y1047500D02*
Y1041750D01*
X385750Y1041500D01*
G01Y1032000D02*
X385581Y1031831D01*
X366634D01*
G01X325800Y972750D02*
X321000D01*
G01X329000Y978800D02*
Y975950D01*
X325800Y972750D01*
G01X315000Y979500D02*
X314250Y978750D01*
X308500D01*
G01Y985500D02*
Y986750D01*
X308750Y987000D01*
Y1002000D01*
G01X314500Y1017000D02*
Y1011750D01*
X308750Y1006000D01*
G01Y1002000D02*
Y1006000D01*
G01X308500Y978750D02*
Y985500D01*
G01X326440Y986200D02*
X320073D01*
X317542Y988731D01*
G01D02*
X316250Y990023D01*
Y996500D01*
G01X322500Y1019000D02*
Y1013000D01*
X316250Y1006750D01*
Y1000500D01*
G01Y996500D02*
Y1000500D01*
G01X331560Y978800D02*
Y972800D01*
X327160Y968400D01*
X325600D01*
G01X321000Y969250D02*
X321850Y968400D01*
X325600D01*
G01X308500Y975250D02*
Y971250D01*
X308750Y971000D01*
G01X321000Y969250D02*
X318750D01*
X317500Y970500D01*
X315000D01*
G01D02*
X309250D01*
X308750Y971000D01*
G01X334750Y973200D02*
Y969400D01*
G01X337250Y982500D02*
X337150Y982400D01*
Y978200D01*
G01D02*
X334750Y975800D01*
Y973200D01*
G01X329000Y986200D02*
Y984000D01*
X330500Y982500D01*
X337250D01*
G01X341900Y969400D02*
X338250D01*
G01X366634Y1061831D02*
X385291D01*
G01X457700Y65500D02*
X455500D01*
X454100Y64100D01*
Y59500D01*
X456100Y57500D01*
X459000D01*
G01D02*
X463750D01*
G01X444400Y39250D02*
X440400D01*
G01X444400D02*
X447300D01*
X448200Y40150D01*
G01X457000Y51500D02*
X455900D01*
X451950Y47550D01*
Y44500D01*
G01D02*
Y43900D01*
X448200Y40150D01*
G01X440500Y46600D02*
Y39350D01*
X440400Y39250D01*
G01X435100Y118850D02*
Y113383D01*
X441800Y106683D01*
Y80500D01*
X445500Y76800D01*
Y74300D01*
G01X450300Y62940D02*
X447060D01*
X445500Y64500D01*
Y74300D01*
G01X465500Y45250D02*
X464750Y44500D01*
X459511D01*
G01D02*
X455450D01*
G01X467250Y57500D02*
Y55250D01*
X466000Y54000D01*
Y51500D01*
G01D02*
Y45750D01*
X465500Y45250D01*
G01X457700Y68060D02*
X462340D01*
X467250Y63150D01*
Y57500D01*
G01X454000Y77150D02*
X458450D01*
X458900Y76700D01*
G01D02*
X461850Y73750D01*
X464000D01*
G01D02*
X468500D01*
G01X450300Y65500D02*
X452500D01*
X454000Y67000D01*
Y77150D01*
G01X468500Y77250D02*
Y80500D01*
G01X446900Y117100D02*
X444300D01*
X442550Y118850D01*
X440849D01*
G01D02*
X435100D01*
G01X389000Y132400D02*
Y144367D01*
X511136Y266503D01*
Y352328D01*
G01X419042Y376350D02*
Y372000D01*
G01Y383182D02*
Y376350D01*
G01Y389032D02*
Y383182D01*
G01X435190Y408695D02*
X493149Y466654D01*
X740417D01*
X762692Y488929D01*
Y614953D01*
X752925Y624720D01*
Y755602D01*
X777943Y780620D01*
Y834485D01*
X796584Y853126D01*
X839491D01*
X842820Y856455D01*
Y869183D01*
X848947Y875310D01*
X854235D01*
X854705Y874840D01*
X860600D01*
G01X435190Y408695D02*
X433775Y407280D01*
Y402959D01*
G01D02*
Y396350D01*
G01X449800Y519750D02*
X445000D01*
G01X453000Y525800D02*
Y522950D01*
X449800Y519750D01*
G01X439000Y526500D02*
X438250Y525750D01*
X432500D01*
G01Y532500D02*
Y533750D01*
X432750Y534000D01*
Y549000D01*
G01X438500Y564000D02*
Y558750D01*
X432750Y553000D01*
G01Y549000D02*
Y553000D01*
G01X432500Y525750D02*
Y532500D01*
G01X450440Y533200D02*
X443669D01*
X440855Y536014D01*
G01D02*
X440250Y536619D01*
Y543500D01*
G01X446500Y566000D02*
Y560000D01*
X440250Y553750D01*
Y547500D01*
G01Y543500D02*
Y547500D01*
G01X455560Y525800D02*
Y519460D01*
X451500Y515400D01*
X449800D01*
G01D02*
X445850D01*
X445000Y516250D01*
G01X432500Y522250D02*
X432622Y522128D01*
Y518128D01*
X432750Y518000D01*
G01X445000Y516250D02*
X442750D01*
X441500Y517500D01*
X439000D01*
G01D02*
X436474D01*
X435974Y518000D01*
X432750D01*
G01X459350Y520600D02*
Y516900D01*
G01X453000Y533200D02*
Y531000D01*
X454500Y529500D01*
X461250D01*
G01X459350Y520600D02*
Y523400D01*
X461250Y525300D01*
G01Y529500D02*
Y525300D01*
G01X466000Y516900D02*
X462850D01*
G01X385750Y583000D02*
Y588500D01*
G01Y579000D02*
Y583000D01*
G01X418742Y828794D02*
Y824444D01*
G01Y828794D02*
Y835876D01*
G01D02*
Y841732D01*
G01X434890Y861395D02*
X433475Y859980D01*
Y855659D01*
G01D02*
Y849050D01*
G01X814750Y940330D02*
Y935210D01*
X811765Y932225D01*
X776987D01*
X762537Y917775D01*
X448289D01*
G01X838400Y869720D02*
X782205D01*
X776587Y875338D01*
X448833D01*
X434890Y861395D01*
G01X385750Y1032000D02*
Y1036000D01*
G01D02*
Y1041500D01*
G01X449800Y972750D02*
X445000D01*
G01X453000Y978800D02*
Y975950D01*
X449800Y972750D01*
G01X439000Y979500D02*
X438250Y978750D01*
X432500D01*
G01Y985500D02*
Y986750D01*
X432750Y987000D01*
Y1002000D01*
G01X438500Y1017000D02*
Y1011750D01*
X432750Y1006000D01*
G01Y1002000D02*
Y1006000D01*
G01X432500Y978750D02*
Y985500D01*
G01X450440Y986200D02*
X444566D01*
X441398Y989368D01*
G01D02*
X440250Y990516D01*
Y996500D01*
G01X446500Y1019000D02*
Y1013000D01*
X440250Y1006750D01*
Y1000500D01*
G01Y996500D02*
Y1000500D01*
G01X455560Y978800D02*
Y972400D01*
X451660Y968500D01*
X449700D01*
G01X445000Y969250D02*
X445750Y968500D01*
X449700D01*
G01X432500Y975250D02*
Y971250D01*
X432750Y971000D01*
G01X445000Y969250D02*
X442750D01*
X441500Y970500D01*
X439000D01*
G01D02*
X433250D01*
X432750Y971000D01*
G01X459150Y973500D02*
Y969200D01*
G01X461250Y982500D02*
Y980134D01*
X461150Y980034D01*
Y978000D01*
G01D02*
X459150Y976000D01*
Y973500D01*
G01X453000Y986200D02*
Y984000D01*
X454500Y982500D01*
X461250D01*
G01X462650Y969200D02*
X466100D01*
G01X392000Y1047500D02*
Y1119620D01*
X395930Y1123550D01*
X761248D01*
X811162Y1073636D01*
Y1028971D01*
X810751Y1028560D01*
G01X574300Y67250D02*
X569500D01*
G01X577500Y73300D02*
Y70450D01*
X574300Y67250D01*
G01X563500Y74000D02*
X562750Y73250D01*
X557000D01*
G01Y80000D02*
Y81250D01*
X557250Y81500D01*
Y96500D01*
G01X557000Y73250D02*
Y80000D01*
G01X574940Y80700D02*
X568666D01*
X565757Y83609D01*
G01D02*
X564750Y84616D01*
Y91000D01*
G01D02*
Y95000D01*
G01X580060Y73300D02*
Y66460D01*
X576500Y62900D01*
X574300D01*
G01D02*
X573150D01*
X572300Y63750D01*
X569500D01*
G01X557000Y69750D02*
Y65750D01*
X557250Y65500D01*
G01X569500Y63750D02*
X567250D01*
X566000Y65000D01*
X563500D01*
G01D02*
X557750D01*
X557250Y65500D01*
G01X490846Y156319D02*
X509503D01*
G01X503900Y126250D02*
X508761D01*
G01X499900D02*
X503900D01*
G01X513600Y126300D02*
X513550Y126250D01*
X508761D01*
G01X499900D02*
X497258D01*
X497189Y126319D01*
X490846D01*
G01X563000Y111500D02*
Y106250D01*
X557250Y100500D01*
G01Y96500D02*
Y100500D01*
G01X571000Y113500D02*
Y107500D01*
X564750Y101250D01*
Y95000D01*
G01X513600Y132300D02*
Y143163D01*
X517473Y147036D01*
Y332556D01*
G01X637300Y132300D02*
Y199060D01*
X621677Y214683D01*
X565655D01*
X523810Y256528D01*
Y312530D01*
G01X748400Y143100D02*
Y215900D01*
X742300Y222000D01*
X567970D01*
X531987Y257983D01*
Y294450D01*
G01X493899Y320895D02*
Y410335D01*
X538937Y455373D01*
X737728D01*
X768767Y486412D01*
Y618214D01*
X759000Y627981D01*
Y753085D01*
X784018Y778103D01*
Y831968D01*
X796925Y844875D01*
X840070D01*
X848895Y853700D01*
Y864395D01*
X851660Y867160D01*
X860600D01*
G01X488448Y338766D02*
Y412578D01*
X534411Y458541D01*
X738032D01*
X766742Y487251D01*
Y617344D01*
X756975Y627111D01*
Y753924D01*
X781993Y778942D01*
Y832807D01*
X796086Y846900D01*
X839231D01*
X846870Y854539D01*
Y865991D01*
X850088Y869209D01*
X853396D01*
X853907Y869720D01*
X860600D01*
G01X482745Y351821D02*
Y414130D01*
X530959Y462344D01*
X738971D01*
X764717Y488090D01*
Y615938D01*
X754950Y625705D01*
Y754763D01*
X779968Y779781D01*
Y833646D01*
X797422Y851100D01*
X840329D01*
X844845Y855616D01*
Y867587D01*
X850543Y873285D01*
X853396D01*
X854401Y872280D01*
X860600D01*
G01X543242Y372300D02*
Y376650D01*
G01Y383482D02*
Y376650D01*
G01X498968Y296814D02*
Y407269D01*
X543776Y452077D01*
X737296D01*
X770792Y485573D01*
Y619194D01*
X761025Y628961D01*
Y752246D01*
X786043Y777264D01*
Y831129D01*
X793004Y838090D01*
X831204D01*
X831214Y838080D01*
X838900D01*
G01X505052Y368552D02*
Y404999D01*
X548452Y448399D01*
X736482D01*
X772817Y484734D01*
Y621107D01*
X763050Y630874D01*
Y751407D01*
X788068Y776425D01*
Y830290D01*
X793843Y836065D01*
X830365D01*
X830910Y835520D01*
X838900D01*
G01X511136Y352328D02*
Y404267D01*
X552229Y445360D01*
X736307D01*
X774842Y483895D01*
Y621946D01*
X765075Y631713D01*
Y749996D01*
X790093Y775014D01*
Y829451D01*
X794682Y834040D01*
X829526D01*
X830606Y832960D01*
X838900D01*
G01X517473Y332556D02*
Y403790D01*
X555117Y441434D01*
X735245D01*
X776867Y483056D01*
Y624334D01*
X767100Y634101D01*
Y749156D01*
X792118Y774174D01*
Y828612D01*
X795521Y832015D01*
X828687D01*
X830302Y830400D01*
X838900D01*
G01X523810Y312530D02*
Y403092D01*
X558733Y438015D01*
X734690D01*
X826500Y529825D01*
Y588375D01*
X769125Y645750D01*
Y748317D01*
X794143Y773335D01*
Y827773D01*
X796360Y829990D01*
X827848D01*
X829998Y827840D01*
X838900D01*
G01Y825280D02*
X829694D01*
X827009Y827965D01*
X797199D01*
X796168Y826934D01*
Y772496D01*
X771150Y747478D01*
Y646589D01*
X828903Y588836D01*
Y527234D01*
X736044Y434375D01*
X564326D01*
X531987Y402036D01*
Y294450D01*
G01X543242Y389332D02*
Y383482D01*
G01X833200Y765400D02*
X828665D01*
X827927Y764662D01*
X818691D01*
X815563Y761534D01*
X788070D01*
X773175Y746639D01*
Y647428D01*
X831673Y588930D01*
Y525060D01*
X737513Y430900D01*
X568326D01*
X557975Y420549D01*
Y412093D01*
G01Y396550D02*
Y403259D01*
G01D02*
Y412093D01*
G01X574300Y519750D02*
X569500D01*
G01X577500Y525800D02*
Y522950D01*
X574300Y519750D01*
G01X563500Y526500D02*
X562750Y525750D01*
X557000D01*
G01Y532500D02*
Y533750D01*
X557250Y534000D01*
Y549000D01*
G01X563000Y564000D02*
Y558750D01*
X557250Y553000D01*
G01Y549000D02*
Y553000D01*
G01X557000Y525750D02*
Y532500D01*
G01X574940Y533200D02*
X569300D01*
X565500Y537000D01*
G01D02*
X564750Y537750D01*
Y543500D01*
G01X571000Y566000D02*
Y560000D01*
X564750Y553750D01*
Y547500D01*
G01Y543500D02*
Y547500D01*
G01X580060Y525800D02*
Y518960D01*
X576600Y515500D01*
X574300D01*
G01D02*
X570250D01*
X569500Y516250D01*
G01X557000Y522250D02*
Y518250D01*
X557250Y518000D01*
G01X569500Y516250D02*
X568250Y517500D01*
X563500D01*
G01D02*
X557750D01*
X557250Y518000D01*
G01X490846Y609075D02*
X509503D01*
G01X510000Y594500D02*
Y588750D01*
X509750Y588500D01*
G01D02*
Y583000D01*
G01Y579000D02*
X501092D01*
X501017Y579075D01*
X490846D01*
G01X509750Y583000D02*
Y579000D01*
G01X516000Y637413D02*
Y594500D01*
G01X509750Y1036000D02*
Y1041500D01*
G01Y1032000D02*
Y1036000D01*
G01X510000Y1047500D02*
Y1041750D01*
X509750Y1041500D01*
G01Y1032000D02*
X509581Y1031831D01*
X490846D01*
G01X574300Y972750D02*
X569500D01*
G01X577500Y978800D02*
Y975950D01*
X574300Y972750D01*
G01X563500Y979500D02*
X562750Y978750D01*
X557000D01*
G01Y985500D02*
Y986750D01*
X557250Y987000D01*
Y1002000D01*
G01X563000Y1017000D02*
Y1011750D01*
X557250Y1006000D01*
G01Y1002000D02*
Y1006000D01*
G01X557000Y978750D02*
Y985500D01*
G01X574940Y986200D02*
X568701D01*
X566574Y988327D01*
G01D02*
X564750Y990151D01*
Y996500D01*
G01X571000Y1019000D02*
Y1013000D01*
X564750Y1006750D01*
Y1000500D01*
G01Y996500D02*
Y1000500D01*
G01X580060Y978800D02*
Y972260D01*
X576100Y968300D01*
X574200D01*
G01X569500Y969250D02*
X570450Y968300D01*
X574200D01*
G01X557000Y975250D02*
Y973921D01*
X557088Y973833D01*
Y971162D01*
X557250Y971000D01*
G01X569500Y969250D02*
X567250D01*
X566000Y970500D01*
X563500D01*
G01D02*
X557750D01*
X557250Y971000D01*
G01X490846Y1061831D02*
X509503D01*
G01X516000Y1047500D02*
Y1119060D01*
X518465Y1121525D01*
X755669D01*
X802162Y1075032D01*
G01X583750Y64300D02*
X583700Y64350D01*
Y68200D01*
G01D02*
Y70850D01*
X585650Y72800D01*
G01D02*
Y74800D01*
X585750Y74900D01*
Y77000D01*
G01X577500Y80700D02*
Y78500D01*
X579000Y77000D01*
X585750D01*
G01X587250Y64300D02*
X590600D01*
G01X615059Y156319D02*
X633716D01*
G01X637300Y126300D02*
X637250Y126250D01*
X632974D01*
G01D02*
X628000D01*
G01X624000D02*
X624069Y126319D01*
X615059D01*
G01X628000Y126250D02*
X624000D01*
G01X654242Y376350D02*
Y372000D01*
G01Y376350D02*
Y383182D01*
G01D02*
Y389032D01*
G01X833200Y762840D02*
X828969D01*
X828766Y762637D01*
X819530D01*
X816402Y759509D01*
X788909D01*
X775200Y745800D01*
Y648267D01*
X833698Y589769D01*
Y523283D01*
X736256Y425841D01*
X687536D01*
X670390Y408695D01*
G01D02*
X668975Y407280D01*
Y402959D01*
G01D02*
Y396350D01*
G01X583550Y520300D02*
Y516300D01*
G01X577500Y533200D02*
Y531000D01*
X579000Y529500D01*
X585750D01*
G01X585650Y525400D02*
X583550Y523300D01*
Y520300D01*
G01X585750Y529500D02*
Y525500D01*
X585650Y525400D01*
G01X583550Y512800D02*
Y508800D01*
G01Y504600D02*
Y508800D01*
G01X615059Y609075D02*
X633716D01*
G01X634500Y594500D02*
Y588750D01*
X634250Y588500D01*
G01D02*
Y583000D01*
G01Y579000D02*
X634175Y579075D01*
X615059D01*
G01X634250Y583000D02*
Y579000D01*
G01X646680Y647138D02*
Y679430D01*
G01X640500Y594500D02*
Y601000D01*
X646680Y607180D01*
Y647138D01*
G01X582648Y829573D02*
Y825223D01*
G01Y842255D02*
Y836405D01*
G01D02*
Y829573D01*
G01X597555Y856859D02*
Y850250D01*
G01X659642Y829050D02*
Y824700D01*
G01Y841732D02*
Y835882D01*
G01D02*
Y829050D01*
G01X585904Y900960D02*
X594056Y909112D01*
G01X909940Y902564D02*
Y910665D01*
X897495Y923110D01*
X844282D01*
X832468Y911296D01*
X811172D01*
X811171Y911295D01*
X803621D01*
X803091Y911825D01*
X596769D01*
X594056Y909112D01*
G01X844940Y915701D02*
X838510Y909271D01*
X812011D01*
X812010Y909270D01*
X802782D01*
X802252Y909800D01*
X598744D01*
X589904Y900960D01*
G01X853398Y914258D02*
X846385Y907245D01*
X801943D01*
X801413Y907775D01*
X600719D01*
X593904Y900960D01*
G01X860219Y912294D02*
X853145Y905220D01*
X801104D01*
X800574Y905750D01*
X602694D01*
X597904Y900960D01*
G01X598970Y862595D02*
X597555Y861180D01*
Y856859D01*
G01X838400Y867160D02*
X780440D01*
X778656Y865376D01*
X601752D01*
X598970Y862595D01*
G01X610207Y900960D02*
X624543D01*
X627308Y903725D01*
X799735D01*
X800265Y903195D01*
X854995D01*
X866410Y914610D01*
X891511D01*
X899700Y906421D01*
Y902564D01*
G01X601904Y900960D02*
X610207D01*
G01X634250Y1036000D02*
Y1041500D01*
G01Y1032000D02*
Y1036000D01*
G01X634500Y1047500D02*
Y1041750D01*
X634250Y1041500D01*
G01Y1032000D02*
X634081Y1031831D01*
X615059D01*
G01X585750Y978100D02*
X583050Y975400D01*
Y973400D01*
G01D02*
Y969500D01*
G01X577500Y986200D02*
Y984000D01*
X579000Y982500D01*
X585750D01*
G01D02*
Y978100D01*
G01X586550Y969500D02*
X590200D01*
G01X615059Y1061831D02*
X633716D01*
G01X640500Y1047500D02*
Y1109500D01*
X650500Y1119500D01*
X748695D01*
X771236Y1096959D01*
G01X628500Y1464750D02*
Y1468500D01*
G01Y1464750D02*
X626750D01*
X610018Y1481482D01*
X587380D01*
X581102Y1475204D01*
Y1466929D01*
G01X707937Y57400D02*
X712250D01*
G01X707700Y65500D02*
X705500D01*
X704200Y64200D01*
Y59700D01*
X706500Y57400D01*
X707937D01*
G01X699600Y40850D02*
X695600D01*
G01X685500Y86000D02*
Y81500D01*
X687700Y79300D01*
G01X695600Y40850D02*
Y63036D01*
X687700Y70936D01*
Y79300D01*
G01X705500Y51300D02*
X702800D01*
X701250Y49750D01*
Y45050D01*
G01D02*
Y42500D01*
X699600Y40850D01*
G01X692250Y74000D02*
Y78500D01*
G01X695000Y113500D02*
Y111661D01*
X690500Y107161D01*
Y84250D01*
X692250Y82500D01*
G01Y78500D02*
Y82500D01*
G01Y74000D02*
Y69250D01*
X698560Y62940D01*
X700300D01*
G01X704750Y45050D02*
X706762D01*
X707312Y44500D01*
X710000D01*
G01X714000Y45250D02*
X713250Y44500D01*
X710000D01*
G01X715750Y57400D02*
Y55250D01*
X714500Y54000D01*
Y51300D01*
G01D02*
Y45750D01*
X714000Y45250D01*
G01X707700Y68060D02*
X710940D01*
X715750Y63250D01*
Y57400D01*
G01X700300Y65500D02*
X702500D01*
X704000Y67000D01*
Y73750D01*
G01X707937D02*
X712500D01*
G01D02*
X717000D01*
G01X704000D02*
X707937D01*
G01X717000Y77250D02*
Y79303D01*
X713803Y82500D01*
X712214D01*
G01X708200Y148900D02*
X711600Y152300D01*
X725500D01*
X729519Y156319D01*
X739272D01*
G01X748250Y126500D02*
Y130500D01*
G01Y126500D02*
X748069Y126319D01*
X739272D01*
G01X748400Y137100D02*
Y133150D01*
X748250Y133000D01*
Y130500D01*
G01X698300Y519750D02*
X693500D01*
G01X701500Y525800D02*
Y522950D01*
X698300Y519750D01*
G01X687500Y526500D02*
X686750Y525750D01*
X681000D01*
G01Y532500D02*
Y533750D01*
X681250Y534000D01*
Y549000D01*
G01X687000Y564000D02*
Y558750D01*
X681250Y553000D01*
G01Y549000D02*
Y553000D01*
G01X681000Y525750D02*
Y532500D01*
G01X698940Y533200D02*
X692793D01*
X690116Y535877D01*
G01D02*
X688750Y537243D01*
Y543500D01*
G01X695000Y566000D02*
Y553750D01*
X688750Y547500D01*
G01Y543500D02*
Y547500D01*
G01X704060Y525800D02*
Y518860D01*
X700300Y515100D01*
X698100D01*
G01D02*
X694650D01*
X693500Y516250D01*
G01X681000Y522250D02*
Y518250D01*
X681250Y518000D01*
G01X693500Y516250D02*
X691250D01*
X690000Y517500D01*
X687500D01*
G01D02*
X681750D01*
X681250Y518000D01*
G01X707800Y520800D02*
Y516950D01*
G01X709650Y525300D02*
X707800Y523450D01*
Y520800D01*
G01X709650Y525300D02*
Y529400D01*
X709750Y529500D01*
G01X701500Y533200D02*
Y531000D01*
X703000Y529500D01*
X709750D01*
G01X707800Y513450D02*
X704650D01*
X703200Y512000D01*
G01X698600Y511100D02*
X702300D01*
X703200Y512000D01*
G01X757929Y609075D02*
X739272D01*
G01X748200Y579050D02*
X748175Y579075D01*
X739272D01*
G01X752200Y579050D02*
X748200D01*
G01X752500Y588000D02*
X756300D01*
X757300Y587000D01*
Y582800D01*
G01X752200Y579050D02*
X756300D01*
X757300Y580050D01*
Y582800D01*
G01X752500Y594000D02*
Y597333D01*
X760667Y605500D01*
Y613787D01*
X749541Y624913D01*
Y717011D01*
G01D02*
Y755082D01*
X775918Y781459D01*
Y837071D01*
X778735Y839888D01*
G01X675790Y861395D02*
X674375Y859980D01*
Y855659D01*
G01D02*
Y849050D01*
G01X809630Y940330D02*
X809629Y940331D01*
Y938004D01*
X807900Y936275D01*
X769554D01*
X758562Y925283D01*
G01X769130Y919152D02*
X765218Y915240D01*
X712863D01*
X712760Y915137D01*
G01X838400Y864600D02*
X782100D01*
X780851Y863351D01*
X677746D01*
X675790Y861395D01*
G01X740364Y901060D02*
X856360D01*
X867500Y912200D01*
X890300D01*
X897140Y905360D01*
Y902564D01*
G01X740364Y901060D02*
X733901D01*
X733895Y901054D01*
G01X758250Y1043000D02*
Y1047750D01*
X757500Y1048500D01*
X752500D01*
G01X739272Y1031831D02*
X749381D01*
X749550Y1032000D01*
G01X749650Y1036000D02*
Y1032100D01*
X749550Y1032000D01*
G01X749650Y1036000D02*
Y1038513D01*
X750500Y1039363D01*
X757500D01*
X758250Y1040113D01*
Y1043000D01*
G01X698300Y972750D02*
X693500D01*
G01X701500Y978800D02*
Y975950D01*
X698300Y972750D01*
G01X687500Y979500D02*
X686750Y978750D01*
X681000D01*
G01Y985500D02*
Y986750D01*
X681250Y987000D01*
Y1002000D01*
G01X687000Y1017000D02*
Y1011750D01*
X681250Y1006000D01*
G01Y1002000D02*
Y1006000D01*
G01X681000Y978750D02*
Y985500D01*
G01X698940Y986200D02*
X693151D01*
X690141Y989210D01*
G01X688750Y996500D02*
Y990601D01*
X690141Y989210D01*
G01X695000Y1019000D02*
Y1013000D01*
X688750Y1006750D01*
Y1000500D01*
G01D02*
Y996500D01*
G01X693500Y969250D02*
X694450Y968300D01*
X698000D01*
G01X704060Y978800D02*
Y971660D01*
X700700Y968300D01*
X698000D01*
G01X681000Y975250D02*
Y971250D01*
X681250Y971000D01*
G01X693500Y969250D02*
X691250D01*
X690000Y970500D01*
X687500D01*
G01D02*
X681750D01*
X681250Y971000D01*
G01X707450Y973600D02*
Y969600D01*
G01X709750Y982500D02*
X709850Y982400D01*
Y978300D01*
G01D02*
X707450Y975900D01*
Y973600D01*
G01X701500Y986200D02*
Y984000D01*
X703000Y982500D01*
X709750D01*
G01X714400Y969600D02*
X710950D01*
G01X739272Y1061831D02*
X757929D01*
G01X752500Y1054500D02*
X784291D01*
X797473Y1041318D01*
G01X987300Y1179800D02*
X981314D01*
X959876Y1158362D01*
X792476D01*
X787776Y1153662D01*
X777162D01*
X762100Y1138600D01*
X759700D01*
G01X982172Y1176631D02*
X961878Y1156337D01*
X793315D01*
X788615Y1151637D01*
X778001D01*
X761364Y1135000D01*
X759762D01*
G01X705500Y1463000D02*
X716250D01*
G01X700050Y1460390D02*
Y1461286D01*
X701764Y1463000D01*
X705500D01*
G01X716250Y1458500D02*
X711363D01*
G01X699750Y1458421D02*
X711284D01*
X711363Y1458500D01*
G01X719750Y1463000D02*
X722084D01*
X724066Y1461018D01*
G01X719750Y1458500D02*
X723008D01*
X724255Y1457253D01*
G01X855118Y262992D02*
X850530Y267580D01*
Y312728D01*
X849325Y313933D01*
Y362274D01*
X854325Y367274D01*
Y406964D01*
X850947Y410342D01*
G01X855118Y268504D02*
X852620Y271002D01*
Y361785D01*
X857000Y366165D01*
Y407044D01*
X860298Y410342D01*
G01X840945Y262992D02*
X836363Y267574D01*
Y311837D01*
X835832Y312368D01*
Y394295D01*
X836451Y394914D01*
Y444751D01*
G01X840945Y268504D02*
X838438Y271011D01*
Y315763D01*
X838507Y315832D01*
Y393186D01*
X839548Y394227D01*
Y446498D01*
X844585Y451535D01*
G01X862205Y277953D02*
X864703Y280451D01*
Y312343D01*
X864225Y312821D01*
Y361080D01*
X876762Y373617D01*
Y416683D01*
X876742Y416703D01*
Y446789D01*
X882358Y452405D01*
Y544893D01*
X779700Y647551D01*
Y734571D01*
X778627Y735644D01*
G01X862205Y272441D02*
X866794Y277030D01*
Y315625D01*
X866900Y315731D01*
Y359971D01*
X879437Y372508D01*
Y445700D01*
X885033Y451296D01*
Y546002D01*
X782700Y648335D01*
Y741032D01*
X778683Y745049D01*
G01X855118Y291338D02*
X859700Y295920D01*
Y311960D01*
X861000Y313260D01*
Y361771D01*
X868753Y369524D01*
Y417758D01*
X872137Y421142D01*
G01X855118Y296850D02*
X857625Y299357D01*
Y362180D01*
X866078Y370633D01*
Y417830D01*
X862766Y421142D01*
G01X840945Y291338D02*
X845524Y295917D01*
Y312832D01*
X845968Y313276D01*
Y380023D01*
G01X841939Y386365D02*
X842786Y385518D01*
Y374795D01*
G01X840945Y296850D02*
X842530D01*
X843449Y297769D01*
Y313051D01*
X843293Y313207D01*
Y370295D01*
X842786Y370802D01*
Y374795D01*
G01X833859Y286614D02*
X829286Y291187D01*
Y312666D01*
X829486Y312866D01*
Y430890D01*
X829484Y430892D01*
Y432138D01*
X827288Y434334D01*
X826042D01*
X812282Y448094D01*
G01X833859Y292126D02*
X831361Y294624D01*
Y311806D01*
X832452Y312897D01*
Y434146D01*
X815255Y451343D01*
G01X867299Y493300D02*
Y485000D01*
X858707Y476408D01*
Y449688D01*
X854285Y445266D01*
Y413680D01*
X850947Y410342D01*
G01X867299Y497200D02*
X870100Y494399D01*
Y483600D01*
X861382Y474882D01*
Y455100D01*
X861383Y455099D01*
Y448580D01*
X856960Y444157D01*
Y413680D01*
X860298Y410342D01*
G01X873200Y487300D02*
X873000Y487100D01*
Y482500D01*
X865325Y474825D01*
Y428149D01*
X866104Y427370D01*
Y423258D01*
X864150Y421304D01*
X862928D01*
X862766Y421142D01*
G01X848799Y457202D02*
X844202D01*
X836451Y449451D01*
Y444751D01*
G01X844585Y451535D02*
X847478D01*
X849539Y453596D01*
G01X846939Y386365D02*
X845968Y385394D01*
Y380023D01*
G01X867299Y508600D02*
X869975Y505924D01*
Y503592D01*
X855574Y489191D01*
Y450339D01*
X845754Y440519D01*
Y391050D01*
X846939Y389865D01*
G01X841939D02*
X843075Y391001D01*
Y441624D01*
X852899Y451448D01*
Y490300D01*
X867299Y504700D01*
G01X837390Y657790D02*
X829490D01*
G01D02*
X828390D01*
X826990Y659190D01*
X824740D01*
G01D02*
Y655190D01*
G01X859590Y652670D02*
X863709D01*
X866276Y650103D01*
G01X865530Y655230D02*
X859590D01*
G01X837390D02*
X833530D01*
X830990Y652690D01*
G01X824740Y651190D02*
X829490D01*
X830990Y652690D01*
G01X837390Y652670D02*
X834970D01*
X832990Y650690D01*
Y649190D01*
X830990Y647190D01*
X829490D01*
G01D02*
X824740D01*
G01X816068Y625673D02*
X817841Y623900D01*
X821208D01*
X894530Y550578D01*
Y342889D01*
X882823Y331182D01*
G01X816068Y625673D02*
X785375Y656366D01*
Y681275D01*
X790760Y686660D01*
X815740D01*
X822899Y679501D01*
X831355D01*
X832586Y678270D01*
X837390D01*
G01X859590Y657790D02*
X873325D01*
X873563Y658028D01*
X879516D01*
X932992Y604552D01*
X1164529D01*
X1199886Y569195D01*
Y476448D01*
X1234254Y442080D01*
G01X859590Y660350D02*
X880058D01*
X932971Y607437D01*
X1172291D01*
X1200821Y578907D01*
Y571124D01*
X1201911Y570034D01*
Y479515D01*
X1214128Y467298D01*
X1214129D01*
X1216078Y465349D01*
G01X859590Y662910D02*
X880362D01*
X933176Y610096D01*
X1175335D01*
X1202846Y582585D01*
Y571963D01*
X1203936Y570873D01*
Y482582D01*
X1232660Y453858D01*
G01X859590Y665470D02*
X880666D01*
X932965Y613171D01*
X1178851D01*
X1205415Y586607D01*
Y572258D01*
X1205961Y571712D01*
Y485649D01*
X1248784Y442826D01*
G01X837390Y675710D02*
X844910D01*
X852900Y667720D01*
Y652477D01*
X855752Y649625D01*
Y626268D01*
X863430Y618590D01*
G01X837390Y673150D02*
X843770D01*
X850875Y666045D01*
Y651637D01*
X851355Y651157D01*
X851356D01*
X853727Y648786D01*
Y617248D01*
X909075Y561900D01*
Y556526D01*
X909090Y556511D01*
Y370280D01*
X910360Y369010D01*
Y363520D01*
X910330Y363490D01*
G01X908340Y360430D02*
X907065Y361705D01*
Y555672D01*
X851702Y611035D01*
Y647947D01*
X850517Y649132D01*
X850516D01*
X848850Y650798D01*
Y664830D01*
X843090Y670590D01*
X837390D01*
G01X788160Y666220D02*
X792598Y661782D01*
X800514D01*
X810132Y671400D01*
X828000D01*
X831370Y668030D01*
X837390D01*
G01D02*
X842170D01*
X846825Y663375D01*
Y649959D01*
X849677Y647107D01*
Y607737D01*
X905040Y552374D01*
Y359907D01*
X909423Y355524D01*
Y354393D01*
G01X821240Y651190D02*
X814320D01*
Y651120D01*
G01X821240Y647190D02*
X813980D01*
Y647430D01*
G01X898059Y343029D02*
Y345196D01*
X897600Y345655D01*
Y550372D01*
X812136Y635836D01*
X808769D01*
Y635837D01*
X796484Y648122D01*
Y648490D01*
G01X837390Y665470D02*
X831066D01*
X827185Y669351D01*
X811049D01*
X796484Y654786D01*
Y648490D01*
G01X902184Y347219D02*
Y347931D01*
X899900Y350215D01*
Y550936D01*
X812068Y638768D01*
X809670D01*
X800684Y647754D01*
Y652390D01*
G01X837390Y662910D02*
X830762D01*
X826347Y667325D01*
X820669D01*
X820668Y667326D01*
X818992D01*
X818991Y667325D01*
X812082D01*
X800684Y655927D01*
Y652390D01*
G01X906616Y351586D02*
Y352622D01*
X902589Y356649D01*
Y551111D01*
X812907Y640793D01*
X810810D01*
X805128Y646475D01*
G01X837390Y660350D02*
X830458D01*
X825508Y665300D01*
X813177D01*
X805128Y657251D01*
Y646475D01*
G01X859590Y650110D02*
X863033D01*
X865945Y647198D01*
Y643688D01*
G01X871192Y322500D02*
X871621Y322071D01*
Y315731D01*
X871630Y315722D01*
Y312700D01*
X871801Y312529D01*
Y291191D01*
X876378Y286614D01*
G01X874562Y321680D02*
X874296Y321414D01*
Y313041D01*
X873876Y312621D01*
Y294628D01*
X876378Y292126D01*
G01X855400Y765400D02*
X857900D01*
X859500Y763800D01*
Y762500D01*
X862000Y760000D01*
X862500D01*
G01D02*
X866050D01*
X867050Y761000D01*
G01X837390Y678270D02*
X837709Y678589D01*
Y681095D01*
G01X1277678Y403046D02*
Y417098D01*
X1208710Y486066D01*
Y589776D01*
X1182831Y615655D01*
X933540D01*
X881345Y667850D01*
X879042D01*
X817373Y729519D01*
Y744099D01*
G01X833200Y760280D02*
X823667D01*
X817373Y753986D01*
Y744099D01*
G01X1338423Y429770D02*
X1323293Y444900D01*
X1269924D01*
X1249292Y465532D01*
Y472870D01*
X1217836Y504326D01*
Y592133D01*
X1185667Y624302D01*
X957533D01*
X957532Y624301D01*
X939076D01*
X939075Y624302D01*
X937476D01*
X932733Y629045D01*
Y629046D01*
X821261Y740518D01*
Y742194D01*
X821262Y742195D01*
Y750518D01*
X828464Y757720D01*
X833200D01*
G01Y755160D02*
X828768D01*
X823287Y749679D01*
Y741356D01*
X934758Y629885D01*
Y629884D01*
X938315Y626327D01*
X939914D01*
X939915Y626326D01*
X956693D01*
X956694Y626327D01*
X1186506D01*
X1221512Y591321D01*
Y503514D01*
X1251318Y473708D01*
Y466370D01*
X1270763Y446925D01*
X1443594D01*
X1462350Y428169D01*
G01X833200Y752600D02*
X829072D01*
X825312Y748840D01*
Y742195D01*
X936783Y630724D01*
Y630723D01*
X939154Y628352D01*
X940753D01*
X940754Y628351D01*
X955854D01*
X955855Y628352D01*
X1189025D01*
X1225314Y592063D01*
Y502576D01*
X1253343Y474547D01*
Y467209D01*
X1271602Y448950D01*
X1560906D01*
X1578333Y431523D01*
G01X833200Y750040D02*
X829376D01*
X827337Y748001D01*
Y743034D01*
X938808Y631563D01*
Y631562D01*
X939993Y630377D01*
X941592D01*
X941593Y630376D01*
X955015D01*
X955016Y630377D01*
X1189864D01*
X1228832Y591409D01*
Y501922D01*
X1255368Y475386D01*
Y468048D01*
X1272441Y450975D01*
X1626467D01*
X1665928Y411514D01*
X1721299D01*
X1721381Y411596D01*
G01X833200Y747480D02*
X829680D01*
X829362Y747162D01*
Y743873D01*
X940833Y632402D01*
X942431D01*
X942432Y632401D01*
X954176D01*
X954177Y632402D01*
X1190703D01*
X1232508Y590597D01*
Y501110D01*
X1257393Y476225D01*
Y468887D01*
X1273280Y453000D01*
X1630708D01*
X1667837Y415871D01*
X1779110D01*
X1786451Y408530D01*
G01X789442Y681063D02*
X793014Y684635D01*
X811245D01*
X816104Y679776D01*
G01D02*
X818404Y677476D01*
X830516D01*
X832282Y675710D01*
X837390D01*
G01X806535Y676210D02*
X802390D01*
X796200Y682400D01*
G01X806535Y676210D02*
X813826D01*
X814585Y675451D01*
X829677D01*
X831978Y673150D01*
X837390D01*
G01Y670590D02*
X831674D01*
X828839Y673425D01*
X796587D01*
X791243Y668081D01*
G01X838900Y817600D02*
X831000D01*
G01D02*
X828782D01*
X827382Y819000D01*
X826250D01*
G01D02*
Y815000D01*
G01X861100Y812480D02*
X863520D01*
X869000Y807000D01*
G01X867040Y815040D02*
X861100D01*
G01X868500Y803050D02*
X863241D01*
X861986Y804305D01*
G01X861100Y809920D02*
Y805191D01*
X861986Y804305D01*
G01X838900Y815040D02*
X835040D01*
X832500Y812500D01*
G01X826250Y811000D02*
X831000D01*
X832500Y812500D01*
G01X830000Y807000D02*
X826250D01*
G01X838900Y812480D02*
X836480D01*
X831000Y807000D01*
X830000D01*
G01X833200Y770520D02*
X828980D01*
X824500Y775000D01*
G01D02*
X823000Y776500D01*
X818050D01*
G01D02*
Y781000D01*
G01X833200Y767960D02*
X827640D01*
X826600Y769000D01*
X824000D01*
G01D02*
X822500D01*
X821000Y767500D01*
X818050D01*
G01D02*
Y772000D01*
G01X855400Y767960D02*
X858740D01*
X860200Y766500D01*
X861800D01*
X863100Y765200D01*
G01X855400Y770520D02*
X859680D01*
X860700Y769500D01*
X862600D01*
G01X867050Y770000D02*
X866550Y769500D01*
X862600D01*
G01X860600Y862040D02*
X854268D01*
X852946Y860718D01*
Y847551D01*
X857172Y843325D01*
X865230D01*
X869709Y838846D01*
Y836291D01*
X883750Y822250D01*
G01X860600Y864600D02*
X852520D01*
X850920Y863000D01*
Y858133D01*
X850921Y858132D01*
Y845779D01*
X855400Y841300D01*
X864391D01*
X867684Y838007D01*
Y831941D01*
X874562Y825063D01*
G01X861100Y817600D02*
X868742D01*
X869989Y818847D01*
G01X861100Y820160D02*
X867299D01*
X870001Y822862D01*
G01X861100Y822720D02*
X857720D01*
X857262Y822262D01*
Y802301D01*
X866662Y792901D01*
X877901D01*
X888075Y782727D01*
Y703942D01*
X947466Y644551D01*
X949142D01*
X949143Y644552D01*
X1196757D01*
X1216040Y625269D01*
G01X861100Y825280D02*
X856659D01*
X855237Y823858D01*
Y801462D01*
X865823Y790876D01*
X877062D01*
X885940Y781998D01*
Y703213D01*
X946627Y642526D01*
X949981D01*
X949982Y642527D01*
X1194898D01*
X1249618Y587807D01*
Y498320D01*
X1267519Y480419D01*
Y473081D01*
X1273185Y467415D01*
X1327523D01*
X1344024Y483916D01*
G01X1465195Y482118D02*
X1448467Y465390D01*
X1272346D01*
X1265494Y472242D01*
Y479580D01*
X1246748Y498326D01*
Y587813D01*
X1194059Y640502D01*
X950821D01*
X950820Y640501D01*
X945788D01*
X883914Y702375D01*
Y704051D01*
X883915Y704052D01*
Y781159D01*
X876290Y788784D01*
X865051D01*
X853212Y800623D01*
Y825454D01*
X855598Y827840D01*
X861100D01*
G01X1587023Y474261D02*
X1573462Y460700D01*
X1274172D01*
X1263469Y471403D01*
Y478741D01*
X1243028Y499182D01*
Y588669D01*
X1193220Y638477D01*
X951660D01*
X951659Y638476D01*
X944949D01*
X881889Y701536D01*
Y704890D01*
X881890Y704891D01*
Y780320D01*
X875452Y786758D01*
X864213D01*
X851187Y799784D01*
Y827050D01*
X854537Y830400D01*
X861100D01*
G01Y832960D02*
X853476D01*
X849162Y828646D01*
Y798945D01*
X863562Y784545D01*
X873123D01*
X873124Y784546D01*
X874800D01*
X879601Y779745D01*
Y760718D01*
X879721Y760598D01*
Y754986D01*
X879601Y754866D01*
Y700960D01*
X944110Y636451D01*
X952498D01*
X952499Y636452D01*
X1192381D01*
X1239732Y589101D01*
Y499614D01*
X1261444Y477902D01*
Y470564D01*
X1273333Y458675D01*
X1274997D01*
X1274998Y458674D01*
X1277038D01*
X1277039Y458675D01*
X1662396D01*
X1701720Y497999D01*
G01X1860109Y497977D02*
X1843241Y481109D01*
X1815554D01*
X1805248Y470803D01*
X1767041D01*
X1764599Y473245D01*
Y481936D01*
X1758173Y488362D01*
X1697288D01*
X1664726Y455800D01*
X1273344D01*
X1259419Y469725D01*
Y477063D01*
X1236183Y500299D01*
Y589786D01*
X1191542Y634427D01*
X953338D01*
X953337Y634426D01*
X943271D01*
X877575Y700122D01*
Y701798D01*
X877576Y701799D01*
Y755705D01*
X877696Y755825D01*
Y759759D01*
X877576Y759879D01*
Y778906D01*
X873962Y782520D01*
X862723D01*
X847137Y798106D01*
Y830242D01*
X852415Y835520D01*
X861100D01*
G01X838900Y822720D02*
X829390D01*
X827723Y824387D01*
X805523D01*
X799075Y817939D01*
Y772075D01*
X791500Y764500D01*
G01X838900Y820160D02*
X829086D01*
X826884Y822362D01*
X806362D01*
X801100Y817100D01*
Y770700D01*
X795300Y764900D01*
G01X860600Y856920D02*
Y853984D01*
X882447Y832137D01*
Y831836D01*
X886583Y827700D01*
X888100D01*
G01X860600Y859480D02*
X855970D01*
X854971Y858481D01*
Y856448D01*
X880209Y831210D01*
G01X822750Y811000D02*
X815498D01*
X815469Y811029D01*
G01X822750Y807000D02*
X815380D01*
X815330Y807050D01*
G01X817950Y785500D02*
X819500D01*
X824500Y780500D01*
G01X833200Y773080D02*
X829448D01*
X828297Y774231D01*
Y776703D01*
X824500Y780500D01*
G01X819870Y940330D02*
Y932430D01*
G01X822470Y927680D02*
X818470D01*
G01D02*
Y929930D01*
X819870Y931330D01*
Y932430D01*
G01X822430Y940330D02*
Y936470D01*
X824970Y933930D01*
G01X826470Y927680D02*
Y932430D01*
X824970Y933930D01*
G01X830470Y927680D02*
Y932300D01*
X830300Y932470D01*
G01X824990Y940330D02*
Y937780D01*
X830300Y932470D01*
G01X860600Y877400D02*
X863200D01*
X867100Y873500D01*
X867700D01*
G01X838400Y882520D02*
X836075D01*
X832000Y886595D01*
Y887000D01*
G01D02*
X830500Y888500D01*
X827750D01*
G01D02*
Y893000D01*
G01X838400Y879960D02*
X833540D01*
X832000Y881500D01*
G01D02*
X830604D01*
X829889Y880785D01*
X828166D01*
X827637Y880256D01*
G01D02*
Y884453D01*
G01X860600Y879960D02*
X864698D01*
X866458Y878200D01*
X867700D01*
G01X860600Y882520D02*
X863320D01*
X863800Y883000D01*
X867350D01*
G01X838400Y877400D02*
X826165D01*
X825427Y876662D01*
X798818D01*
X796396Y879084D01*
G01X838400Y874840D02*
X826469D01*
X826266Y874637D01*
X787472D01*
X785560Y876549D01*
G01X907380Y902564D02*
Y909604D01*
X895899Y921085D01*
X850324D01*
X844940Y915701D01*
G01X804510Y940330D02*
Y946591D01*
X808309Y950390D01*
X891483D01*
X915630Y974537D01*
Y984023D01*
X975352Y1043745D01*
X1203196D01*
X1243867Y1003074D01*
Y941058D01*
X1270800Y914125D01*
X1328017D01*
X1335088Y921196D01*
X1725917D01*
X1726771Y922050D01*
G01X807070Y940330D02*
Y945530D01*
X809905Y948365D01*
X892322D01*
X917655Y973698D01*
Y983184D01*
X976191Y1041720D01*
X1202357D01*
X1241842Y1002235D01*
Y940219D01*
X1269962Y912099D01*
X1328856D01*
X1333600Y916843D01*
Y916844D01*
X1335927Y919171D01*
X1764543D01*
X1770722Y925350D01*
X1796350D01*
X1814500Y943500D01*
X1861278D01*
X1866318Y948540D01*
G01X812190Y940330D02*
Y935650D01*
X810790Y934250D01*
X773233D01*
X768449Y929466D01*
G01X817310Y940330D02*
Y934770D01*
X812740Y930200D01*
X780178D01*
X769130Y919152D01*
G01X904820Y902564D02*
Y908543D01*
X894303Y919060D01*
X858200D01*
X853398Y914258D01*
G01X902260Y902564D02*
Y907482D01*
X893014Y916728D01*
X864653D01*
X860219Y912294D01*
G01X838400Y862040D02*
X825900D01*
G01X838400Y859480D02*
X828080D01*
X826000Y857400D01*
G01X799390Y940330D02*
Y948713D01*
X805117Y954440D01*
X889805D01*
X911578Y976213D01*
Y985699D01*
X973674Y1047795D01*
X1204874D01*
X1248317Y1004352D01*
Y942336D01*
X1272478Y918175D01*
X1326339D01*
X1333410Y925246D01*
X1467097D01*
X1472646Y930795D01*
G01X801950Y940330D02*
Y947652D01*
X806713Y952415D01*
X890644D01*
X913604Y975375D01*
Y984861D01*
X974513Y1045770D01*
X1204035D01*
X1246292Y1003513D01*
Y941497D01*
X1271639Y916150D01*
X1327178D01*
X1334249Y923221D01*
X1605886D01*
X1607884Y925219D01*
G01X826470Y924180D02*
Y919076D01*
X824040Y916646D01*
X808954D01*
X801300Y924300D01*
G01X830470Y924180D02*
Y917440D01*
X827001Y913971D01*
X807845D01*
X798624Y923192D01*
Y925408D01*
X799303Y926087D01*
Y927296D01*
G01X838400Y885080D02*
Y890600D01*
X833500Y895500D01*
G01X827750Y897500D02*
X831500D01*
X833500Y895500D01*
G01X824990Y962530D02*
Y966489D01*
X827233Y968732D01*
X828772D01*
X830470Y970430D01*
G01D02*
Y974180D01*
G01D02*
X834470D01*
G01X822430Y962530D02*
Y968470D01*
G01D02*
Y974140D01*
X822470Y974180D01*
G01D02*
X826470D01*
G01X839970Y966420D02*
X839684Y966706D01*
X834871D01*
G01X827550Y962530D02*
Y965531D01*
X828725Y966706D01*
X834871D01*
G01X819870Y962530D02*
Y976265D01*
X817753Y978382D01*
Y1078073D01*
X779222Y1116604D01*
G01X817310Y962530D02*
Y974078D01*
X814330Y977058D01*
Y1026361D01*
G01X814750Y962530D02*
Y973089D01*
X811162Y976677D01*
Y1028149D01*
X810751Y1028560D01*
G01X812190Y962530D02*
Y971466D01*
X808500Y975156D01*
Y1068694D01*
X802162Y1075032D01*
G01X809630Y962530D02*
Y969843D01*
X805712Y973761D01*
Y1062483D01*
X771236Y1096959D01*
G01X807070Y962530D02*
Y967968D01*
X802289Y972749D01*
Y1036502D01*
X797473Y1041318D01*
G01X804510Y962530D02*
Y959511D01*
X805329Y958692D01*
X888329D01*
X907528Y977891D01*
Y1016682D01*
X943844Y1052998D01*
X1223634D01*
G01X801950Y962530D02*
Y959207D01*
X804490Y956667D01*
X889168D01*
X909553Y977052D01*
Y986538D01*
X972835Y1049820D01*
X1205713D01*
X1250343Y1005190D01*
Y943174D01*
X1273317Y920200D01*
X1325500D01*
X1332571Y927271D01*
X1338701D01*
X1340324Y928894D01*
G01X844120Y974180D02*
X848320D01*
X848400Y974100D01*
G01X844120Y974180D02*
X839970D01*
G01D02*
Y969920D01*
G01X911811Y263779D02*
X991924Y343892D01*
Y362424D01*
X1014416Y384916D01*
Y385157D01*
X1042634Y413375D01*
X1058623D01*
X1067872Y422624D01*
G01X911811Y258268D02*
X994599Y341056D01*
Y345251D01*
X994600Y345252D01*
Y349146D01*
X994599Y349147D01*
Y360961D01*
X1017091Y383453D01*
Y384048D01*
X1043743Y410700D01*
X1065976D01*
X1074400Y419124D01*
G01X911811Y268110D02*
X912832D01*
X989899Y345222D01*
Y364299D01*
X1036100Y410500D01*
G01X904725Y282677D02*
X904877D01*
X909315Y287115D01*
Y314458D01*
X1015257Y420400D01*
X1045300D01*
G01X876378Y277953D02*
X879257Y280832D01*
Y318857D01*
X922800Y362400D01*
G01X876378Y272441D02*
X881932Y277995D01*
Y317667D01*
X922365Y358100D01*
X922700D01*
G01X890552Y262992D02*
X893052Y265492D01*
Y317932D01*
G01X904725Y287008D02*
X905308D01*
X907240Y288940D01*
Y315489D01*
X1014979Y423228D01*
X1033200D01*
G01X904725Y301181D02*
Y301775D01*
X902218Y304282D01*
Y317356D01*
X904844Y319982D01*
X908869D01*
X1015018Y426131D01*
X1017500D01*
G01X897638Y296457D02*
Y296878D01*
X900142Y299382D01*
Y318144D01*
X904427Y322429D01*
X908452D01*
X1015412Y429389D01*
X1044789D01*
X1047900Y432500D01*
G01X897638Y300787D02*
Y301362D01*
X895127Y303873D01*
Y312210D01*
X895890Y312973D01*
Y316756D01*
X903809Y324675D01*
X907834D01*
X1014573Y431414D01*
X1037314D01*
X1041600Y435700D01*
G01X950843Y378827D02*
Y378437D01*
X1002209Y429803D01*
Y429811D01*
X1009628Y437230D01*
X1016557D01*
G01X872137Y421142D02*
X868779Y424500D01*
Y428479D01*
X868000Y429258D01*
Y473000D01*
X875922Y480922D01*
Y491178D01*
X873000Y494100D01*
G01X1115105Y520057D02*
X1113731Y518683D01*
Y505210D01*
X1125048Y493893D01*
Y476070D01*
X1120265Y471287D01*
X971071D01*
X922525Y519833D01*
G01X1109593Y520057D02*
X1111056Y518594D01*
Y504101D01*
X1122373Y492784D01*
Y477179D01*
X1119156Y473962D01*
X972787D01*
X929182Y517567D01*
X929096D01*
G01X959913Y522177D02*
X955800D01*
X953673Y520050D01*
X952100D01*
G01X947587Y520632D02*
X944919D01*
X944387Y520100D01*
G01X952100Y520050D02*
X949682D01*
X949100Y520632D01*
X947587D01*
G01X941557Y547005D02*
X945656D01*
G01X950639Y546991D02*
X945670D01*
X945656Y547005D01*
G01X950639Y546991D02*
X954141D01*
X955000Y547850D01*
G01X962271Y548291D02*
X955441D01*
X955000Y547850D01*
G01X1113593Y476094D02*
X1109187Y480500D01*
X970740D01*
X935490Y515750D01*
Y519550D01*
G01X959913Y524737D02*
X956724D01*
X956609Y524852D01*
X952818D01*
X952703Y524737D01*
X951860D01*
G01D02*
X950763D01*
X950158Y524132D01*
X947587D01*
G01X935490Y519550D02*
X936070Y520130D01*
X940440D01*
X942977Y522667D01*
Y524023D01*
G01X947587Y524132D02*
X943086D01*
X942977Y524023D01*
G01X945838Y529107D02*
X946751Y530020D01*
X951739D01*
G01X959913Y527297D02*
X957403D01*
X954680Y530020D01*
X951739D01*
G01X950639Y550491D02*
X946967D01*
X946079Y551379D01*
G01X962271Y550851D02*
X957849D01*
X957100Y551600D01*
X951748D01*
X950639Y550491D01*
G01X946123Y556600D02*
X951915D01*
G01X962271Y553411D02*
X959889D01*
X956700Y556600D01*
X951915D01*
G01X866276Y650103D02*
X869189Y647190D01*
X871240D01*
G01D02*
Y643190D01*
G01X865530Y655230D02*
X871200D01*
X871240Y655190D01*
G01D02*
Y651190D01*
G01X883750Y822250D02*
X892351Y813649D01*
Y705394D01*
X949143Y648602D01*
X1251254D01*
X1269477Y666825D01*
X1663425D01*
X1672200Y675600D01*
Y820333D01*
X1712280Y860413D01*
X1727525D01*
X1728694Y859244D01*
Y855959D01*
G01X1852907D02*
Y860061D01*
X1851043Y861925D01*
X1839651D01*
X1827214Y849488D01*
Y689076D01*
X1802938Y664800D01*
X1271830D01*
X1253607Y646577D01*
X948304D01*
X890326Y704555D01*
Y809299D01*
X874562Y825063D01*
G01X1245567Y420602D02*
X1192440Y473729D01*
Y568960D01*
X1165245Y596155D01*
X918871D01*
X892391Y622635D01*
G01D02*
X884801Y630225D01*
G01X898676Y631324D02*
X930137Y599863D01*
X1165315D01*
X1194465Y570713D01*
Y476796D01*
X1247949Y423312D01*
Y423302D01*
G01X898676Y631324D02*
X896300Y633700D01*
X892400D01*
G01X896283Y829425D02*
X900451Y825257D01*
Y708750D01*
X952499Y656702D01*
X1235102D01*
X1259100Y680700D01*
Y852600D01*
X1255741Y855959D01*
X1231844D01*
G01X886342Y834927D02*
X898426Y822843D01*
Y707911D01*
X951660Y654677D01*
X1247041D01*
X1266164Y673800D01*
X1325100D01*
X1330716Y679416D01*
Y856516D01*
X1335273Y861073D01*
X1355142D01*
X1356057Y860158D01*
Y855959D01*
G01X888100Y827700D02*
X896401Y819399D01*
Y707072D01*
X950821Y652652D01*
X1247880D01*
X1266103Y670875D01*
X1428675D01*
X1449000Y691200D01*
Y852500D01*
X1457133Y860633D01*
X1477761D01*
X1480269Y858125D01*
Y855959D01*
G01X880209Y831210D02*
X894376Y817043D01*
Y706233D01*
X949982Y650627D01*
X1250415D01*
X1268638Y668850D01*
X1565941D01*
X1583300Y686209D01*
Y818800D01*
X1578489Y823611D01*
Y855012D01*
X1583977Y860500D01*
X1602382D01*
X1604482Y858400D01*
Y855959D01*
G01X871240Y635690D02*
X870200Y634650D01*
Y631500D01*
G01X871240Y639190D02*
X867873D01*
X865945Y641118D01*
Y643688D01*
G01X960370Y761010D02*
X958120D01*
X956894Y762236D01*
Y766356D01*
X955482Y767768D01*
G01X867050Y761000D02*
Y756500D01*
G01X925400Y782520D02*
X931680D01*
X935025Y779175D01*
Y771239D01*
X956639Y749625D01*
X974939D01*
X1008225Y716339D01*
Y684075D01*
X1031277Y661023D01*
X1116345D01*
X1118505Y658863D01*
G01X1114905Y658882D02*
X1029218D01*
X1006200Y681900D01*
Y715500D01*
X974100Y747600D01*
X955800D01*
X933000Y770400D01*
Y778336D01*
X931376Y779960D01*
X925400D01*
G01X903300Y763200D02*
Y763000D01*
X903000Y762700D01*
Y758975D01*
X903125Y758850D01*
G01X912250Y778000D02*
Y782800D01*
G01X925400Y777400D02*
X921920D01*
X920820Y778500D01*
X917600D01*
G01D02*
X915009D01*
X914509Y778000D01*
X912250D01*
G01X947600Y772280D02*
X952702D01*
X953390Y772968D01*
X955482D01*
G01D02*
X957412D01*
X960370Y770010D01*
G01X947600Y774840D02*
X950831D01*
X954159Y778168D01*
X955482D01*
G01D02*
X957307D01*
X958149Y779010D01*
X960370D01*
G01X947600Y769720D02*
X953530D01*
X955482Y767768D01*
G01X917700Y774200D02*
X916500D01*
X916300Y774000D01*
X912250D01*
G01X925400Y774840D02*
X920599D01*
X919959Y774200D01*
X917700D01*
G01Y769200D02*
Y770279D01*
X918548Y771127D01*
X920745D01*
X921898Y772280D01*
X925400D01*
G01X919550Y764800D02*
Y766234D01*
X917700Y768084D01*
Y769200D01*
G01X951430Y861030D02*
Y857430D01*
X948300Y854300D01*
X946634D01*
X946167Y853833D01*
G01X944000Y849250D02*
X948500D01*
G01D02*
Y851500D01*
X946167Y853833D01*
G01X953990Y861030D02*
Y855990D01*
X952500Y854500D01*
G01X957500Y849250D02*
X953000D01*
G01D02*
X952500Y849750D01*
Y854500D01*
G01X956550Y861030D02*
Y856871D01*
X956061Y856382D01*
Y855162D01*
X957095Y854128D01*
G01X962000Y849250D02*
X961973D01*
X957095Y854128D01*
G01X935000Y849250D02*
X935250Y849500D01*
Y854000D01*
G01X946310Y861030D02*
X942280D01*
X935250Y854000D01*
G01X939500Y849250D02*
Y853500D01*
X940000Y854000D01*
G01X948870Y861030D02*
X948600Y860760D01*
Y858435D01*
X947265Y857100D01*
X943100D01*
X940000Y854000D01*
G01X872750Y803000D02*
X874903Y805153D01*
Y807000D01*
G01D02*
X869000D01*
G01X874903Y811000D02*
Y812847D01*
X872750Y815000D01*
G01D02*
X872710Y815040D01*
X867040D01*
G01X867050Y765500D02*
X866750Y765200D01*
X863100D01*
G01X1115105Y819270D02*
X1110521Y814686D01*
X1086063D01*
X1080288Y808911D01*
X1007613D01*
X1003690Y804988D01*
X957942D01*
X954255Y808675D01*
X928339D01*
X924484Y812530D01*
Y812558D01*
G01X1109593Y819270D02*
X1107084Y816761D01*
X1083641D01*
X1077816Y810936D01*
X1006771D01*
X1003061Y807226D01*
X958568D01*
X954898Y810896D01*
X929820D01*
X925779Y814937D01*
X923312D01*
X921047Y812672D01*
Y811463D01*
G01X931800Y791500D02*
Y790589D01*
X938051Y784338D01*
Y780349D01*
X941000Y777400D01*
X947600D01*
G01X934800Y795300D02*
X935730D01*
X941346Y789684D01*
Y781876D01*
X943262Y779960D01*
X947600D01*
G01Y782520D02*
X975573D01*
X1011037Y747056D01*
Y736868D01*
G01X1015618Y700908D02*
Y745339D01*
X975877Y785080D01*
X947600D01*
G01X1119042Y812183D02*
X1114465Y807606D01*
X1089439D01*
X1089399Y807646D01*
X1084752D01*
X1081967Y804861D01*
X1009292D01*
X1005369Y800938D01*
X956264D01*
X952578Y804624D01*
X925860D01*
X923259Y807225D01*
X919177D01*
X916855Y809547D01*
Y810934D01*
G01X947600Y787640D02*
X976181D01*
X1019284Y744537D01*
Y721708D01*
G01X947600Y790200D02*
X976485D01*
X1023243Y743442D01*
Y732861D01*
G01X1028089Y707561D02*
Y741460D01*
X976789Y792760D01*
X947600D01*
G01X1032654Y697436D02*
Y739759D01*
X977628Y794785D01*
X953825D01*
X953290Y795320D01*
X947600D01*
G01X909144Y803346D02*
X911591Y800899D01*
X913597D01*
G01D02*
X918642D01*
X921661Y797880D01*
X925400D01*
G01Y795320D02*
X920416D01*
X918219Y797517D01*
X907863D01*
X906008Y799372D01*
G01D02*
X903700Y801680D01*
Y803200D01*
G01X917211Y793314D02*
X913313D01*
X912800Y792801D01*
X912762D01*
G01X917211Y793314D02*
X920045D01*
X920599Y792760D01*
X925400D01*
G01X908543Y792632D02*
X910425Y790750D01*
X919606D01*
X920156Y790200D01*
X925400D01*
G01X903221Y793938D02*
X907237D01*
X908543Y792632D01*
G01X912030Y787650D02*
X912574Y788194D01*
X917211D01*
G01X925400Y787640D02*
X920336D01*
X919786Y788190D01*
X917215D01*
X917211Y788194D01*
G01X907800Y788700D02*
X910888Y785612D01*
X914780D01*
X916892Y783500D01*
X917600D01*
G01X925400Y785080D02*
X920382D01*
X918802Y783500D01*
X917600D01*
G01X913059Y810367D02*
X916192Y813500D01*
X917900D01*
X919000Y812400D01*
Y810463D01*
X920136Y809327D01*
X924527D01*
X927205Y806649D01*
X953417D01*
X957103Y802963D01*
X1004530D01*
X1008453Y806886D01*
X1081128D01*
X1083923Y809681D01*
X1111028D01*
X1113530Y812183D01*
G01X906166Y812784D02*
Y810334D01*
X910609Y805891D01*
X914482D01*
X917446Y802927D01*
X921311D01*
X923664Y800574D01*
X950900D01*
X954586Y796888D01*
X1007047D01*
X1010970Y800811D01*
X1085403D01*
X1085700Y800514D01*
X1110523D01*
X1115105Y805096D01*
G01X1109593D02*
X1107086Y802589D01*
X1087000D01*
X1086753Y802836D01*
X1010131D01*
X1006208Y798913D01*
X955425D01*
X951739Y802599D01*
X924886D01*
X922424Y805061D01*
X918250D01*
X915344Y807967D01*
X911994D01*
X909971Y809990D01*
Y813437D01*
X908208Y815200D01*
X904447D01*
X902560Y813313D01*
G01X876862Y842155D02*
X883553D01*
X896283Y829425D01*
G01X881702Y838859D02*
X882410D01*
X886342Y834927D01*
G01X879667Y877303D02*
X880979D01*
X882814Y875468D01*
Y870047D01*
X883108Y869753D01*
Y865269D01*
X882814Y864975D01*
Y849421D01*
X892612Y839623D01*
X904917D01*
X920461Y824079D01*
G01X870550Y765500D02*
X872893D01*
X874593Y763800D01*
G01X920461Y824079D02*
X930913Y813627D01*
X955951D01*
X959677Y809901D01*
X1001952D01*
X1005662Y813611D01*
X1042929D01*
X1047507Y818189D01*
X1056190D01*
X1057750Y816629D01*
Y814500D01*
G01X884684Y877406D02*
X885489Y876601D01*
Y871156D01*
X885783Y870862D01*
Y864160D01*
X885489Y863866D01*
Y850530D01*
X893721Y842298D01*
X906226D01*
X917052Y831472D01*
G01X870550Y770000D02*
X872511D01*
X874821Y767690D01*
G01X917052Y831472D02*
X932222Y816302D01*
X957061D01*
X960787Y812576D01*
X1000843D01*
X1004553Y816286D01*
X1041596D01*
X1046174Y820864D01*
X1056617D01*
X1057750Y821997D01*
Y824250D01*
G01X953742Y818977D02*
X933903D01*
X931380Y821500D01*
G01X1057750Y828400D02*
Y830411D01*
X1056423Y831738D01*
X1051446D01*
X1038669Y818961D01*
X1003444D01*
X999734Y815251D01*
X961896D01*
X958170Y818977D01*
X953742D01*
G01X935485Y821400D02*
X936049Y821964D01*
X941564D01*
G01X1057750Y837800D02*
Y836062D01*
X1056101Y834413D01*
X1050337D01*
X1037560Y821636D01*
X1002335D01*
X998625Y817926D01*
X963005D01*
X958967Y821964D01*
X941564D01*
G01X920170Y857430D02*
Y849500D01*
G01X935000Y845750D02*
X934994Y845756D01*
X931206D01*
G01X1029592Y825127D02*
X1028776Y824311D01*
X1001226D01*
X997516Y820601D01*
X964722D01*
X954323Y831000D01*
X930706D01*
X920170Y841536D01*
Y849500D01*
G01X908750Y774000D02*
X903832D01*
X903572Y773740D01*
G01X903500Y769900D02*
X903700Y770100D01*
X912017D01*
X914146Y767971D01*
Y767854D01*
X916050Y765950D01*
Y764800D01*
G01X939500Y845750D02*
Y842400D01*
G01X925073Y840417D02*
X923000Y842490D01*
Y855760D01*
X924670Y857430D01*
G01X1029771Y830913D02*
X1025844Y826986D01*
X1000117D01*
X996407Y823276D01*
X965831D01*
X955432Y833675D01*
X931815D01*
X925073Y840417D01*
G01X868500Y799550D02*
X869350Y798700D01*
X872600D01*
G01X937875Y869750D02*
Y860922D01*
X928267Y851314D01*
Y843733D01*
X933167Y838833D01*
X943294D01*
G01X909940Y871500D02*
Y880364D01*
G01Y871500D02*
Y865260D01*
X911080Y864120D01*
G01D02*
X915580D01*
G01X918380Y911780D02*
Y915664D01*
G01X915060Y902564D02*
Y908460D01*
X918380Y911780D01*
G01Y915664D02*
X922716D01*
X922760Y915620D01*
G01X912500Y902564D02*
Y911000D01*
X913000Y911500D01*
G01D02*
X914260Y912760D01*
Y915620D01*
G01D02*
X909760D01*
G01X927260D02*
Y915245D01*
X923645Y911630D01*
G01X917620Y902564D02*
Y905605D01*
X923645Y911630D01*
G01X920170Y864090D02*
Y865830D01*
X915250Y870750D01*
G01X912500Y880364D02*
Y873500D01*
X915250Y870750D01*
G01X924670Y864090D02*
Y866254D01*
X920712Y870212D01*
G01X915060Y880364D02*
Y875864D01*
X920712Y870212D01*
G01X867700Y873500D02*
X870000D01*
X870500Y874000D01*
X872250D01*
G01D02*
Y869500D01*
G01Y878500D02*
X869875D01*
X869575Y878200D01*
X867700D01*
G01X872250Y883000D02*
X867350D01*
G01X894580Y880364D02*
Y884553D01*
X900101Y890074D01*
X922102D01*
X927908Y895880D01*
Y901006D01*
X949477Y922575D01*
X977222D01*
X1063591Y1008944D01*
G01X897140Y880364D02*
Y884249D01*
X900940Y888049D01*
X922941D01*
X929933Y895041D01*
Y900167D01*
X950316Y920550D01*
X978366D01*
X1056428Y998612D01*
G01X894317Y865406D02*
Y870280D01*
X895346Y871309D01*
G01X899700Y880364D02*
Y875663D01*
X895346Y871309D01*
G01X900346D02*
Y867762D01*
X895918Y863334D01*
X892189D01*
X890117Y865406D01*
G01X902260Y880364D02*
Y874860D01*
X900346Y872946D01*
Y871309D01*
G01X894317Y861206D02*
X894338Y861227D01*
X899649D01*
X902749Y864327D01*
G01X904820Y880364D02*
Y866398D01*
X902749Y864327D01*
G01X898596Y858067D02*
X893256D01*
X890117Y861206D01*
G01X907380Y880364D02*
Y864474D01*
X900973Y858067D01*
X898596D01*
G01X894580Y902564D02*
Y899020D01*
X895426Y898174D01*
X918746D01*
X919808Y899236D01*
Y904362D01*
X946346Y930900D01*
X972914D01*
X1059569Y1017555D01*
G01X892020Y902564D02*
Y897580D01*
X893451Y896149D01*
X919585D01*
X921833Y898397D01*
Y903523D01*
X947185Y928875D01*
X973753D01*
X1060195Y1015317D01*
X1060496D01*
X1061807Y1016628D01*
Y1016929D01*
X1082335Y1037457D01*
X1093332D01*
G01X889460Y880364D02*
Y886420D01*
X897164Y894124D01*
X920424D01*
X923858Y897558D01*
Y902684D01*
X947874Y926700D01*
X974442D01*
X1061034Y1013292D01*
X1061335D01*
X1063832Y1015789D01*
Y1016090D01*
X1082601Y1034859D01*
X1124848D01*
G01X892020Y880364D02*
Y885450D01*
X898669Y892099D01*
X921263D01*
X925883Y896719D01*
Y901845D01*
X948638Y924600D01*
X975206D01*
X1061873Y1011267D01*
X1062174D01*
X1065857Y1014950D01*
Y1015251D01*
X1083214Y1032608D01*
X1160314D01*
G01X875750Y878500D02*
X878470D01*
X879667Y877303D01*
G01X875750Y883000D02*
X878444D01*
X878498Y882946D01*
X879144D01*
X884684Y877406D01*
G01X920170Y860590D02*
Y857430D01*
G01X924670Y860590D02*
Y857430D01*
G01X948870Y883230D02*
Y887101D01*
X954208Y892439D01*
Y894134D01*
G01D02*
Y896066D01*
X954750Y896608D01*
Y898500D01*
G01X940499Y905125D02*
X934709Y899335D01*
Y888791D01*
X937875Y885625D01*
Y869750D01*
G01X947250Y911875D02*
X947249D01*
X940499Y905125D01*
G01X1022080Y960728D02*
Y960709D01*
X973246Y911875D01*
X947250D01*
G01X957000Y1215500D02*
Y1218700D01*
X954200Y1221500D01*
X952500D01*
X951500Y1222500D01*
G01D02*
Y1226250D01*
G01D02*
X947500D01*
G01X959500D02*
X955500D01*
G01X955425Y1215500D02*
Y1217575D01*
X954000Y1219000D01*
X945500D01*
X943500Y1221000D01*
G01D02*
Y1226250D01*
G01X1036100Y410500D02*
X1042200Y416600D01*
X1053300D01*
X1069800Y433100D01*
X1091506D01*
X1118694Y460288D01*
X1136100D01*
G01X1147440Y473040D02*
Y468340D01*
X1142300Y463200D01*
X1118742D01*
X1092342Y436800D01*
X1069000D01*
X1052600Y420400D01*
X1045300D01*
G01X1033200Y423228D02*
X1050828D01*
X1067200Y439600D01*
X1092278D01*
X1117903Y465225D01*
X1140425D01*
X1143720Y468520D01*
G01X1017500Y426131D02*
X1050131D01*
X1066500Y442500D01*
X1092314D01*
X1118426Y468612D01*
X1130494D01*
X1132300Y470418D01*
X1136928D01*
X1139330Y472820D01*
G01X1092000Y448400D02*
X1089200Y445600D01*
X1061000D01*
X1047900Y432500D01*
G01X1088000Y448500D02*
X1054400D01*
X1041600Y435700D01*
G01X1016557Y437230D02*
X1023570D01*
X1042140Y455800D01*
X1095100D01*
G01X976213Y522177D02*
X980600D01*
X980727Y522050D01*
X983300D01*
G01X987333Y523018D02*
X990538D01*
X991538Y522018D01*
G01X983300Y522050D02*
X984064D01*
X985032Y523018D01*
X987333D01*
G01X995633Y547651D02*
X1000044D01*
X1000051Y547644D01*
G01X991129Y547651D02*
X995633D01*
G01X991129D02*
X986299D01*
X986200Y547750D01*
G01X978571Y548291D02*
X982760D01*
X983301Y547750D01*
X986200D01*
G01X1004460Y533819D02*
X1004279Y534000D01*
X993300D01*
X991360Y532060D01*
Y529780D01*
G01X1004460Y533819D02*
X1006438Y531841D01*
Y529062D01*
X1052000Y483500D01*
X1113003D01*
X1119242Y477261D01*
G01X976213Y524737D02*
X980037D01*
X981818Y526518D01*
X987333D01*
G01X991360Y529780D02*
X991713Y529427D01*
Y526457D01*
G01X987333Y526518D02*
X991652D01*
X991713Y526457D01*
G01X976213Y519617D02*
Y513787D01*
X977700Y512300D01*
X981500D01*
G01X991688Y517437D02*
Y514288D01*
X989700Y512300D01*
X981500D01*
G01X1015143Y577288D02*
X979149D01*
X967760Y565899D01*
Y552556D01*
X966055Y550851D01*
X962271D01*
G01X1119042Y555490D02*
X1116162Y558370D01*
X1048776D01*
X1029858Y577288D01*
X1015143D01*
G01X1003166Y574208D02*
X979853D01*
X970436Y564791D01*
Y552184D01*
X971769Y550851D01*
X978571D01*
G01X1113530Y555490D02*
X1110340Y552300D01*
X1089710D01*
X1086315Y555695D01*
X1046854D01*
X1028341Y574208D01*
X1003166D01*
G01X991129Y551151D02*
X995161D01*
X996091Y552081D01*
G01X978571Y550851D02*
X982651D01*
X982951Y551151D01*
X991129D01*
G01X978571Y545731D02*
Y541129D01*
X980700Y539000D01*
X984200D01*
G01X989498Y539555D02*
X988943Y539000D01*
X984200D01*
G01X1011037Y736868D02*
Y687654D01*
X1035574Y663117D01*
X1132453D01*
X1136346Y659224D01*
X1227424D01*
X1232490Y664290D01*
G01X1015618Y700908D02*
Y687509D01*
X1037985Y665142D01*
X1133294D01*
X1137187Y661249D01*
X1224496D01*
X1229575Y666328D01*
X1234652D01*
X1236690Y664290D01*
G01X1019284Y721708D02*
Y688343D01*
X1040460Y667167D01*
X1134133D01*
X1138026Y663274D01*
X1223352D01*
X1228568Y668490D01*
X1232490D01*
G01X1023243Y732861D02*
Y690058D01*
X1044109Y669192D01*
X1134972D01*
X1138865Y665299D01*
X1222513D01*
X1227742Y670528D01*
X1234652D01*
X1236690Y668490D01*
G01X1028089Y707561D02*
Y689901D01*
X1046773Y671217D01*
X1135811D01*
X1139704Y667324D01*
X1221674D01*
X1227040Y672690D01*
X1232490D01*
G01X1236690D02*
X1234652Y674728D01*
X1225099D01*
X1219720Y669349D01*
X1140543D01*
X1136650Y673242D01*
X1049818D01*
X1032654Y690406D01*
Y697436D01*
G01X960370Y770010D02*
Y765510D01*
G01Y779010D02*
Y774510D01*
G01X966093Y849250D02*
X962000D01*
G01X979120Y845050D02*
Y839091D01*
X979107Y839078D01*
G01X977570Y835178D02*
Y837541D01*
X979107Y839078D01*
G01X974120Y845050D02*
Y839208D01*
X974163Y839165D01*
G01X973070Y835178D02*
Y838072D01*
X974163Y839165D01*
G01X984120Y845050D02*
Y838620D01*
X983000Y837500D01*
G01X983070Y833240D02*
X983000Y833310D01*
Y837500D01*
G01X961670Y861030D02*
Y853930D01*
X963200Y852400D01*
X967666D01*
X970840Y855574D01*
Y868660D01*
X968665Y870835D01*
Y889549D01*
X976896Y897780D01*
X976897D01*
X980637Y901520D01*
Y901521D01*
X983311Y904195D01*
G01X1119042Y840529D02*
X1114458Y835945D01*
X1077856D01*
X1066314Y847487D01*
X1049720D01*
X1032447Y830214D01*
Y829805D01*
X1029592Y826950D01*
Y825127D01*
G01X1113530Y840529D02*
X1111032Y838031D01*
X1092008D01*
X1091419Y838620D01*
X1079881D01*
X1068339Y850162D01*
X1048611D01*
X1029772Y831323D01*
Y830914D01*
X1029771Y830913D01*
G01X1005450Y845510D02*
Y849166D01*
G01X1008060Y856130D02*
Y853847D01*
X1007038Y852825D01*
Y852783D01*
X1006108Y851853D01*
Y849824D01*
X1005450Y849166D01*
G01X1005500Y856130D02*
Y853000D01*
X1004500Y852000D01*
X1002000D01*
X999500Y849500D01*
G01X1000950Y845510D02*
X999500Y846960D01*
Y849500D01*
G01X1034131Y855984D02*
X1033065Y857050D01*
X1029600D01*
G01X1018300Y856130D02*
Y860925D01*
X1018975Y861600D01*
X1020200D01*
X1020860Y860940D01*
Y856130D01*
G01D02*
X1022914D01*
X1024550Y857766D01*
Y860050D01*
X1026500Y862000D01*
X1028500D01*
G01X1034134Y851705D02*
Y848192D01*
X1033807Y847865D01*
G01X1029912Y849214D02*
X1031261Y847865D01*
X1033807D01*
G01X1015740Y856130D02*
Y852288D01*
X1020061Y847967D01*
G01D02*
X1020250Y847778D01*
Y842500D01*
G01X1005450Y842010D02*
Y837269D01*
X1005272Y837091D01*
G01X977570Y831678D02*
Y828619D01*
X977676Y828513D01*
G01X1115105Y847616D02*
X1115058D01*
X1111851Y850823D01*
X1077396D01*
X1072707Y855512D01*
X1046393D01*
X1028623Y837742D01*
X1019281D01*
X1017501Y835962D01*
X1006401D01*
X1005272Y837091D01*
G01X1109593Y847616D02*
X1106277Y844300D01*
X1079851D01*
X1071314Y852837D01*
X1047502D01*
X1029732Y835067D01*
X1020625D01*
X1018845Y833287D01*
X1004612D01*
X1000827Y837072D01*
G01X1000950Y842010D02*
Y837195D01*
X1000827Y837072D01*
G01X973070Y831678D02*
Y828512D01*
G01X989120Y865050D02*
Y869000D01*
X989933Y869813D01*
Y872000D01*
G01D02*
Y874109D01*
X989742Y874300D01*
Y876050D01*
G01D02*
X993942D01*
G01X984120Y865050D02*
Y869780D01*
X982500Y871400D01*
G01D02*
X980400Y873500D01*
Y876008D01*
X980442Y876050D01*
G01D02*
X985542D01*
G01X979120Y865050D02*
Y869500D01*
X977210Y871410D01*
X974219D01*
X971982Y873647D01*
G01D02*
X972042Y873707D01*
Y877750D01*
G01D02*
X976242D01*
G01X1206414Y704261D02*
X1218574Y716421D01*
Y801171D01*
X1195867Y823878D01*
Y852854D01*
X1219629Y876616D01*
Y995807D01*
X1202271Y1013165D01*
X1087014D01*
X985678Y911829D01*
Y906562D01*
X983311Y904195D01*
G01X1209931Y701608D02*
X1221654Y713331D01*
Y800955D01*
X1197892Y824717D01*
Y852015D01*
X1221654Y875777D01*
Y996646D01*
X1203110Y1015190D01*
X1086003D01*
X980484Y909671D01*
Y904534D01*
X978033Y902083D01*
G01D02*
X964230Y888280D01*
Y883230D01*
G01X1207468Y697962D02*
X1209803D01*
X1223679Y711838D01*
Y801794D01*
X1199917Y825556D01*
Y851176D01*
X1223679Y874938D01*
Y997485D01*
X1203949Y1017215D01*
X1084314D01*
X975288Y908189D01*
Y902954D01*
X972854Y900520D01*
G01X961670Y883230D02*
Y889335D01*
X963908Y891573D01*
Y891574D01*
X972854Y900520D01*
G01X959110Y883230D02*
Y890440D01*
X964170Y895500D01*
G01X1210283Y695565D02*
X1226837Y712119D01*
Y801500D01*
X1201942Y826395D01*
Y850337D01*
X1226837Y875232D01*
Y997191D01*
X1205974Y1018054D01*
Y1018055D01*
X1204789Y1019240D01*
X1083475D01*
X970834Y906599D01*
Y902164D01*
X964170Y895500D01*
G01X1039500Y883250D02*
Y878500D01*
G01D02*
Y874700D01*
G01X1029600Y857050D02*
Y860900D01*
X1028500Y862000D01*
G01X1104600Y967800D02*
X1104200Y967400D01*
X1083468D01*
X1050500Y934432D01*
Y892750D01*
X1048000Y890250D01*
G01D02*
X1050500Y887750D01*
Y886000D01*
X1078600Y857900D01*
X1111216D01*
X1115105Y861789D01*
G01X1109593D02*
X1106382Y865000D01*
X1075284D01*
X1053500Y886784D01*
Y888250D01*
X1055500Y890250D01*
G01D02*
X1053175Y892575D01*
Y933323D01*
X1083852Y964000D01*
X1100850D01*
X1101950Y962900D01*
G01X1030862Y951946D02*
Y911599D01*
X1026566Y907303D01*
X1009719D01*
X1009666Y907250D01*
X1005500D01*
G01Y910750D02*
X1016000D01*
G01X1000500D02*
Y915000D01*
X1001500Y916000D01*
X1003000D01*
G01X1005500Y910750D02*
Y915000D01*
X1004500Y916000D01*
X1003000D01*
G01X1019875Y918250D02*
X1024250D01*
X1025500Y919500D01*
G01X1024507Y929750D02*
Y935517D01*
X1024024Y936000D01*
Y939306D01*
G01X1024507Y929750D02*
Y924493D01*
X1025500Y923500D01*
Y919500D01*
G01X1068569Y1191530D02*
X1015445D01*
X1014977Y1191062D01*
X1007776D01*
X996514Y1179800D01*
X987300D01*
G01X982172Y1176631D02*
X996272D01*
X1008658Y1189017D01*
X1070466D01*
X1072931Y1191482D01*
G01X958575Y1215500D02*
Y1220075D01*
X959500Y1221000D01*
G01D02*
Y1226250D01*
G01X970500Y1205000D02*
X975750D01*
G01X965000Y1205925D02*
X967975D01*
X968524Y1205376D01*
X969908D01*
X970284Y1205000D01*
X970500D01*
G01X972000Y1223400D02*
Y1221600D01*
X968000Y1217600D01*
Y1211650D01*
X967000Y1210650D01*
X965000D01*
G01X975750Y1225000D02*
X973600D01*
X972000Y1223400D01*
G01X965000Y1204350D02*
X967150D01*
X970500Y1201000D01*
X972000D01*
G01D02*
X975750D01*
G01X965000Y1202776D02*
Y1201500D01*
X969500Y1197000D01*
X970500D01*
G01D02*
X975750D01*
G01X961724Y1215500D02*
X963000D01*
X967500Y1220000D01*
Y1221000D01*
G01D02*
Y1226250D01*
G01X972000Y1209000D02*
X975750D01*
G01X965000Y1207500D02*
X968936D01*
X969062Y1207626D01*
X970026D01*
X971400Y1209000D01*
X972000D01*
G01X975750Y1213000D02*
Y1209000D01*
G01Y1217000D02*
Y1221000D01*
G01X970500Y1213000D02*
Y1215700D01*
X971800Y1217000D01*
X975750D01*
G01X965000Y1209075D02*
X968175D01*
X970500Y1211400D01*
Y1213000D01*
G01X960150Y1215500D02*
Y1217650D01*
X963500Y1221000D01*
Y1222500D01*
G01D02*
Y1226250D01*
G01X979250Y1201000D02*
X982500D01*
G01X979250Y1197000D02*
X982500D01*
G01X1049260Y1466691D02*
X1046960Y1464391D01*
X1040663D01*
G01D02*
X1031163D01*
G01X1007493Y1448289D02*
X1008333D01*
X1012443Y1452399D01*
X1015443D01*
G01X1023693Y1455899D02*
X1020193Y1452399D01*
X1015443D01*
G01X1016943Y1446320D02*
X1007193D01*
G01X1023693Y1451399D02*
X1023227D01*
X1018148Y1446320D01*
X1016943D01*
G01X1027443Y1444649D02*
Y1447399D01*
X1028443Y1448399D01*
X1038303D01*
G01X1048553D02*
X1043606D01*
G01X1038303D02*
X1043606D01*
G01X1035526Y1455899D02*
X1027193D01*
G01Y1451399D02*
X1037075D01*
X1041176Y1455500D01*
G01X1113530Y527143D02*
X1116973Y523700D01*
X1143100D01*
X1153700Y513100D01*
Y480800D01*
X1149900Y477000D01*
Y465000D01*
X1139400Y454500D01*
X1115770D01*
X1092345Y431075D01*
X1076323D01*
X1067872Y422624D01*
G01X1109593Y534230D02*
X1112269Y531554D01*
X1144646D01*
X1158148Y518052D01*
Y468748D01*
X1140900Y451500D01*
X1116554D01*
X1093454Y428400D01*
X1083676D01*
X1074400Y419124D01*
G01X1115105Y534230D02*
X1118545Y537670D01*
X1184630D01*
X1188800Y533500D01*
Y507600D01*
G01X1364600Y189600D02*
Y223200D01*
X1330950Y256850D01*
Y348404D01*
X1294740Y384614D01*
Y402900D01*
X1211879Y485761D01*
Y591677D01*
X1184809Y618747D01*
X1134600D01*
G01X1453052Y199552D02*
X1439819Y212785D01*
X1378659D01*
X1332975Y258469D01*
Y349243D01*
X1296765Y385453D01*
Y403739D01*
X1214794Y485710D01*
Y592311D01*
X1185442Y621663D01*
X1131963D01*
X1129500Y619200D01*
G01X1115825Y621993D02*
X1120959D01*
G01D02*
X1125025D01*
G01X1115105Y776750D02*
X1113451Y778404D01*
X1113066D01*
X1111670Y779800D01*
X1082800D01*
X1056104Y753104D01*
Y697112D01*
X1056116Y697100D01*
G01X1109593Y776750D02*
X1107087Y774244D01*
X1080602D01*
X1058960Y752602D01*
Y691560D01*
X1057806Y690406D01*
Y680253D01*
X1057826Y680233D01*
G01X1119042Y769663D02*
X1116536Y772169D01*
X1081391D01*
X1060985Y751763D01*
Y689387D01*
X1059927Y688329D01*
G01X1113530Y769663D02*
X1111021Y767154D01*
X1079409D01*
X1064220Y751965D01*
Y683755D01*
X1064216Y683751D01*
G01X1115105Y762577D02*
X1112603Y765079D01*
X1080579D01*
X1067554Y752054D01*
Y694447D01*
G01X1109593Y762577D02*
X1106416Y759400D01*
X1078600D01*
X1071179Y751979D01*
Y682315D01*
G01X1107674Y677776D02*
X1133989D01*
X1140298Y684085D01*
X1231285D01*
X1232490Y685290D01*
G01X1103770Y675413D02*
X1135211D01*
X1140888Y681090D01*
X1214657D01*
G01X1119042Y783836D02*
X1122068Y780810D01*
X1186580D01*
X1190995Y776395D01*
G01X1113530Y783836D02*
X1116032Y786338D01*
X1181588D01*
X1186690Y791440D01*
G01X1119042Y798010D02*
X1121550Y795502D01*
X1171698D01*
X1171715Y795485D01*
X1173990Y797760D01*
G01X1113530Y798010D02*
X1117360Y801840D01*
X1174180D01*
X1177300Y804960D01*
G01X1115105Y790923D02*
X1117615Y788413D01*
X1178053D01*
X1180520Y790880D01*
G01X1109593Y790923D02*
X1112097Y793427D01*
X1175097D01*
X1179690Y798020D01*
G01X1057750Y814500D02*
X1074200D01*
X1080212Y820512D01*
X1088350D01*
X1089581Y821743D01*
X1091419D01*
X1091459Y821783D01*
X1114469D01*
X1119042Y826356D01*
G01X1057750Y824250D02*
X1057918Y824418D01*
X1092733D01*
X1093293Y823858D01*
X1111032D01*
X1113530Y826356D01*
G01X1115105Y833443D02*
X1110523Y828861D01*
X1092005D01*
X1091419Y828275D01*
X1057875D01*
X1057750Y828400D01*
G01X1109593Y833443D02*
X1107086Y830936D01*
X1091433D01*
X1091419Y830950D01*
X1069234D01*
X1062384Y837800D01*
X1057750D01*
G01X1113530Y925569D02*
X1118109Y930148D01*
X1140150D01*
X1141639Y928659D01*
X1199131D01*
X1205372Y922418D01*
Y870387D01*
X1190191Y855206D01*
Y821525D01*
X1212703Y799013D01*
Y758435D01*
G01X1119042Y925569D02*
X1121546Y928073D01*
X1138431D01*
X1140935Y925569D01*
X1199357D01*
X1203347Y921579D01*
Y871226D01*
X1188166Y856045D01*
Y820686D01*
X1206937Y801915D01*
Y755002D01*
G01X1115105Y918482D02*
X1117611Y920988D01*
X1178312D01*
X1182564Y916736D01*
X1185244D01*
X1189224Y912756D01*
G01X1109593Y918482D02*
X1114174Y923063D01*
X1181037D01*
X1184408Y919692D01*
X1187667D01*
X1188509Y918850D01*
G01X1184750Y899500D02*
X1157995D01*
X1143595Y913900D01*
X1121546D01*
X1119042Y911396D01*
G01X1184750Y906100D02*
Y906782D01*
X1183049Y908483D01*
X1153117D01*
X1145621Y915979D01*
X1118113D01*
X1113530Y911396D01*
G01X1184750Y886000D02*
X1158038D01*
X1137220Y906818D01*
X1117614D01*
X1115105Y904309D01*
G01X1184750Y892600D02*
X1158500D01*
X1142207Y908893D01*
X1114177D01*
X1109593Y904309D01*
G01X1063591Y1008944D02*
X1083937Y1029290D01*
X1200467D01*
X1231205Y998552D01*
Y935658D01*
X1268321Y898542D01*
X1746778D01*
X1771561Y923325D01*
X1803425D01*
X1820700Y940600D01*
G01X1056428Y998612D02*
X1085081Y1027265D01*
X1199628D01*
X1229180Y997713D01*
Y934819D01*
X1267802Y896197D01*
X1747297D01*
X1772400Y921300D01*
X1808800D01*
X1827700Y940200D01*
X1848500D01*
G01X1325500Y907000D02*
X1272196D01*
X1239489Y939707D01*
Y1001724D01*
X1201518Y1039695D01*
X1081709D01*
X1059569Y1017555D01*
G01X1443992Y904962D02*
X1271370D01*
X1237464Y938868D01*
Y1000885D01*
X1200892Y1037457D01*
X1093332D01*
G01X1572900Y902900D02*
X1270568D01*
X1235256Y938212D01*
Y1000229D01*
X1200626Y1034859D01*
X1124848D01*
G01X1124612Y1380773D02*
Y1379352D01*
X1124586Y1379326D01*
Y1377650D01*
X1125337Y1376899D01*
Y1375548D01*
X1126112Y1374773D01*
X1130112D01*
G01X1134112Y1370023D02*
X1130112D01*
G01D02*
Y1374773D01*
G01X1123037Y1380773D02*
Y1374473D01*
G01D02*
Y1374073D01*
X1122112Y1373148D01*
Y1370023D01*
G01D02*
X1126112D01*
G01X1105862Y1391273D02*
X1111012D01*
G01X1116612Y1390348D02*
X1113937D01*
X1113012Y1391273D01*
X1111012D01*
G01X1109612Y1371600D02*
X1111300Y1373288D01*
Y1376500D01*
X1113612Y1378812D01*
Y1384623D01*
X1114612Y1385623D01*
X1116612D01*
G01X1105850Y1371200D02*
X1109212D01*
X1109612Y1371600D01*
G01Y1395273D02*
X1105862D01*
G01X1116612Y1391923D02*
X1114751D01*
X1113457Y1393217D01*
Y1394028D01*
X1112212Y1395273D01*
X1109612D01*
G01X1116612Y1393497D02*
Y1394773D01*
X1112112Y1399273D01*
X1111112D01*
G01D02*
X1105862D01*
G01X1119888Y1380773D02*
X1118612D01*
X1114112Y1376273D01*
Y1374773D01*
G01D02*
Y1370023D01*
G01X1105862Y1387273D02*
X1109612D01*
G01X1116612Y1388773D02*
X1111612D01*
X1110112Y1387273D01*
X1109612D01*
G01X1105862Y1383273D02*
Y1387273D01*
G01X1116612Y1387198D02*
X1113323D01*
X1111112Y1384987D01*
Y1383273D01*
G01X1105862Y1379273D02*
X1107112D01*
X1111112Y1383273D01*
G01X1105850Y1375200D02*
Y1379261D01*
X1105862Y1379273D01*
G01X1121462Y1380773D02*
Y1378823D01*
X1118301Y1375662D01*
Y1374458D01*
G01X1118112Y1370023D02*
Y1372173D01*
X1118301Y1372362D01*
Y1374458D01*
G01X1138112Y1370023D02*
Y1375273D01*
G01X1126187Y1380773D02*
Y1378913D01*
X1127727Y1377373D01*
X1136012D01*
X1138112Y1375273D01*
G01X1102362Y1395273D02*
X1092773D01*
X1091000Y1393500D01*
G01X1102362Y1399273D02*
X1089500D01*
X1086646Y1396419D01*
G01X1188800Y507600D02*
Y496400D01*
X1160900Y468500D01*
G01X1250648Y425686D02*
X1234254Y442080D01*
G01X1245959Y435527D02*
X1245899D01*
X1218485Y462941D01*
Y462942D01*
X1216078Y465349D01*
G01X1265295Y421223D02*
X1232660Y453858D01*
G01X1252800Y585100D02*
Y588509D01*
X1216040Y625269D01*
G01X1212587Y749295D02*
X1212703Y749411D01*
Y758435D01*
G01X1212587Y745095D02*
X1206937Y750745D01*
Y755002D01*
G01X1214657Y681090D02*
X1232490D01*
G01X1217111Y829350D02*
Y825000D01*
G01Y842032D02*
Y836182D01*
G01D02*
Y829350D01*
G01X1231844Y855959D02*
Y849250D01*
G01X1709500Y900700D02*
X1269904D01*
X1233230Y937374D01*
Y999391D01*
X1200013Y1032608D01*
X1160314D01*
G01X1193474Y912331D02*
X1189649D01*
X1189224Y912756D01*
G01X1193544Y918091D02*
X1189268D01*
X1188509Y918850D01*
G01X1180090Y896524D02*
X1181774D01*
X1184750Y899500D01*
G01X1181550Y906100D02*
X1184750D01*
G01Y889200D02*
Y886000D01*
G01Y896300D02*
Y892600D01*
G01X1252800Y1037700D02*
X1237502Y1052998D01*
X1223634D01*
G01X1202394Y1335151D02*
Y1326833D01*
G01X1235600D02*
Y1335151D01*
G01X1197394D02*
Y1326833D01*
G01X1230600D02*
Y1335151D01*
G01X1208394Y1340033D02*
X1203394D01*
G01D02*
X1202394Y1339033D01*
Y1335151D01*
G01X1235600D02*
Y1339033D01*
X1236600Y1340033D01*
G01D02*
X1241600D01*
G01X1193894D02*
X1198894D01*
G01D02*
Y1338489D01*
X1197394Y1336989D01*
Y1335151D01*
G01X1230600D02*
Y1336989D01*
X1232100Y1338489D01*
Y1340033D01*
G01D02*
X1227100D01*
G01X1307200Y50500D02*
X1313650D01*
X1313700Y50550D01*
G01X1334250Y104300D02*
Y88011D01*
X1317900Y71661D01*
Y68900D01*
G01D02*
X1315309D01*
X1315059Y69150D01*
X1311700D01*
G01X1299800Y47940D02*
X1302640D01*
X1303500Y48800D01*
Y54000D01*
X1306950Y57450D01*
Y59950D01*
G01X1305050Y63900D02*
Y61850D01*
X1306950Y59950D01*
G01X1299500Y102000D02*
Y92600D01*
X1295000Y88100D01*
Y74600D01*
X1297200Y72400D01*
X1302200D01*
X1305050Y69550D01*
Y68900D01*
G01D02*
Y63900D01*
G01X1313700Y54050D02*
X1317800D01*
G01X1307200Y53060D02*
Y54400D01*
X1311100Y58300D01*
X1312100D01*
G01X1313700Y54050D02*
Y56700D01*
X1312100Y58300D01*
G01X1311700Y65650D02*
X1314750D01*
X1317900Y62500D01*
Y59900D01*
G01D02*
Y54150D01*
X1317800Y54050D01*
G01X1303500Y41750D02*
X1297850D01*
X1296700Y42900D01*
Y48900D01*
X1298300Y50500D01*
X1299800D01*
G01X1318000Y41750D02*
X1313000D01*
G01D02*
X1308000D01*
G01D02*
X1303500D01*
G01X1318000Y38250D02*
X1322450Y33800D01*
X1352900D01*
X1364600Y45500D01*
Y189600D01*
G01X1256756Y156319D02*
X1288878D01*
G01X1262600Y126350D02*
X1257533D01*
G01X1266600D02*
X1262600D01*
G01X1253000Y126400D02*
X1253050Y126350D01*
X1257533D01*
G01X1266600D02*
X1271531D01*
X1271562Y126319D01*
X1288878D01*
G01X1334250Y109500D02*
Y104300D01*
G01Y109500D02*
Y113500D01*
G01X1333000Y120000D02*
Y116750D01*
X1334250Y115500D01*
Y113500D01*
G01X1253000Y132400D02*
X1256800D01*
G01X1262945Y377600D02*
Y383269D01*
G01D02*
Y389119D01*
G01X1277678Y403046D02*
Y396337D01*
G01X1338423Y429770D02*
X1356057Y412136D01*
Y403203D01*
G01X1257000Y434600D02*
Y434610D01*
X1248784Y442826D01*
G01X1311200Y517000D02*
X1317000D01*
G01X1322000Y517250D02*
X1321750Y517000D01*
X1317000D01*
G01X1332500Y527000D02*
X1332750Y527250D01*
Y533500D01*
G01X1336500D02*
X1338000Y535000D01*
Y559750D01*
X1335250Y562500D01*
G01X1333500Y573000D02*
Y571250D01*
X1335250Y569500D01*
Y566500D01*
G01Y562500D02*
Y566500D01*
G01X1332750Y533500D02*
X1336500D01*
G01X1303800Y514440D02*
X1306140D01*
X1306800Y515100D01*
Y525500D01*
G01D02*
Y529950D01*
X1306850Y530000D01*
G01X1308500Y539500D02*
Y537226D01*
X1306850Y535576D01*
Y534000D01*
G01Y530000D02*
Y534000D01*
G01X1329250Y533500D02*
X1324500D01*
G01X1311200Y519560D02*
X1314560D01*
X1315750Y520750D01*
X1322000D01*
G01D02*
X1326500D01*
G01D02*
Y524000D01*
X1323500Y527000D01*
G01D02*
Y532500D01*
X1324500Y533500D01*
G01X1322000Y508250D02*
X1317000D01*
G01D02*
X1312000D01*
G01D02*
X1307500D01*
G01X1303800Y517000D02*
X1300600D01*
X1298700Y515100D01*
Y509800D01*
X1300250Y508250D01*
X1307500D01*
G01X1322000Y504750D02*
X1325500D01*
G01X1256756Y609075D02*
X1288878D01*
G01X1266600Y579050D02*
X1262600D01*
G01D02*
X1257500D01*
G01X1252800Y579100D02*
X1252850Y579050D01*
X1257500D01*
G01X1266600D02*
X1267150D01*
X1267175Y579075D01*
X1288878D01*
G01X1262400Y1031750D02*
X1257100D01*
G01X1266400D02*
X1262400D01*
G01X1252800Y1031700D02*
X1252850Y1031750D01*
X1257100D01*
G01X1266400D02*
X1269619D01*
X1269700Y1031831D01*
X1288878D01*
G01X1311200Y969500D02*
X1317000D01*
G01X1322000Y969750D02*
X1321750Y969500D01*
X1317000D01*
G01X1335250Y1015000D02*
X1338000Y1012250D01*
Y986500D01*
X1337500Y986000D01*
G01D02*
X1332750D01*
G01X1333500Y1025500D02*
Y1023750D01*
X1335250Y1022000D01*
Y1019000D01*
G01D02*
Y1015000D01*
G01X1332500Y979500D02*
X1332750Y979750D01*
Y986000D01*
G01X1307850Y977800D02*
Y982200D01*
G01X1303800Y966940D02*
X1306940D01*
X1307850Y967850D01*
Y977800D01*
G01X1308500Y992000D02*
Y989500D01*
X1307850Y988850D01*
Y986200D01*
G01Y982200D02*
Y986200D01*
G01X1329250Y986000D02*
X1324500D01*
G01X1311200Y972060D02*
X1314560D01*
X1315750Y973250D01*
X1322000D01*
G01D02*
X1326500D01*
G01D02*
Y976500D01*
X1323500Y979500D01*
G01D02*
Y985000D01*
X1324500Y986000D01*
G01X1322000Y960750D02*
X1317000D01*
G01D02*
X1312000D01*
G01D02*
X1307500D01*
G01X1303800Y969500D02*
X1300100D01*
X1298500Y967900D01*
Y962500D01*
X1300250Y960750D01*
X1307500D01*
G01X1322000Y957250D02*
X1325500D01*
G01X1256756Y1061831D02*
X1288878D01*
G01X1288124Y1480000D02*
Y1482250D01*
X1289574Y1483700D01*
G01X1348031Y1466929D02*
X1334960Y1480000D01*
X1288124D01*
G01X1435200Y64000D02*
X1441000D01*
G01X1427800Y61440D02*
X1429440D01*
X1431300Y63300D01*
Y72150D01*
G01X1432250Y77000D02*
X1431300Y76050D01*
Y72150D01*
G01X1432500Y86500D02*
X1432250Y86250D01*
Y81000D01*
G01D02*
Y77000D01*
G01X1435200Y66560D02*
X1436560D01*
X1438200Y68200D01*
X1441200D01*
G01X1431500Y55250D02*
X1436000D01*
G01X1427800Y64000D02*
X1424400D01*
X1422900Y62500D01*
Y57600D01*
X1425250Y55250D01*
X1431500D01*
G01X1380969Y156319D02*
X1413091D01*
G01X1391200Y126350D02*
X1387200D01*
G01X1381756D02*
X1387200D01*
G01X1376700Y126400D02*
X1376750Y126350D01*
X1381756D01*
G01X1391200D02*
X1391231Y126319D01*
X1413091D01*
G01X1376700Y132400D02*
Y136000D01*
G01X1341324Y372244D02*
Y383426D01*
G01D02*
Y389276D01*
G01X1356057Y403203D02*
Y396494D01*
G01X1435200Y517000D02*
X1441000D01*
G01X1427800Y514440D02*
X1430640D01*
X1431350Y515150D01*
Y525000D01*
G01D02*
Y529900D01*
G01X1432500Y539500D02*
Y535050D01*
X1431350Y533900D01*
G01Y529900D02*
Y533900D01*
G01X1435200Y519560D02*
X1438560D01*
X1439750Y520750D01*
X1446000D01*
G01X1436000Y508250D02*
X1431500D01*
G01X1427800Y517000D02*
X1423400D01*
X1421700Y515300D01*
Y510800D01*
X1424250Y508250D01*
X1431500D01*
G01X1377100Y573200D02*
Y516992D01*
X1344024Y483916D01*
G01X1380969Y609075D02*
X1413091D01*
G01X1390400Y579050D02*
X1386400D01*
G01X1377100Y579200D02*
X1381600D01*
G01X1386400Y579050D02*
X1384107D01*
X1383957Y579200D01*
X1381600D01*
G01X1390400Y579050D02*
X1397266D01*
X1397291Y579075D01*
X1413091D01*
G01X1341324Y829350D02*
Y825000D01*
G01Y842032D02*
Y836182D01*
G01D02*
Y829350D01*
G01X1356057Y855959D02*
Y849250D01*
G01X1376900Y1025800D02*
Y982703D01*
X1359197Y965000D01*
Y947767D01*
X1340324Y928894D01*
G01X1391000Y1031850D02*
X1387000D01*
G01X1376900Y1031800D02*
X1381500D01*
G01X1387000Y1031850D02*
X1384337D01*
X1384287Y1031800D01*
X1381500D01*
G01X1391000Y1031850D02*
X1398463D01*
X1398482Y1031831D01*
X1413091D01*
G01X1435200Y969500D02*
X1441000D01*
G01X1427800Y966940D02*
X1430140D01*
X1431600Y968400D01*
Y974800D01*
X1431350Y975050D01*
Y978200D01*
G01D02*
Y982400D01*
G01X1432500Y992000D02*
Y987550D01*
X1431350Y986400D01*
G01Y982400D02*
Y986400D01*
G01X1435200Y972060D02*
X1438560D01*
X1439750Y973250D01*
X1446000D01*
G01X1436000Y960750D02*
X1431500D01*
G01X1427800Y969500D02*
X1424800D01*
X1422300Y967000D01*
Y963300D01*
X1424850Y960750D01*
X1431500D01*
G01X1380969Y1061831D02*
X1413091D01*
G01X1446000Y64250D02*
X1445750Y64000D01*
X1441000D01*
G01X1456500Y74000D02*
X1456750Y74250D01*
Y80500D01*
G01X1460500D02*
X1462000Y82000D01*
Y106750D01*
X1459250Y109500D01*
G01X1456750Y80500D02*
X1460500D01*
G01X1446000Y67750D02*
X1443750D01*
X1443300Y68200D01*
X1441200D01*
G01X1450500Y67750D02*
Y71000D01*
X1447500Y74000D01*
G01X1450500Y67750D02*
X1446000D01*
G01X1447500Y74000D02*
Y76800D01*
X1451200Y80500D01*
X1453250D01*
G01X1446000Y55250D02*
X1441000D01*
G01X1436000D02*
X1441000D01*
G01X1446000Y51750D02*
X1449500D01*
X1464025Y66275D01*
Y188579D01*
X1453052Y199552D01*
G01X1505181Y156319D02*
X1537303D01*
G01X1515400Y126350D02*
X1511400D01*
G01X1505968D02*
X1511400D01*
G01X1501300Y126400D02*
X1501350Y126350D01*
X1505968D01*
G01X1515400D02*
X1515431Y126319D01*
X1537303D01*
G01X1457500Y120000D02*
Y118250D01*
X1459250Y116500D01*
Y113500D01*
G01Y109500D02*
Y113500D01*
G01X1501300Y136100D02*
Y132400D01*
G01X1465536Y372244D02*
Y383426D01*
G01D02*
Y389276D01*
G01X1462350Y428169D02*
X1480269Y410250D01*
Y403203D01*
G01D02*
Y396494D01*
G01X1446000Y517250D02*
X1445750Y517000D01*
X1441000D01*
G01X1456500Y527000D02*
X1456750Y527250D01*
Y533500D01*
G01X1460500D02*
X1462000Y535000D01*
Y559750D01*
X1459250Y562500D01*
G01X1457500Y573000D02*
Y571250D01*
X1459250Y569500D01*
Y566500D01*
G01Y562500D02*
Y566500D01*
G01X1456750Y533500D02*
X1460500D01*
G01X1453250D02*
X1448500D01*
G01X1446000Y520750D02*
X1450500D01*
G01D02*
Y524000D01*
X1447500Y527000D01*
G01D02*
Y532500D01*
X1448500Y533500D01*
G01X1446000Y508250D02*
X1441000D01*
G01D02*
X1436000D01*
G01X1446000Y504750D02*
X1449500D01*
G01X1500800Y572800D02*
Y517723D01*
X1465195Y482118D01*
G01X1505181Y609075D02*
X1537303D01*
G01X1500800Y578800D02*
X1505900D01*
G01X1515200Y579050D02*
X1511200D01*
G01D02*
X1509087D01*
X1508837Y578800D01*
X1505900D01*
G01X1515200Y579050D02*
X1520004D01*
X1520029Y579075D01*
X1537303D01*
G01X1465536Y829350D02*
Y825000D01*
G01Y842032D02*
Y836182D01*
G01D02*
Y829350D01*
G01X1480269Y855959D02*
Y849250D01*
G01X1500700Y1025800D02*
Y1007186D01*
X1484414Y990900D01*
Y942563D01*
X1472646Y930795D01*
G01X1515400Y1031850D02*
X1511400D01*
G01D02*
X1505700D01*
G01X1500700Y1031800D02*
X1505650D01*
X1505700Y1031850D01*
G01X1515400D02*
X1515419Y1031831D01*
X1537303D01*
G01X1446000Y969750D02*
X1445750Y969500D01*
X1441000D01*
G01X1459250Y1015000D02*
X1462000Y1012250D01*
Y986500D01*
X1461500Y986000D01*
G01X1456500Y979500D02*
X1456750Y979750D01*
Y986000D01*
G01X1457500Y1025500D02*
Y1023750D01*
X1459250Y1022000D01*
Y1019000D01*
G01D02*
Y1015000D01*
G01X1456750Y986000D02*
X1461500D01*
G01X1453250D02*
X1448500D01*
G01X1446000Y973250D02*
X1450500D01*
G01D02*
Y976500D01*
X1447500Y979500D01*
G01D02*
Y985000D01*
X1448500Y986000D01*
G01X1446000Y960750D02*
X1441000D01*
G01D02*
X1436000D01*
G01X1446000Y957250D02*
X1447850D01*
X1450100Y959500D01*
G01X1505181Y1061831D02*
X1537303D01*
G01X1556700Y50500D02*
X1562500D01*
G01X1567500Y50750D02*
X1567250Y50500D01*
X1562500D01*
G01X1576800Y69000D02*
X1570000D01*
G01X1604650Y129000D02*
X1608400D01*
X1614075Y123325D01*
Y84189D01*
X1598886Y69000D01*
X1576800D01*
G01X1570000D02*
X1569750Y69250D01*
X1563500D01*
G01X1549300Y47940D02*
X1552040D01*
X1553200Y49100D01*
Y55400D01*
X1555450Y57650D01*
Y59500D01*
G01D02*
Y63300D01*
G01X1549000Y102000D02*
Y99900D01*
X1545000Y95900D01*
Y75000D01*
X1546700Y73300D01*
X1551450D01*
X1555450Y69300D01*
G01Y63300D02*
Y69300D01*
G01X1563500Y65750D02*
Y61000D01*
G01X1556700Y53060D02*
X1560060D01*
X1561250Y54250D01*
X1567500D01*
G01D02*
X1572000D01*
G01D02*
Y57000D01*
X1570000Y59000D01*
Y60000D01*
G01D02*
X1564500D01*
X1563500Y61000D01*
G01X1553000Y41750D02*
X1545950D01*
X1545100Y42600D01*
Y49200D01*
X1546400Y50500D01*
X1549300D01*
G01X1567500Y41750D02*
X1562500D01*
G01D02*
X1557500D01*
G01D02*
X1553000D01*
G01X1616100Y203786D02*
Y83350D01*
X1571000Y38250D01*
X1567500D01*
G01X1625300Y126400D02*
X1630131D01*
X1630181Y126350D01*
G01X1590400Y141000D02*
X1597900D01*
X1604650Y134250D01*
Y133000D01*
G01D02*
Y129000D01*
G01X1625300Y136000D02*
Y132400D01*
G01X1589749Y372244D02*
Y383426D01*
G01D02*
Y389276D01*
G01X1578333Y431523D02*
X1604482Y405374D01*
Y403203D01*
G01D02*
Y396494D01*
G01X1625500Y573000D02*
Y512738D01*
X1587023Y474261D01*
G01X1559700Y517000D02*
X1565500D01*
G01X1570500Y517250D02*
X1570250Y517000D01*
X1565500D01*
G01X1581000Y527000D02*
X1581250Y527250D01*
Y533500D01*
G01X1585000D02*
X1586500Y535000D01*
Y559750D01*
X1583750Y562500D01*
G01X1582000Y573000D02*
Y571250D01*
X1583750Y569500D01*
Y566500D01*
G01Y562500D02*
Y566500D01*
G01X1581250Y533500D02*
X1585000D01*
G01X1552300Y514440D02*
X1554840D01*
X1555450Y515050D01*
Y524900D01*
G01D02*
Y529800D01*
G01X1557000Y539500D02*
Y535350D01*
X1555450Y533800D01*
G01Y529800D02*
Y533800D01*
G01X1577750Y533500D02*
X1573000D01*
G01X1559700Y519560D02*
X1563060D01*
X1564250Y520750D01*
X1570500D01*
G01D02*
X1575000D01*
G01D02*
Y524000D01*
X1572000Y527000D01*
G01D02*
Y532500D01*
X1573000Y533500D01*
G01X1570500Y508250D02*
X1565500D01*
G01D02*
X1560500D01*
G01D02*
X1556000D01*
G01X1552300Y517000D02*
X1549100D01*
X1547000Y514900D01*
Y509600D01*
X1548350Y508250D01*
X1556000D01*
G01X1570500Y504750D02*
X1574000D01*
G01X1625500Y579000D02*
X1630050D01*
X1630100Y579050D01*
G01X1589749Y829350D02*
Y826651D01*
X1591400Y825000D01*
G01X1589749Y842032D02*
Y836182D01*
G01D02*
Y829350D01*
G01X1604482Y855959D02*
Y849250D01*
G01X1625400Y1025900D02*
Y1013800D01*
X1618000Y1006400D01*
Y935335D01*
X1607884Y925219D01*
G01X1625400Y1031900D02*
X1625450Y1031850D01*
X1629800D01*
G01X1559700Y969500D02*
X1565500D01*
G01X1570500Y969750D02*
X1570250Y969500D01*
X1565500D01*
G01X1583750Y1015000D02*
Y1013750D01*
X1586500Y1011000D01*
Y986500D01*
X1586000Y986000D01*
G01X1581000Y979500D02*
X1581250Y979750D01*
Y986000D01*
G01X1582000Y1025500D02*
Y1023750D01*
X1583750Y1022000D01*
Y1019000D01*
G01D02*
Y1015000D01*
G01X1581250Y986000D02*
X1586000D01*
G01X1555750Y978600D02*
Y982600D01*
G01X1552300Y966940D02*
X1554840D01*
X1555750Y967850D01*
Y978600D01*
G01X1557000Y992000D02*
Y987850D01*
X1555750Y986600D01*
G01Y982600D02*
Y986600D01*
G01X1577750Y986000D02*
X1573000D01*
G01X1559700Y972060D02*
X1563060D01*
X1564250Y973250D01*
X1570500D01*
G01D02*
X1575000D01*
G01D02*
Y976500D01*
X1572000Y979500D01*
G01D02*
Y985000D01*
X1573000Y986000D01*
G01X1570500Y960750D02*
X1565500D01*
G01D02*
X1560500D01*
G01D02*
X1556000D01*
G01X1552300Y969500D02*
X1548700D01*
X1546800Y967600D01*
Y962200D01*
X1548250Y960750D01*
X1556000D01*
G01X1570500Y957250D02*
X1574000D01*
G01X1683700Y64000D02*
X1689500D01*
G01X1694500Y64250D02*
X1694250Y64000D01*
X1689500D01*
G01X1705000Y74000D02*
X1705250Y74250D01*
Y80500D01*
G01X1709000D02*
X1710500Y82000D01*
Y106750D01*
X1707750Y109500D01*
G01X1705250Y80500D02*
X1709000D01*
G01X1676300Y61440D02*
X1677940D01*
X1679600Y63100D01*
Y72500D01*
G01D02*
Y76950D01*
X1679650Y77000D01*
G01D02*
Y81000D01*
G01D02*
X1681000Y82350D01*
Y86500D01*
G01X1701750Y80500D02*
X1697000D01*
G01X1683700Y66560D02*
X1687060D01*
X1688250Y67750D01*
X1694500D01*
G01D02*
X1699000D01*
G01D02*
Y71000D01*
X1696000Y74000D01*
G01D02*
Y79500D01*
X1697000Y80500D01*
G01X1694500Y55250D02*
X1689500D01*
G01X1680000D02*
X1684500D01*
G01D02*
X1689500D01*
G01X1676300Y64000D02*
X1673300D01*
X1671300Y62000D01*
Y57900D01*
X1673950Y55250D01*
X1680000D01*
G01X1712525Y191268D02*
Y61805D01*
X1702470Y51750D01*
X1694500D01*
G01X1629394Y156319D02*
X1661516D01*
G01X1639300Y126350D02*
X1635300D01*
G01D02*
X1630181D01*
G01X1639300D02*
X1642722D01*
X1642753Y126319D01*
X1661516D01*
G01X1706000Y120000D02*
Y118250D01*
X1707750Y116500D01*
Y113500D01*
G01Y109500D02*
Y113500D01*
G01X1721381Y411596D02*
X1763114D01*
X1767651Y407059D01*
Y402301D01*
G01X1683700Y517000D02*
X1689500D01*
G01X1694500Y517250D02*
X1694250Y517000D01*
X1689500D01*
G01X1705000Y527000D02*
X1705250Y527250D01*
Y533500D01*
G01X1709000D02*
X1710500Y535000D01*
Y559750D01*
X1707750Y562500D01*
G01X1706000Y573000D02*
Y571250D01*
X1707750Y569500D01*
Y566500D01*
G01Y562500D02*
Y566500D01*
G01X1705250Y533500D02*
X1709000D01*
G01X1676300Y514440D02*
X1679140D01*
X1680050Y515350D01*
Y525200D01*
G01D02*
Y530100D01*
G01X1681000Y539500D02*
Y535050D01*
X1680050Y534100D01*
G01Y530100D02*
Y534100D01*
G01X1701750Y533500D02*
X1697000D01*
G01X1683700Y519560D02*
X1687060D01*
X1688250Y520750D01*
X1694500D01*
G01D02*
X1699000D01*
G01D02*
Y524000D01*
X1696000Y527000D01*
G01D02*
Y532500D01*
X1697000Y533500D01*
G01X1694500Y508250D02*
X1689500D01*
G01D02*
X1684500D01*
G01D02*
X1680000D01*
G01X1676300Y517000D02*
X1672800D01*
X1671400Y515600D01*
Y509500D01*
X1672650Y508250D01*
X1680000D01*
G01X1694500Y504750D02*
X1698000D01*
G01X1757000Y595000D02*
X1752708D01*
X1748524Y590816D01*
Y544803D01*
X1701720Y497999D01*
G01X1629394Y609075D02*
X1661516D01*
G01X1638200Y579050D02*
X1634200D01*
G01D02*
X1630100D01*
G01X1638200D02*
X1645833D01*
X1645858Y579075D01*
X1661516D01*
G01X1713961Y829350D02*
Y825000D01*
G01Y842032D02*
Y836182D01*
G01D02*
Y829350D01*
G01X1639100Y1031850D02*
X1635100D01*
G01X1629800D02*
X1635100D01*
G01X1639100D02*
X1643330D01*
X1643349Y1031831D01*
X1661516D01*
G01X1683700Y969500D02*
X1689500D01*
G01X1694500Y969750D02*
X1694250Y969500D01*
X1689500D01*
G01X1705000Y979500D02*
Y983000D01*
X1705250Y983250D01*
Y986000D01*
G01X1709000D02*
X1710500Y987500D01*
Y1012250D01*
X1707750Y1015000D01*
G01X1706000Y1025500D02*
Y1023750D01*
X1707750Y1022000D01*
Y1019000D01*
G01Y1015000D02*
Y1019000D01*
G01X1705250Y986000D02*
X1709000D01*
G01X1676300Y966940D02*
X1678840D01*
X1679650Y967750D01*
Y978000D01*
G01D02*
Y982300D01*
G01X1681000Y992000D02*
Y987650D01*
X1679650Y986300D01*
G01Y982300D02*
Y986300D01*
G01X1701750Y986000D02*
X1697000D01*
G01X1683700Y972060D02*
X1687060D01*
X1688250Y973250D01*
X1694500D01*
G01D02*
X1699000D01*
G01D02*
Y976500D01*
X1696000Y979500D01*
G01D02*
Y985000D01*
X1697000Y986000D01*
G01X1694500Y960750D02*
X1689500D01*
G01D02*
X1684500D01*
G01D02*
X1680000D01*
G01X1676300Y969500D02*
X1672800D01*
X1671200Y967900D01*
Y963000D01*
X1673450Y960750D01*
X1680000D01*
G01X1694500Y957250D02*
X1698000D01*
G01X1629394Y1061831D02*
X1661516D01*
G01X1656250Y1465000D02*
Y1468750D01*
X1667500Y1480000D01*
X1715275D01*
X1728346Y1466929D01*
G01X1656250Y1465000D02*
Y1461250D01*
G01X1816000Y72700D02*
X1818400D01*
X1822428Y76728D01*
Y77200D01*
G01X1808600Y70140D02*
X1803660D01*
X1803200Y70600D01*
G01D02*
Y72750D01*
X1803650Y73200D01*
Y74500D01*
X1803100Y75050D01*
G01X1796300Y111100D02*
Y100300D01*
X1792000Y96000D01*
Y78800D01*
X1795750Y75050D01*
X1799100D01*
G01D02*
X1803100D01*
G01X1816000Y75260D02*
Y78011D01*
X1818928Y80939D01*
G01X1801150Y63200D02*
X1804700D01*
X1804800Y63100D01*
G01D02*
X1806150Y64450D01*
X1808500D01*
G01X1808600Y72700D02*
X1811400D01*
X1812750Y71350D01*
Y64400D01*
G01X1808500Y64450D02*
X1812700D01*
X1812750Y64400D01*
G01X1834018Y169783D02*
Y135240D01*
X1832838Y134060D01*
Y112062D01*
X1834600Y110300D01*
Y80800D01*
X1818200Y64400D01*
X1816250D01*
G01X1802461Y23406D02*
Y19139D01*
X1803900Y17700D01*
X1811800D01*
G01X1825350Y32000D02*
X1823150Y29800D01*
X1822600D01*
X1817816Y25016D01*
Y20116D01*
X1815400Y17700D01*
X1811800D01*
G01X1799901Y23406D02*
Y18699D01*
X1803600Y15000D01*
X1815564D01*
X1819841Y19277D01*
Y24177D01*
X1823439Y27775D01*
X1824561D01*
X1824724Y27938D01*
X1828627D01*
X1830288Y26277D01*
Y25762D01*
X1830950Y25100D01*
G01X1797341Y23406D02*
Y18395D01*
X1802761Y12975D01*
X1823975D01*
X1830950Y19950D01*
Y20900D01*
G01X1799901Y39586D02*
Y36799D01*
X1801200Y35500D01*
X1808100D01*
X1810800Y38200D01*
X1812800D01*
G01X1803400Y50350D02*
X1803900Y49850D01*
Y46100D01*
G01X1802461Y39586D02*
Y44661D01*
X1803900Y46100D01*
G01X1808300Y50450D02*
Y46200D01*
X1808200Y46100D01*
G01X1805021Y39586D02*
Y42921D01*
X1808200Y46100D01*
G01X1803400Y53850D02*
Y56780D01*
X1803620Y57000D01*
G01X1808300Y53950D02*
Y56600D01*
X1807500Y57400D01*
G01X1753606Y156319D02*
X1785728D01*
G01X1754300Y125900D02*
X1749700D01*
G01X1763600Y126350D02*
X1759600D01*
G01D02*
X1757234D01*
X1756784Y125900D01*
X1754300D01*
G01X1763600Y126350D02*
X1769376D01*
X1769407Y126319D01*
X1785728D01*
G01X1749700Y131900D02*
Y135600D01*
G01X1805142Y383782D02*
Y372600D01*
G01X1753442Y402630D02*
Y405641D01*
X1753631Y405830D01*
G01X1753509Y396293D02*
Y402563D01*
X1753442Y402630D01*
G01X1767666Y396297D02*
Y402286D01*
X1767651Y402301D01*
G01X1805142Y389632D02*
Y383782D01*
G01X1786451Y408530D02*
X1786466Y408545D01*
X1817343D01*
X1819875Y406013D01*
Y403559D01*
G01X1807700Y517000D02*
X1813500D01*
G01X1818500Y517250D02*
X1818250Y517000D01*
X1813500D01*
G01X1800300Y514440D02*
X1802140D01*
X1804050Y516350D01*
Y525100D01*
G01D02*
Y530100D01*
G01X1805000Y539500D02*
Y535050D01*
X1804050Y534100D01*
G01Y530100D02*
Y534100D01*
G01X1807700Y519560D02*
X1811060D01*
X1812250Y520750D01*
X1818500D01*
G01Y508250D02*
X1813500D01*
G01D02*
X1808500D01*
G01D02*
X1804000D01*
G01X1800300Y517000D02*
X1797100D01*
X1795500Y515400D01*
Y510900D01*
X1798150Y508250D01*
X1804000D01*
G01X1753606Y609075D02*
X1785728D01*
G01X1763000Y595000D02*
Y589000D01*
G01X1763250Y579500D02*
Y583500D01*
G01Y579500D02*
X1763675Y579075D01*
X1785728D01*
G01X1763250Y583500D02*
Y588750D01*
X1763000Y589000D01*
G01X1728694Y855959D02*
Y849250D01*
G01X1749300Y1025900D02*
Y996900D01*
X1735500Y983100D01*
Y930779D01*
X1726771Y922050D01*
G01X1763300Y1031850D02*
X1759300D01*
G01X1754300D02*
X1759300D01*
G01X1749300Y1031900D02*
X1754250D01*
X1754300Y1031850D01*
G01X1763300D02*
X1763981D01*
X1764000Y1031831D01*
X1785728D01*
G01X1807700Y969500D02*
X1813500D01*
G01X1818500Y969750D02*
X1818250Y969500D01*
X1813500D01*
G01X1803750Y978100D02*
Y982200D01*
G01X1800300Y966940D02*
X1802940D01*
X1803750Y967750D01*
Y978100D01*
G01X1805000Y992000D02*
Y987450D01*
X1803750Y986200D01*
G01Y982200D02*
Y986200D01*
G01X1807700Y972060D02*
X1811060D01*
X1812250Y973250D01*
X1818500D01*
G01Y960750D02*
X1813500D01*
G01D02*
X1808500D01*
G01D02*
X1804000D01*
G01X1800300Y969500D02*
X1796800D01*
X1795200Y967900D01*
Y962200D01*
X1796650Y960750D01*
X1804000D01*
G01X1753606Y1061831D02*
X1785728D01*
G01X1878298Y68922D02*
X1874500Y72720D01*
Y73700D01*
G01D02*
Y73750D01*
X1878250Y77500D01*
G01Y81500D02*
Y82850D01*
X1879741Y84341D01*
X1882966D01*
X1885000Y86375D01*
Y111500D01*
X1899819Y126319D01*
X1909941D01*
G01X1878250Y77500D02*
Y81500D01*
G01X1822428Y80939D02*
Y77200D01*
G01X1874900Y25250D02*
X1877500D01*
X1878600Y24150D01*
G01X1883500Y29300D02*
Y25500D01*
X1882150Y24150D01*
X1878600D01*
G01X1868800Y31300D02*
X1866750D01*
X1865500Y30050D01*
X1862300D01*
G01X1862900Y34200D02*
X1864800D01*
X1867450Y36850D01*
Y38100D01*
G01X1856000Y85500D02*
Y74000D01*
X1867450Y62550D01*
Y42100D01*
G01Y38100D02*
Y42100D01*
G01X1862300Y30050D02*
Y33600D01*
X1862900Y34200D01*
G01X1880940Y36700D02*
X1871300D01*
X1870200Y37800D01*
Y63000D01*
X1862750Y70450D01*
Y73500D01*
G01D02*
Y78000D01*
G01X1865500Y113000D02*
X1864000D01*
X1861000Y110000D01*
Y83750D01*
X1862750Y82000D01*
G01Y78000D02*
Y82000D01*
G01X1818900Y88800D02*
Y94400D01*
G01X1818928Y85039D02*
Y88772D01*
X1818900Y88800D01*
G01X1818928Y80939D02*
Y85039D01*
G01X1886060Y29300D02*
Y22810D01*
X1882250Y19000D01*
X1878700D01*
G01D02*
X1877650D01*
X1874900Y21750D01*
G01X1862300Y26550D02*
X1862550Y26300D01*
Y22300D01*
G01D02*
X1868800D01*
G01D02*
X1874350D01*
X1874900Y21750D01*
G01X1872900Y42250D02*
X1876700D01*
G01X1883500Y36700D02*
Y39400D01*
X1884600Y40500D01*
Y42250D01*
G01X1876700D02*
X1880500D01*
G01X1884600D02*
X1880500D01*
G01X1872298Y68922D02*
X1868600D01*
G01X1872900Y45750D02*
Y49000D01*
G01X1834950Y29300D02*
X1832250Y32000D01*
X1825350D01*
G01X1838850Y25200D02*
X1838550Y25500D01*
X1835000D01*
G01D02*
X1831350D01*
X1830950Y25100D01*
G01X1838850Y21100D02*
X1838450Y20700D01*
X1835000D01*
G01X1830950Y20900D02*
X1834800D01*
X1835000Y20700D01*
G01X1878100Y149600D02*
X1893600D01*
X1900319Y156319D01*
X1909941D01*
G01X1830000Y101000D02*
X1825850D01*
X1825650Y100800D01*
G01X1830000Y101000D02*
X1830750Y101750D01*
Y109500D01*
G01X1829500Y120000D02*
Y118000D01*
X1830750Y116750D01*
Y113500D01*
G01Y109500D02*
Y113500D01*
G01X1827900Y94400D02*
Y96400D01*
X1825650Y98650D01*
Y100800D01*
G01X1818900Y94400D02*
Y97550D01*
X1822150Y100800D01*
G01X1819875Y403559D02*
Y396850D01*
G01X1876100Y521200D02*
Y525900D01*
X1876150Y525950D01*
G01D02*
Y530600D01*
G01Y534600D02*
X1879004Y537454D01*
X1883630D01*
X1885500Y539324D01*
Y565000D01*
X1899575Y579075D01*
X1909941D01*
G01X1876150Y530600D02*
Y534600D01*
G01X1853250Y522200D02*
Y527000D01*
G01X1859300Y519000D02*
X1856450D01*
X1853250Y522200D01*
G01X1829000Y527000D02*
X1829250Y527250D01*
Y533500D01*
G01X1833000D02*
X1834500Y535000D01*
Y559750D01*
X1831750Y562500D01*
G01X1830000Y573000D02*
Y571250D01*
X1831750Y569500D01*
Y566500D01*
G01Y562500D02*
Y566500D01*
G01X1829250Y533500D02*
X1833000D01*
G01X1857500Y558000D02*
Y564000D01*
G01X1851750Y549000D02*
Y544250D01*
X1849500Y542000D01*
G01X1851750Y553000D02*
X1852500D01*
X1857500Y558000D01*
G01X1851750Y549000D02*
Y553000D01*
G01X1849500Y542000D02*
X1848750Y541250D01*
X1843000D01*
G01X1859250Y543500D02*
Y531162D01*
G01X1866700Y521560D02*
X1863440D01*
X1862500Y522500D01*
Y524493D01*
X1859250Y527743D01*
Y531162D01*
G01X1865500Y566000D02*
Y557000D01*
X1859250Y550750D01*
Y547500D01*
G01D02*
Y543500D01*
G01X1825750Y533500D02*
X1821000D01*
G01X1818500Y520750D02*
X1823000D01*
G01D02*
Y524000D01*
X1820000Y527000D01*
G01D02*
Y532500D01*
X1821000Y533500D01*
G01X1859300Y516440D02*
X1851310D01*
X1849750Y518000D01*
G01X1843000Y537750D02*
X1843250Y537500D01*
Y533500D01*
G01X1849750Y527000D02*
Y518000D01*
G01Y527000D02*
Y532750D01*
X1849500Y533000D01*
G01D02*
X1843750D01*
X1843250Y533500D01*
G01X1866700Y519000D02*
X1864500D01*
X1863000Y517500D01*
Y510750D01*
G01X1848500D02*
X1853000D01*
G01D02*
X1858000D01*
G01X1863000D02*
X1858000D01*
G01X1818500Y504750D02*
X1822000D01*
G01X1876100Y515200D02*
Y513968D01*
X1860109Y497977D01*
G01X1848500Y507250D02*
Y504000D01*
G01X1878200Y602900D02*
X1894400D01*
X1900575Y609075D01*
X1909941D01*
G01X1838174Y829350D02*
Y825000D01*
G01Y842032D02*
Y836182D01*
G01D02*
Y829350D01*
G01X1852907Y855959D02*
Y849250D01*
G01X1867500Y982200D02*
X1873700Y976000D01*
Y969769D01*
X1869689Y965758D01*
Y951911D01*
X1866318Y948540D01*
G01X1867500Y988200D02*
X1871900D01*
G01D02*
X1875750D01*
X1875800Y988250D01*
G01X1879800D02*
X1882000D01*
X1885000Y991250D01*
Y1017500D01*
X1899331Y1031831D01*
X1909941D01*
G01X1875800Y988250D02*
X1879800D01*
G01X1853250Y975200D02*
Y980000D01*
G01X1859300Y972000D02*
X1856450D01*
X1853250Y975200D01*
G01X1831750Y1015000D02*
X1834500Y1012250D01*
Y986500D01*
X1834000Y986000D01*
G01X1829000Y979500D02*
X1829250Y979750D01*
Y986000D01*
G01X1830000Y1025500D02*
Y1023750D01*
X1831750Y1022000D01*
Y1019000D01*
G01D02*
Y1015000D01*
G01X1829250Y986000D02*
X1834000D01*
G01X1857500Y1017000D02*
Y1010000D01*
G01X1851750Y1002000D02*
Y997250D01*
X1849500Y995000D01*
G01X1857500Y1010000D02*
X1853500Y1006000D01*
X1851750D01*
G01Y1002000D02*
Y1006000D01*
G01X1849500Y995000D02*
X1848750Y994250D01*
X1843000D01*
G01X1859250Y996500D02*
Y983276D01*
G01X1866700Y974560D02*
X1863940D01*
X1862500Y976000D01*
Y978000D01*
X1859250Y981250D01*
Y983276D01*
G01X1865500Y1019000D02*
Y1010000D01*
X1859250Y1003750D01*
Y1000500D01*
G01D02*
Y996500D01*
G01X1825750Y986000D02*
X1821000D01*
G01X1818500Y973250D02*
X1823000D01*
G01D02*
Y976500D01*
X1820000Y979500D01*
G01D02*
Y985000D01*
X1821000Y986000D01*
G01X1859300Y969440D02*
X1851310D01*
X1849750Y971000D01*
G01X1843000Y990750D02*
X1843250Y990500D01*
Y986500D01*
G01X1849750Y980000D02*
Y971000D01*
G01Y980000D02*
Y985750D01*
X1849500Y986000D01*
G01D02*
X1843750D01*
X1843250Y986500D01*
G01X1866700Y972000D02*
X1866589Y972111D01*
X1864611D01*
X1863000Y970500D01*
Y963750D01*
G01X1858000D02*
X1853000D01*
G01D02*
X1848500D01*
G01X1863000D02*
X1858000D01*
G01X1818500Y957250D02*
X1822000D01*
G01X1848500Y960250D02*
Y957000D01*
G01X1878300Y1056100D02*
X1894600D01*
X1900331Y1061831D01*
X1909941D01*
G54D108*
G01X129821Y40886D02*
X128286D01*
X126900Y39500D01*
G01X210700Y62940D02*
X215100D01*
G01X457700D02*
X462100D01*
G01X668000Y1448500D02*
X673500D01*
G01X707700Y62940D02*
X712000D01*
G01X685079Y1463250D02*
Y1467829D01*
X685850Y1468600D01*
G01X680250Y1450547D02*
X677155D01*
X675108Y1448500D01*
X673500D01*
G01X1010620Y856130D02*
Y852074D01*
X1009600Y851054D01*
G01X1009750Y846500D02*
Y850904D01*
X1009600Y851054D01*
G01X964230Y861030D02*
Y855630D01*
X964200Y855600D01*
G01X1013180Y856130D02*
Y853080D01*
X1013535Y852725D01*
Y846785D01*
X1013250Y846500D01*
G01X992522Y1451149D02*
X992520Y1451151D01*
Y1454578D01*
X992528Y1454586D01*
Y1455978D01*
X993100Y1456550D01*
G01X1093900Y1292025D02*
X1100625D01*
G01X1816000Y70140D02*
X1820200D01*
G01X1808600Y75260D02*
Y78200D01*
G01X1795600Y44900D02*
X1797341Y43159D01*
Y39586D01*
G54D33*
X95500Y181800D03*
Y634300D03*
Y1087300D03*
X140500Y131900D03*
X219500Y181800D03*
X265000Y132000D03*
X219500Y634300D03*
X220000Y1087300D03*
X344000Y181800D03*
Y634300D03*
Y1087300D03*
X468000Y181800D03*
X389000Y132200D03*
X468000Y634300D03*
Y1087300D03*
X513600Y132100D03*
X528334Y1433529D03*
X528200Y1462400D03*
X592500Y181800D03*
X637300Y132100D03*
X592500Y634300D03*
Y1087300D03*
X651295Y1430719D03*
X716500Y181800D03*
X748400Y142900D03*
X716500Y634300D03*
X752500Y593800D03*
X716500Y1087300D03*
X752500Y1054300D03*
X838470Y942230D03*
X958738Y1418618D03*
X1131215Y1315870D03*
X1213033Y1313744D03*
X1180009Y1313953D03*
X1298500Y151800D03*
Y181300D03*
X1253000Y132200D03*
X1298500Y604800D03*
Y634300D03*
X1252800Y584900D03*
Y1037500D03*
X1298500Y1057300D03*
Y1086800D03*
X1422500Y151800D03*
Y181300D03*
X1376700Y132200D03*
X1422500Y604800D03*
Y634300D03*
Y1057300D03*
Y1086800D03*
X1501300Y132200D03*
X1547000Y151800D03*
Y181300D03*
X1625300Y132200D03*
X1547000Y604800D03*
Y634300D03*
Y1057300D03*
Y1086800D03*
X1671000Y151800D03*
Y181300D03*
Y604800D03*
Y634300D03*
Y1057300D03*
Y1086800D03*
X1795000Y151800D03*
Y181300D03*
X1749700Y131700D03*
X1795000Y604800D03*
Y634300D03*
Y1057300D03*
Y1086800D03*
X1887000Y181300D03*
Y634300D03*
Y1087300D03*
G54D42*
X69567Y389096D03*
X73442Y396596D03*
X65692D03*
X57300Y841750D03*
X61175Y849250D03*
X53425D03*
X180300Y841750D03*
X184175Y849250D03*
X176425D03*
X171374Y1421750D03*
X175249Y1429250D03*
X167499D03*
X203700Y388850D03*
X207575Y396350D03*
X199825D03*
X305400Y389050D03*
X309275Y396550D03*
X301525D03*
X305400Y841750D03*
X309275Y849250D03*
X301525D03*
X429900Y388850D03*
X433775Y396350D03*
X426025D03*
X429600Y841550D03*
X433475Y849050D03*
X425725D03*
X554100Y389050D03*
X557975Y396550D03*
X550225D03*
X665100Y388850D03*
X668975Y396350D03*
X661225D03*
X593680Y842750D03*
X597555Y850250D03*
X589805D03*
X670500Y841550D03*
X666625Y849050D03*
X674375D03*
X934000Y862250D03*
X937875Y869750D03*
X930125D03*
X1016000Y910750D03*
X1019875Y918250D03*
X1012125D03*
X1028050Y1479564D03*
X1024175Y1487064D03*
X1031925D03*
X1031163Y1464391D03*
X1035038Y1471891D03*
X1027288D03*
X1227969Y841750D03*
X1231844Y849250D03*
X1224094D03*
X1209846Y1407553D03*
X1213721Y1415053D03*
X1205971D03*
X1273803Y388837D03*
X1277678Y396337D03*
X1269928D03*
X1310500Y1421750D03*
X1314375Y1429250D03*
X1306625D03*
X1352182Y388994D03*
X1356057Y396494D03*
X1348307D03*
X1352182Y841750D03*
X1356057Y849250D03*
X1348307D03*
X1476394Y388994D03*
X1480269Y396494D03*
X1472519D03*
X1476394Y841750D03*
X1480269Y849250D03*
X1472519D03*
X1600607Y388994D03*
X1604482Y396494D03*
X1596732D03*
X1600607Y841750D03*
X1604482Y849250D03*
X1596732D03*
X1720944D03*
X1698626Y1421750D03*
X1702501Y1429250D03*
X1694751D03*
X1763791Y388797D03*
X1767666Y396297D03*
X1759916D03*
X1816000Y389350D03*
X1812125Y396850D03*
X1749634Y388793D03*
X1753509Y396293D03*
X1745759D03*
X1724819Y841750D03*
X1728694Y849250D03*
X1819875Y396850D03*
X1849032Y841750D03*
X1852907Y849250D03*
X1845157D03*
G54D60*
X184252Y1445275D03*
Y1466929D03*
X167716Y1445275D03*
Y1466929D03*
X233858Y1445275D03*
Y1466929D03*
X217322Y1445275D03*
Y1466929D03*
X200787Y1445275D03*
Y1466929D03*
X581102Y1445275D03*
Y1466929D03*
X564567Y1445275D03*
Y1466929D03*
X548031Y1445275D03*
Y1466929D03*
X614173Y1445275D03*
Y1466929D03*
X597637Y1445275D03*
Y1466929D03*
X1331496Y1445275D03*
Y1466929D03*
X1314960Y1445275D03*
Y1466929D03*
X1381102Y1445275D03*
Y1466929D03*
X1364566Y1445275D03*
Y1466929D03*
X1348031Y1445275D03*
Y1466929D03*
X1711811Y1445275D03*
Y1466929D03*
X1695275Y1445275D03*
Y1466929D03*
X1761417Y1445275D03*
Y1466929D03*
X1744881Y1445275D03*
Y1466929D03*
X1728346Y1445275D03*
Y1466929D03*
G54D15*
X92200Y72400D03*
X89000Y62800D03*
X60200Y96500D03*
X58659Y383528D03*
X73392Y403305D03*
X92000Y525300D03*
X90300Y516800D03*
X60200Y549000D03*
X46392Y836182D03*
X61125Y855959D03*
X97963Y908025D03*
X97055Y899023D03*
X89597Y901301D03*
X74763Y909325D03*
X73463Y892025D03*
X60200Y1002000D03*
X92200Y968000D03*
Y972500D03*
X164200Y25100D03*
X160500Y32100D03*
X175600Y25100D03*
X164200Y21100D03*
X175600Y20900D03*
X171800Y29200D03*
X147500Y44400D03*
Y48500D03*
X194882Y461287D03*
X187424Y463565D03*
X172590Y471589D03*
X171290Y454289D03*
X192792Y383182D03*
X184200Y549000D03*
X140700Y583000D03*
X184125Y855659D03*
X109763Y911925D03*
X109722Y903550D03*
X140700Y1036000D03*
X184700Y1002000D03*
X141174Y1472900D03*
X142074Y1452500D03*
Y1434000D03*
X128274Y1479100D03*
X198700Y78500D03*
X207200Y45100D03*
X207590Y474189D03*
X195790Y470289D03*
X207549Y465814D03*
X207525Y402959D03*
X216100Y525200D03*
X214600Y516600D03*
X264700Y583000D03*
X214300Y969700D03*
X216700Y978100D03*
X264400Y1036000D03*
X340600Y72600D03*
X338400Y63700D03*
X308700Y96500D03*
X294492Y383482D03*
X309225Y403259D03*
X340700Y525300D03*
X338500Y516800D03*
X308700Y549000D03*
X294492Y836182D03*
X309225Y855959D03*
X308700Y1002000D03*
X338200Y969400D03*
X340600Y978200D03*
X455400Y44500D03*
X418992Y383182D03*
X433725Y402959D03*
X464700Y525300D03*
X462800Y516900D03*
X432700Y549000D03*
X389200Y583000D03*
X418692Y835876D03*
X433425Y855659D03*
X389200Y1036000D03*
X432700Y1002000D03*
X462600Y969200D03*
X464600Y978000D03*
X557200Y96500D03*
X543192Y383482D03*
X557925Y403259D03*
X557200Y549000D03*
X513200Y583000D03*
Y1036000D03*
X557200Y1002000D03*
X589100Y72800D03*
X587200Y64300D03*
X654192Y383182D03*
X668925Y402959D03*
X589100Y525400D03*
X637700Y583000D03*
X659592Y835882D03*
X582598Y836405D03*
X597505Y856859D03*
X586500Y969500D03*
X589200Y978100D03*
X637700Y1036000D03*
X671700Y1430000D03*
X695700Y78500D03*
X704700Y45050D03*
X751700Y130500D03*
X713100Y525300D03*
X681200Y549000D03*
X674325Y855659D03*
X681200Y1002000D03*
X710900Y969600D03*
X713300Y978300D03*
X753100Y1036000D03*
X714200Y1453500D03*
X715500Y1467300D03*
X727200Y1449000D03*
X715600Y1471600D03*
X824690Y659190D03*
Y647190D03*
Y651190D03*
X818000Y776500D03*
X817900Y785500D03*
X818000Y767500D03*
X826200Y819000D03*
Y807000D03*
Y811000D03*
X827700Y897500D03*
Y888500D03*
X827587Y880256D03*
X874690Y643190D03*
Y651190D03*
X870500Y756500D03*
X878353Y811000D03*
X876200Y803000D03*
X919500Y764800D03*
X912200Y774000D03*
Y778000D03*
X875700Y869500D03*
X958200Y898500D03*
X944200D03*
X958750Y1403400D03*
Y1399400D03*
X992948Y539555D03*
X995138Y517437D03*
X999541Y552081D03*
X995163Y526457D03*
X963820Y761010D03*
Y779010D03*
Y765510D03*
X1037581Y855984D03*
X1023700Y842500D03*
X1037584Y851705D03*
X1029862Y849214D03*
X1033042Y825127D03*
X1004007Y899075D03*
X993597Y895065D03*
X1011481Y903075D03*
X1021739Y900965D03*
X1027474Y939306D03*
X979200Y1225000D03*
Y1205000D03*
Y1221000D03*
Y1213000D03*
X979143Y1418699D03*
X1037550Y1496914D03*
X1023950Y1492814D03*
X1045250D03*
X1037550D03*
X1130200Y1291700D03*
Y1296700D03*
X1105812Y1379273D03*
Y1399273D03*
Y1395273D03*
Y1387273D03*
X1115200Y1358500D03*
X1217061Y836182D03*
X1231794Y855959D03*
X1188200Y892600D03*
Y886000D03*
Y906100D03*
Y899500D03*
X1334200Y109500D03*
X1262895Y383269D03*
X1277628Y403046D03*
X1335200Y562500D03*
Y1015000D03*
X1288074Y1471500D03*
X1289074Y1452500D03*
Y1434000D03*
X1274789Y1483400D03*
X1435700Y77000D03*
X1341274Y383426D03*
X1356007Y403203D03*
X1341274Y836182D03*
X1356007Y855959D03*
X1459200Y109500D03*
X1465486Y383426D03*
X1480219Y403203D03*
X1459200Y562500D03*
X1465486Y836182D03*
X1480219Y855959D03*
X1459200Y1015000D03*
X1604600Y129000D03*
X1589699Y383426D03*
X1604432Y403203D03*
X1583700Y562500D03*
X1589699Y836182D03*
X1604432Y855959D03*
X1583700Y1015000D03*
X1707700Y109500D03*
X1715359Y475007D03*
X1714059Y457707D03*
X1707700Y562500D03*
X1713911Y836182D03*
X1707700Y1015000D03*
X1669326Y1452500D03*
Y1434000D03*
X1816200Y64400D03*
X1738559Y473707D03*
X1750318Y469232D03*
X1737651Y464705D03*
X1730193Y466983D03*
X1805092Y383782D03*
X1753392Y402630D03*
X1767601Y402301D03*
X1750359Y477607D03*
X1728644Y855959D03*
X1812963Y908025D03*
X1812055Y899023D03*
X1804597Y901301D03*
X1789763Y909325D03*
X1788463Y892025D03*
X1806841Y1490100D03*
X1809811Y1471000D03*
X1822378Y85039D03*
Y80939D03*
X1881700Y77500D03*
X1866200Y78000D03*
X1867400Y38100D03*
X1825300Y32000D03*
X1830900Y25100D03*
Y20900D03*
X1838400Y29300D03*
X1842300Y25200D03*
Y21100D03*
X1830700Y109500D03*
X1819825Y403559D03*
X1831700Y562500D03*
X1879600Y530600D03*
X1851700Y549000D03*
X1853200Y527000D03*
X1838124Y836182D03*
X1852857Y855959D03*
X1824763Y911925D03*
X1824722Y903550D03*
X1831700Y1015000D03*
X1851700Y1002000D03*
X1853200Y980000D03*
G54D51*
X149300Y37300D03*
X136866Y156319D03*
Y609075D03*
X116263Y911525D03*
X136866Y1061831D03*
X261078Y156319D03*
X214090Y473789D03*
X261078Y609075D03*
Y1061831D03*
X385291Y156319D03*
Y609075D03*
Y1061831D03*
X509503Y156319D03*
Y609075D03*
Y1061831D03*
X633716Y156319D03*
Y609075D03*
Y1061831D03*
X708200Y148900D03*
X757929Y609075D03*
Y1061831D03*
X1020061Y847967D03*
X1256756Y156319D03*
Y609075D03*
Y1061831D03*
X1380969Y156319D03*
Y609075D03*
Y1061831D03*
X1505181Y156319D03*
Y609075D03*
Y1061831D03*
X1629394Y156319D03*
Y609075D03*
Y1061831D03*
X1812800Y38200D03*
X1753606Y156319D03*
X1756859Y477207D03*
X1753606Y609075D03*
Y1061831D03*
X1878100Y149600D03*
X1878200Y602900D03*
X1831263Y911525D03*
X1878300Y1056100D03*
G54D24*
X78000Y44000D03*
X38000Y86000D03*
X86700Y80700D03*
X92250Y80500D03*
X75000Y73300D03*
X92500Y62800D03*
X56750Y62000D03*
X64250Y87500D03*
X95800Y71800D03*
X30500Y67000D03*
X74000Y87500D03*
X89000D03*
X84000D03*
X79000D03*
X81500Y105000D03*
X48000Y160000D03*
X95500Y186000D03*
X89000Y162700D03*
X49500Y140500D03*
X64250Y98500D03*
X73500Y120500D03*
X72900Y133000D03*
X50000Y105500D03*
X54500D03*
X59000D03*
X88000Y204000D03*
X76000Y232000D03*
X50000Y200000D03*
X38000Y348000D03*
X55209Y379278D03*
X58709Y372346D03*
X38000Y418000D03*
Y452000D03*
X69942Y406555D03*
X65692Y392187D03*
X58728Y393206D03*
X84581Y397946D03*
X79581D03*
X88000Y498000D03*
Y478000D03*
X38000Y544000D03*
X81500Y557500D03*
X64250Y551000D03*
X86700Y533200D03*
X75000Y525800D03*
X92250Y533000D03*
X93800Y516800D03*
X64250Y540000D03*
X50000Y558000D03*
X54500D03*
X59000D03*
X53250Y518000D03*
X95500Y525500D03*
X79000Y540000D03*
X84000D03*
X89000D03*
X74000D03*
X40000Y614000D03*
X76000Y642000D03*
X38000Y660000D03*
X95500Y638500D03*
X89000Y615200D03*
X73500Y573000D03*
X72800Y585500D03*
X49500Y593000D03*
X92000Y758000D03*
X34000Y792000D03*
X100000Y800000D03*
X57675Y851609D03*
X53425Y853600D03*
X46461Y853382D03*
X42942Y831932D03*
X46442Y825000D03*
X73526Y850100D03*
X68526D03*
X26000Y908000D03*
Y940000D03*
X88000Y946000D03*
X91114Y909791D03*
X85000Y885500D03*
X89000D03*
Y881500D03*
X85000D03*
X89000Y877500D03*
X85000D03*
X89000Y889500D03*
X85000D03*
X89000Y893500D03*
X85000D03*
X81166Y892754D03*
Y888754D03*
X41263Y887025D03*
X48763D03*
X55763D03*
X51263Y894525D03*
X46763Y891525D03*
X83300Y908900D03*
X100310Y899557D03*
X68900Y897700D03*
X77263Y898225D03*
X83500Y898662D03*
X73430Y898509D03*
X66263Y879525D03*
X67763Y883525D03*
X81500Y1010500D03*
X38000Y996000D03*
X73500Y1026000D03*
X72600Y1038400D03*
X49500Y1046000D03*
X86700Y986200D03*
X75000Y978800D03*
X64250Y1004000D03*
X92250Y986000D03*
X95500Y968000D03*
X59000Y1011000D03*
X54500D03*
X50000D03*
X64250Y993000D03*
X53250Y971000D03*
X95500Y972500D03*
X74000Y993000D03*
X89000D03*
X84000D03*
X79000D03*
X50000Y1100000D03*
X95500Y1091500D03*
X89000Y1068200D03*
X50000Y1150000D03*
Y1200000D03*
X100000Y1250000D03*
X50000D03*
Y1300000D03*
X100000D03*
X50000Y1350000D03*
X100000D03*
Y1400000D03*
X50000D03*
X86000Y1444000D03*
X144000Y88000D03*
X111437Y81319D03*
Y66319D03*
X106937Y84370D03*
Y93819D03*
X111437Y51319D03*
X118437Y27697D03*
X148050Y20971D03*
X126900Y39500D03*
X150700Y33100D03*
X157900Y17900D03*
X157600Y24500D03*
X157400Y35800D03*
X183500Y75450D03*
Y80250D03*
X178500Y80000D03*
X185551Y21529D03*
X151200Y48500D03*
Y44400D03*
X145864Y33216D03*
X175650Y28600D03*
X158000Y152000D03*
X154000Y106000D03*
X111437Y161319D03*
Y151319D03*
X173500Y140500D03*
X111437Y131319D03*
Y121319D03*
X127600Y119300D03*
X106937Y103268D03*
X131600Y119100D03*
X174000Y236000D03*
X118437Y199941D03*
X112000Y316000D03*
X162000Y310000D03*
X150000Y350000D03*
X189342Y378932D03*
X192842Y372000D03*
X102000Y440000D03*
X174000Y410000D03*
X178993Y455018D03*
Y451018D03*
X192861Y400482D03*
X182827Y447764D03*
Y455764D03*
X186827D03*
X182827Y451764D03*
X186827D03*
X182827Y439764D03*
Y443764D03*
X188941Y472055D03*
X153590Y449289D03*
X146590D03*
X149090Y456789D03*
X144590Y453789D03*
X139090Y449289D03*
X181127Y471164D03*
X166727Y459964D03*
X175090Y460489D03*
X181327Y460926D03*
X171257Y460773D03*
X165590Y445789D03*
X164127Y442264D03*
X156000Y544000D03*
X130000Y560000D03*
X144000Y550000D03*
X152000Y492000D03*
X160000Y508000D03*
X188250Y550951D03*
X106937Y556024D03*
Y537126D03*
Y546575D03*
X111437Y534075D03*
Y519075D03*
Y504075D03*
X118437Y480453D03*
X188250Y540000D03*
X176439Y524992D03*
X182300Y558600D03*
X173600Y554400D03*
Y558600D03*
X178100D03*
X176506Y539295D03*
X180500Y576000D03*
X162000Y614000D03*
X118437Y652697D03*
X111437Y614075D03*
Y604075D03*
Y584075D03*
Y574075D03*
X173500Y593000D03*
X140750Y575500D03*
X143000Y587000D03*
X174000Y686000D03*
X156000Y768000D03*
X150000Y800000D03*
X168937Y850845D03*
X163740Y846722D03*
X159740D03*
X154737Y854845D03*
Y850845D03*
X168937Y854845D03*
X176425Y853700D03*
X180400Y852300D03*
X176558Y831000D03*
X172318Y844782D03*
X169442Y824700D03*
X191026Y850100D03*
X196026D03*
X136000Y912000D03*
X140000Y938000D03*
X188000Y932000D03*
X159860Y924548D03*
X163860D03*
X168863Y916425D03*
Y920425D03*
X118437Y933209D03*
X154663Y916425D03*
Y920425D03*
X173763Y907525D03*
X189763D03*
X185763D03*
X181763D03*
X177763D03*
X193763D03*
X102263Y919025D03*
X113763Y865025D03*
X106263Y900025D03*
X180500Y1028500D03*
X160000Y982000D03*
X142000Y1008000D03*
X140750Y1028500D03*
X174000Y1046000D03*
X111437Y1036831D03*
Y1026831D03*
X188750Y1004000D03*
X111437Y956831D03*
Y986831D03*
Y971831D03*
X106937Y1008780D03*
Y989882D03*
Y999331D03*
X183500Y1011000D03*
X179000D03*
X174500D03*
X188750Y993000D03*
X178200Y977700D03*
X140750Y1039250D03*
X125500Y992500D03*
X136500Y1111500D03*
X164000Y1068000D03*
X118437Y1105453D03*
X111437Y1066831D03*
Y1056831D03*
X158484Y1416000D03*
X139774Y1420600D03*
X131143Y1427661D03*
X130601Y1411700D03*
X136774Y1411000D03*
X188274Y1416600D03*
X165774Y1422700D03*
X157574Y1453500D03*
X145374Y1452500D03*
X145274Y1434685D03*
X156674Y1435085D03*
X167499Y1434000D03*
X104074Y1462500D03*
X114874Y1476700D03*
X118574Y1465900D03*
X121274Y1447400D03*
X124874Y1442600D03*
X151874Y1449800D03*
X149955Y1431573D03*
X135374Y1464000D03*
Y1445500D03*
X105774Y1491000D03*
X120474Y1482800D03*
X132674Y1484200D03*
X137624Y1469000D03*
X175249Y1434075D03*
X156374Y1430500D03*
X130322Y1434014D03*
X135174Y1452400D03*
X104184Y1457200D03*
X139374Y1486100D03*
X124074Y1437200D03*
X113314Y1441700D03*
X262000Y30000D03*
X280000Y90000D03*
X264000Y94000D03*
X202500Y82500D03*
X231000Y82000D03*
X231149Y93819D03*
X235649Y81319D03*
Y66319D03*
X203300Y71700D03*
X215100Y62940D03*
X207000Y80500D03*
X235649Y51319D03*
X242649Y27697D03*
X220000Y80500D03*
X200819Y74819D03*
X217000Y38250D03*
X198800Y34000D03*
X203078Y33972D03*
X215500Y80500D03*
X203000Y87500D03*
X213000D03*
X208000D03*
X197500D03*
X284000Y160000D03*
X256000Y142000D03*
X235649Y161319D03*
Y151319D03*
X219500Y186000D03*
X213500Y162700D03*
X235649Y131319D03*
Y121319D03*
X231149Y103268D03*
X250900Y119500D03*
X197000Y133000D03*
X197500Y120500D03*
X254900Y119600D03*
X198000Y198000D03*
X212000Y236000D03*
X288000Y242000D03*
X250000Y250000D03*
X242649Y199941D03*
X214000Y328000D03*
X250000Y350000D03*
Y300000D03*
X291042Y379232D03*
X286000Y422000D03*
X257567Y409386D03*
X261567D03*
X266764Y417509D03*
Y413509D03*
X252564D03*
Y417509D03*
X199825Y400700D03*
X204075Y398609D03*
X271590Y469789D03*
X275590D03*
X279590D03*
X283590D03*
X287590D03*
X291590D03*
X218214Y397600D03*
X213214D03*
X198137Y461821D03*
X204090Y462289D03*
X212500Y557500D03*
X216000Y498000D03*
X286000Y490000D03*
Y506000D03*
X268000Y544000D03*
X278000Y554000D03*
X266690Y479089D03*
Y483089D03*
X252490D03*
Y479089D03*
X257687Y487212D03*
X261687D03*
X231149Y556024D03*
X232433Y537126D03*
X231149Y546575D03*
X235649Y534075D03*
Y519075D03*
Y504075D03*
X242649Y480453D03*
X210700Y533200D03*
X199000Y525800D03*
X216250Y533000D03*
X218000Y516600D03*
X200090Y481289D03*
X220000Y524000D03*
X203000Y540000D03*
X208000D03*
X213000D03*
X198000D03*
X286000Y612000D03*
X200000Y646000D03*
X242649Y652697D03*
X235649Y614075D03*
X213500Y615200D03*
X219500Y638500D03*
X235649Y604075D03*
Y584075D03*
Y574075D03*
X268187Y578998D03*
X197200Y585500D03*
X197500Y573000D03*
X264750Y586250D03*
X250000Y700000D03*
Y750000D03*
Y850000D03*
Y800000D03*
X291042Y831932D03*
X252000Y906000D03*
X212000Y916000D03*
X213500Y951500D03*
X263500Y939500D03*
X242649Y933209D03*
X197263Y901025D03*
X284500Y982000D03*
X265000Y1008500D03*
X206000Y1010500D03*
X198000Y1026000D03*
X197300Y1038500D03*
X264250Y1028500D03*
X235649Y1036831D03*
Y1026831D03*
X252100Y959100D03*
X211200Y986200D03*
X199500Y978800D03*
X216750Y986000D03*
X231149Y1008780D03*
Y989882D03*
Y999331D03*
X235649Y986831D03*
Y971831D03*
X218100Y969700D03*
X264450Y1039250D03*
X252000Y992500D03*
X220000Y978200D03*
X198500Y993000D03*
X213500D03*
X208500D03*
X203500D03*
X288000Y1068000D03*
X200000Y1100000D03*
X242649Y1105453D03*
X220000Y1091500D03*
X213500Y1068200D03*
X235649Y1066831D03*
Y1056831D03*
X200000Y1200000D03*
X250000D03*
Y1150000D03*
X200000D03*
X227500Y1303000D03*
X250000Y1350000D03*
X209374Y1416300D03*
X259500Y1494000D03*
X256000Y1466000D03*
X386000Y28000D03*
X338000Y30000D03*
Y44000D03*
X355362Y84370D03*
Y93819D03*
X359862Y81319D03*
Y66319D03*
X323500Y73300D03*
X340750Y80500D03*
X335200Y80700D03*
X359862Y51319D03*
X366862Y27697D03*
X341800Y63700D03*
X311800Y83700D03*
X301750Y65500D03*
X340650Y69300D03*
X327500Y87500D03*
X332500D03*
X337500D03*
X322500D03*
X359862Y161319D03*
Y151319D03*
X344000Y186000D03*
X337500Y162700D03*
X298000Y140500D03*
X359862Y131319D03*
X357506Y123493D03*
X355362Y103268D03*
X375500Y119400D03*
X312750Y98500D03*
X322000Y120500D03*
X321500Y133000D03*
X293700Y105500D03*
X298500D03*
X302999Y105501D03*
X379500Y119500D03*
X324000Y196000D03*
X366862Y199941D03*
X358000Y318000D03*
X294542Y372300D03*
X320000Y422000D03*
X336000Y466000D03*
X384000Y468000D03*
X305775Y398909D03*
X301525Y400900D03*
X294561Y400682D03*
X320514Y397600D03*
X315514D03*
X295090Y463289D03*
X338000Y498000D03*
X355362Y556024D03*
Y537126D03*
Y546575D03*
X312750Y551000D03*
X359862Y534075D03*
Y519075D03*
Y504075D03*
X366862Y480453D03*
X335200Y533200D03*
X323500Y525800D03*
X340750Y533000D03*
X341800Y516800D03*
X312750Y536300D03*
X299104Y556943D03*
X303604D03*
X308104D03*
X301750Y518000D03*
X344000Y525300D03*
X322500Y540000D03*
X337500D03*
X332500D03*
X327500D03*
X324000Y650000D03*
X359862Y614075D03*
X366862Y652697D03*
X344000Y638500D03*
X337500Y615200D03*
X359862Y604075D03*
Y584075D03*
X374261Y572963D03*
X322000Y573000D03*
X323380Y589452D03*
X298000Y593000D03*
X334000Y686000D03*
X342000Y758000D03*
X350000Y850000D03*
Y800000D03*
X301525Y853600D03*
X305775Y851609D03*
X294561Y853382D03*
X294542Y825000D03*
X320526Y850100D03*
X315526D03*
X337500Y946500D03*
X359500Y925400D03*
X330000Y1010500D03*
X304500Y1028500D03*
X359862Y1036831D03*
Y1026831D03*
X322000Y1026000D03*
X321200Y1038500D03*
X298000Y1046000D03*
X358800Y955900D03*
X355362Y1008780D03*
Y989882D03*
Y999331D03*
X359862Y986831D03*
Y971831D03*
X335200Y986200D03*
X323500Y978800D03*
X312750Y1004000D03*
X340750Y986000D03*
X341900Y969400D03*
X307500Y1011000D03*
X303000D03*
X298500D03*
X312750Y993000D03*
X302100Y978200D03*
X376000Y993000D03*
X344200Y978200D03*
X322500Y993000D03*
X337500D03*
X332500D03*
X327500D03*
X318000Y1058000D03*
X326000Y1106000D03*
X366862Y1105453D03*
X359862Y1066831D03*
Y1056831D03*
X344000Y1091500D03*
X337500Y1068200D03*
X300000Y1200000D03*
Y1150000D03*
X373492Y1317441D03*
Y1322441D03*
Y1327441D03*
Y1332441D03*
X343688Y1317736D03*
Y1322736D03*
Y1327736D03*
Y1332736D03*
X313688D03*
Y1327736D03*
Y1322736D03*
Y1317736D03*
Y1312736D03*
X369086Y1313208D03*
X374086D03*
X379086D03*
X384086D03*
X324086D03*
X329086D03*
X334086D03*
X339086D03*
X344086D03*
X349086D03*
X354086D03*
X359086D03*
X364086D03*
X294086D03*
X299086D03*
X304086D03*
X309086D03*
X319086D03*
X350000Y1400000D03*
X373492Y1337441D03*
Y1342441D03*
Y1347441D03*
Y1352441D03*
X343688Y1337736D03*
Y1342736D03*
Y1347736D03*
Y1352736D03*
X313688D03*
Y1347736D03*
Y1342736D03*
Y1337736D03*
X323688Y1357736D03*
X328688D03*
X333688D03*
X338688D03*
X343688D03*
X348688D03*
X353688D03*
X358688D03*
X363688D03*
X368688D03*
X373688D03*
X378688D03*
X383688D03*
X298688D03*
X303688D03*
X308688D03*
X313688D03*
X318688D03*
X293688D03*
X300000Y1400000D03*
X410679Y31098D03*
X414000Y58000D03*
X402000Y64000D03*
X454000Y83800D03*
X479574Y84370D03*
Y93819D03*
X462100Y62940D03*
X450300Y71700D03*
X425500Y72600D03*
X435500D03*
X430500D03*
X440500D03*
X468500Y80500D03*
X465500Y38250D03*
X425500Y41250D03*
X430500D03*
X434804Y41242D03*
X444663Y32417D03*
X440400Y32400D03*
X464000Y80500D03*
X446400Y91100D03*
X456900D03*
X461900D03*
X451900D03*
X467500Y116000D03*
X394000Y164000D03*
Y174000D03*
X462000Y162700D03*
X468000Y186000D03*
X422000Y140500D03*
X479574Y103268D03*
X441300Y126000D03*
X445500Y133000D03*
X440849Y111648D03*
X437500Y134500D03*
X441500D03*
X433500D03*
X430083Y122357D03*
X388000Y196000D03*
X416000D03*
X400000Y350000D03*
X415542Y378932D03*
X419042Y372000D03*
X428000Y430000D03*
X460000Y468000D03*
X426025Y400700D03*
X419061Y400382D03*
X430275Y399351D03*
X445014Y397600D03*
X440014D03*
X402000Y560000D03*
X388000Y548000D03*
X410000Y544000D03*
X392000Y490000D03*
X460000Y496000D03*
X479574Y556024D03*
Y537126D03*
Y546575D03*
X436750Y551000D03*
X459200Y533200D03*
X446993Y527868D03*
X464750Y533000D03*
X466000Y516900D03*
X436750Y538400D03*
X422500Y558000D03*
X427000D03*
X431500D03*
X429210Y512992D03*
X464801Y521156D03*
X446500Y540000D03*
X461500D03*
X456500D03*
X451500D03*
X410000Y616000D03*
X468000Y638500D03*
X467029Y610775D03*
X441641Y574141D03*
X445546Y586021D03*
X421820Y593641D03*
X389250Y575500D03*
X390632Y588624D03*
X422000Y684000D03*
X454000Y686000D03*
X466000Y762000D03*
X400000Y800000D03*
X425725Y853400D03*
X429975Y851409D03*
X418761Y853082D03*
X415242Y831882D03*
X418742Y824444D03*
X440026Y850100D03*
X445026D03*
X387500Y939000D03*
X462000Y947000D03*
X428500Y1028500D03*
X454000Y1010500D03*
X407000Y984000D03*
X389500Y1009000D03*
X446000Y1026000D03*
X445100Y1038500D03*
X389250Y1028500D03*
X422000Y1046000D03*
X459200Y986200D03*
X447500Y978800D03*
X436750Y1004000D03*
X464750Y986000D03*
X479574Y1008780D03*
Y989882D03*
Y999331D03*
X466100Y969200D03*
X431500Y1011000D03*
X427000D03*
X422500D03*
X436750Y993000D03*
X426300Y976800D03*
X389250Y1039250D03*
X468300Y978000D03*
X446500Y993000D03*
X461500D03*
X456500D03*
X451500D03*
X448000Y1106000D03*
X410000Y1068000D03*
X468000Y1091500D03*
X462000Y1068200D03*
X450000Y1150000D03*
Y1200000D03*
X389086Y1313208D03*
X394086D03*
X390500Y1386000D03*
X388688Y1357736D03*
X393688D03*
X532000Y90000D03*
X534000Y58000D03*
X512000Y28000D03*
X572000Y73300D03*
X484074Y81319D03*
Y66319D03*
Y51319D03*
X491074Y27697D03*
X561250Y87500D03*
X550250Y65500D03*
X576000Y87500D03*
X571000D03*
X556000Y156000D03*
X568000Y190000D03*
X544000Y160000D03*
X502500Y139500D03*
X512000Y104000D03*
X546500Y140500D03*
X484074Y161319D03*
Y151319D03*
X561250Y98500D03*
X570500Y120500D03*
X569900Y133000D03*
X499900Y119400D03*
X484074Y131319D03*
Y121319D03*
X547000Y105500D03*
X551500D03*
X556000D03*
X503900Y119500D03*
X534000Y222500D03*
X493000Y218500D03*
X491074Y199941D03*
X539742Y379232D03*
X543242Y372300D03*
Y400682D03*
X550225Y400900D03*
X554475Y399651D03*
X569014Y397600D03*
X564014D03*
X516000Y488000D03*
X574000D03*
X524000Y560000D03*
X561250Y551000D03*
X572000Y525800D03*
X484074Y504075D03*
X491074Y480453D03*
X483513Y535912D03*
X484074Y519075D03*
X561250Y540000D03*
X550250Y518000D03*
X571000Y540000D03*
X576000D03*
X536000Y644000D03*
X510000Y656000D03*
X491074Y652697D03*
X484074Y614075D03*
X565279Y578552D03*
X569900Y585500D03*
X551276Y597925D03*
X483265Y606243D03*
X484074Y584075D03*
Y574075D03*
X513250Y574252D03*
X516000Y637413D03*
X546500Y572000D03*
X551044Y572149D03*
X555321Y572375D03*
X517999Y583015D03*
X552000Y686000D03*
X542000Y764000D03*
X500000Y800000D03*
Y850000D03*
X564026Y850100D03*
X569026D03*
X512000Y939000D03*
X483549Y925564D03*
X513500Y1009000D03*
X532000Y983000D03*
X553000Y1028500D03*
X570500Y1026000D03*
X569900Y1038500D03*
X546500Y1046000D03*
X513250Y1028500D03*
X484074Y1036831D03*
Y1026831D03*
X572000Y978800D03*
X561250Y1004000D03*
X499800Y956831D03*
X484074Y986831D03*
Y971831D03*
X556000Y1011000D03*
X551500D03*
X547000D03*
X561250Y993000D03*
X550700Y979500D03*
X513250Y1039250D03*
X500000Y992000D03*
X571000Y993000D03*
X576000D03*
X534000Y1068000D03*
X550000Y1100000D03*
X491074Y1105453D03*
X484074Y1066831D03*
Y1056831D03*
X500000Y1150000D03*
X550000D03*
Y1200000D03*
X500000D03*
X522000Y1294000D03*
X505224Y1424156D03*
X523455Y1416564D03*
X524236Y1463672D03*
X542066Y1440238D03*
X537466D03*
X532866D03*
X528798Y1437733D03*
X524722Y1436362D03*
X528500Y1444600D03*
X507250Y1478000D03*
X535200Y1466100D03*
X523500Y1455400D03*
X503001Y1454922D03*
X513624Y1458624D03*
X504000Y1470500D03*
X503035Y1444331D03*
X528250Y1470900D03*
X496500Y1476000D03*
X508867Y1497771D03*
X585500Y45000D03*
X650000Y84000D03*
X578000Y52000D03*
X592500Y28000D03*
X603787Y84370D03*
Y93819D03*
X608287Y81319D03*
Y66319D03*
X589250Y80500D03*
X583700Y80700D03*
X608287Y51319D03*
X615287Y27697D03*
X590600Y64300D03*
X670500Y80000D03*
X589150Y69500D03*
X581000Y87500D03*
X586000D03*
X638000Y104000D03*
X654000Y162500D03*
X664500Y97000D03*
X579000Y105000D03*
X670500Y140500D03*
X608287Y161319D03*
Y151319D03*
X592500Y186000D03*
X586000Y162700D03*
X608287Y131319D03*
Y121319D03*
X603787Y103268D03*
X624000Y119400D03*
X626000Y140000D03*
X628000Y119500D03*
X652000Y214000D03*
X582500Y266000D03*
X615287Y199941D03*
X586500Y292000D03*
X643000Y317500D03*
X614500Y318500D03*
X639000Y354500D03*
X602500Y365000D03*
X650742Y378932D03*
X654242Y372000D03*
X661225Y400738D03*
X654261Y400382D03*
X665475Y399378D03*
X638000Y488000D03*
X644000Y558000D03*
X603787Y556024D03*
Y537126D03*
Y546575D03*
X608287Y534075D03*
Y519075D03*
Y504075D03*
X615287Y480453D03*
X589250Y533000D03*
X583700Y533200D03*
X583550Y504600D03*
X672018Y557014D03*
X592500Y525300D03*
X586000Y540000D03*
X581000D03*
X664651Y513000D03*
X671000Y648000D03*
X672500Y615500D03*
X615287Y652697D03*
X622687Y614091D03*
X592500Y638500D03*
X586043Y615962D03*
X670500Y593000D03*
X622703Y604103D03*
X623005Y584047D03*
X608287Y574075D03*
X637750Y575500D03*
X666900Y665400D03*
X637750Y586250D03*
X590000Y680000D03*
X646680Y679430D03*
X600000Y770000D03*
X650000D03*
X624000Y846000D03*
X579148Y832411D03*
X666625Y853400D03*
X670875Y851409D03*
X589805Y854600D03*
X594055Y852609D03*
X659661Y853082D03*
X582667Y853605D03*
X656142Y831632D03*
X582648Y825223D03*
X659642Y824700D03*
X585000Y948000D03*
X636000Y939000D03*
X615287Y933209D03*
X585904Y900960D03*
X589904D03*
X593904D03*
X597904D03*
X601904D03*
X673000Y885500D03*
X578000Y1010500D03*
X652500Y984500D03*
X625000Y1014500D03*
X653500Y997500D03*
X670500Y1046000D03*
X637750Y1028500D03*
X608287Y1036831D03*
Y1026831D03*
X601800Y955500D03*
X589250Y986000D03*
X603787Y1008780D03*
Y989882D03*
Y999331D03*
X608287Y986831D03*
Y971831D03*
X583700Y986200D03*
X590200Y969500D03*
X671000Y1011000D03*
X624500Y993000D03*
X592800Y978100D03*
X586000Y993000D03*
X581000D03*
X599000Y1115500D03*
X631500Y1112500D03*
X660000Y1068000D03*
X615287Y1105453D03*
X592500Y1091500D03*
X608287Y1066831D03*
Y1056831D03*
X586000Y1068200D03*
X672000Y1146000D03*
X670000Y1196000D03*
X646102Y1321750D03*
X641102D03*
X668000Y1418900D03*
X672000Y1419000D03*
X646200Y1420576D03*
X641200D03*
X637971Y1425400D03*
X657836Y1433318D03*
X658000Y1449200D03*
X653000Y1488500D03*
X665700Y1463500D03*
Y1468500D03*
X650000Y1464052D03*
Y1467948D03*
Y1457448D03*
Y1453552D03*
X636250Y1468500D03*
X628500D03*
X637972Y1441419D03*
X658000Y1444000D03*
X665700Y1458000D03*
Y1453000D03*
X624750Y1461250D03*
X729201Y87285D03*
X727636Y93834D03*
X732500Y81319D03*
Y66319D03*
X704000Y80500D03*
X699500Y82500D03*
X700300Y71700D03*
X712000Y62940D03*
X732500Y51319D03*
X739500Y27697D03*
X712214Y82500D03*
X680500Y80250D03*
X675500Y80000D03*
X697787Y74488D03*
X714000Y38250D03*
X695600Y34000D03*
X699932Y34034D03*
X709000Y79500D03*
X700000Y87500D03*
X705000D03*
X710000D03*
X694500D03*
X711352Y26875D03*
X715205Y27012D03*
X705171Y16254D03*
X681000Y171500D03*
X732500Y161319D03*
Y151319D03*
X716500Y186000D03*
X710300Y162700D03*
X747290Y118820D03*
X732500Y131319D03*
Y121319D03*
X728000Y103268D03*
X694500Y120500D03*
X694200Y133000D03*
X753473Y138459D03*
X714000Y240000D03*
X700000Y200000D03*
X732087Y207847D03*
X756000Y326000D03*
X718000Y332000D03*
X704500Y408500D03*
X685514Y397600D03*
X680514D03*
X716000Y568500D03*
X688000Y496000D03*
X728000Y556024D03*
Y537126D03*
Y546575D03*
X688298Y551625D03*
X732500Y504075D03*
X707700Y533200D03*
X696000Y525800D03*
X732500Y519075D03*
X713250Y533000D03*
X732500Y534075D03*
X724600Y487100D03*
X698600Y511100D03*
X685250Y540000D03*
X680902Y557860D03*
X676402D03*
X674250Y518000D03*
X714600Y498100D03*
X716400Y525200D03*
X695000Y540000D03*
X700000D03*
X705000D03*
X710000D03*
X747843Y612115D03*
X739500Y652697D03*
X710300Y635400D03*
Y615200D03*
X748200Y572200D03*
X732500Y574075D03*
X694200Y585500D03*
X732500Y584075D03*
X694500Y573000D03*
X746356Y604075D03*
X752200Y572300D03*
X710000Y760500D03*
X726500Y681500D03*
X693500Y680000D03*
X712000Y720000D03*
X709871Y686246D03*
X718100Y738500D03*
X718200Y744000D03*
X723000Y739200D03*
X723300Y743700D03*
X728175Y741300D03*
X728100Y745500D03*
X680526Y850100D03*
X685526D03*
X710000Y950500D03*
X739500Y933209D03*
X701700Y872700D03*
X714500Y870100D03*
X723600Y872400D03*
X712760Y915137D03*
X727600Y872300D03*
X733895Y901054D03*
X754000Y884524D03*
X757600Y884400D03*
X677000Y885500D03*
Y1028500D03*
X702500Y1010500D03*
X753050Y1028500D03*
X694500Y1026000D03*
X694000Y1038500D03*
X732500Y1036831D03*
Y1026831D03*
X730900Y955800D03*
X707700Y986200D03*
X696000Y978800D03*
X685250Y1004000D03*
X713250Y986000D03*
X728000Y1008780D03*
Y989882D03*
Y999331D03*
X732500Y986831D03*
Y971831D03*
X714400Y969600D03*
X680000Y1011000D03*
X675500D03*
X685250Y993000D03*
X675400Y980500D03*
X755200Y992400D03*
X716800Y978300D03*
X700000Y993000D03*
X705000D03*
X710000D03*
X695000D03*
X759249Y1008800D03*
X750000Y1084000D03*
X698000Y1102000D03*
X739500Y1105453D03*
X716500Y1091500D03*
X710300Y1068200D03*
X732500Y1066831D03*
Y1056831D03*
X759700Y1138600D03*
X759762Y1135000D03*
X738000Y1152000D03*
X740000Y1202000D03*
X748000Y1170000D03*
X746000Y1218000D03*
X700000Y1150000D03*
X698500Y1418900D03*
X693000Y1418800D03*
X689000Y1419000D03*
X681000Y1419100D03*
X685000Y1418900D03*
X703500Y1426000D03*
X676500Y1419500D03*
X742880Y1422632D03*
X739532Y1425934D03*
X720455Y1438500D03*
X684000Y1482000D03*
X699500Y1476000D03*
X685000Y1453500D03*
X690000Y1448500D03*
X695000Y1453500D03*
X690000Y1458500D03*
Y1453500D03*
X724248Y1465560D03*
X730500Y1451500D03*
X685850Y1468600D03*
X724000Y1439700D03*
X717600Y1449700D03*
X746832Y1451034D03*
X735232Y1439334D03*
X739332Y1462234D03*
X750867Y1438001D03*
X722200Y1476900D03*
X680900Y1469200D03*
X680200Y1465500D03*
X675550Y1458721D03*
Y1452216D03*
X692000Y1471156D03*
X689250Y1433500D03*
X681250D03*
X745000Y1463000D03*
X730341Y1446725D03*
X756332Y1465934D03*
X745032Y1468534D03*
X732232Y1477094D03*
X718900Y1472800D03*
X679800Y1483500D03*
X708600Y1469900D03*
X724066Y1461018D03*
X724255Y1457253D03*
X735232Y1451210D03*
X771500Y251000D03*
X802000Y263500D03*
X804500Y379000D03*
X769500Y431500D03*
X807500Y473700D03*
X835165Y470414D03*
X787971Y466121D03*
X791971D03*
X787971Y461921D03*
X791971D03*
X787971Y457721D03*
X791971D03*
X848799Y457202D03*
X849539Y453596D03*
X827313Y464805D03*
X827361Y459317D03*
X860519Y428234D03*
X860716Y417600D03*
X850947Y417592D03*
X812282Y448094D03*
X815255Y451343D03*
X808395Y454315D03*
X834000Y499000D03*
X858740Y486430D03*
X846950Y645820D03*
Y640820D03*
X822841Y662242D03*
X794883Y639984D03*
X798475Y640227D03*
X863430Y618590D03*
X788160Y666220D03*
X814320Y651120D03*
X813980Y647430D03*
X860360Y605900D03*
X836862Y637500D03*
X815148Y654937D03*
X824618Y614617D03*
X827750Y611798D03*
X791530Y614700D03*
X791680Y619050D03*
X799900Y636300D03*
X807440Y629910D03*
X802900Y634000D03*
X839400Y744920D03*
X859664Y683428D03*
X837709Y681095D03*
X789442Y681063D03*
X796200Y682400D03*
X791243Y668081D03*
X778627Y735644D03*
X778683Y745049D03*
X853900Y839200D03*
X833300Y856920D03*
X841309Y796644D03*
X841800Y804499D03*
X854973Y780437D03*
X810700Y776500D03*
X818162Y819005D03*
X810659Y767500D03*
X778735Y839888D03*
X791500Y764500D03*
X795300Y764900D03*
X826000Y857400D03*
X815469Y811029D03*
X815330Y807050D03*
X818113Y814998D03*
X834200Y796220D03*
X810700Y772000D03*
Y781000D03*
X858500Y845700D03*
X858100Y850000D03*
X848300Y847700D03*
X804200Y798200D03*
X811372Y795900D03*
X808372Y797900D03*
X805372Y801700D03*
X834470Y944430D03*
X842270Y942411D03*
X818434Y919985D03*
X820883Y879428D03*
X820900Y888500D03*
X825900Y862040D03*
X801300Y924300D03*
X799303Y927296D03*
X822463Y920345D03*
X842270Y936402D03*
X861300Y895300D03*
X819000Y896100D03*
X817337Y886075D03*
X815400Y892800D03*
X844800Y895902D03*
X845732Y891713D03*
X826000Y1004000D03*
X846500Y997500D03*
X827000Y985500D03*
X796301Y959795D03*
X822470Y981470D03*
X839970D03*
X834470D03*
X826470D03*
X848400Y974100D03*
X836953Y1023500D03*
X826000Y1062000D03*
X846500Y1055000D03*
X826000Y1094000D03*
Y1128000D03*
X844000Y1092000D03*
Y1128000D03*
X842700Y1071900D03*
X782712Y1211404D03*
Y1206904D03*
X772601Y1223511D03*
Y1219011D03*
Y1214511D03*
X777101Y1223511D03*
X832800Y1147500D03*
X795100Y1150400D03*
X798920Y1150500D03*
X821900Y1173700D03*
X773300Y1159700D03*
X769800Y1156500D03*
X776800Y1169700D03*
X780722Y1166357D03*
X780000Y1162800D03*
X859113Y1283983D03*
X822500Y1331000D03*
Y1298000D03*
Y1294000D03*
X860000Y1410843D03*
X842500Y1411343D03*
X852000Y1402000D03*
Y1406000D03*
X822500Y1373500D03*
Y1369500D03*
X835000Y1402500D03*
Y1398000D03*
X822500Y1335000D03*
X820000Y1448000D03*
X772361Y1451972D03*
X882823Y331182D03*
X909236Y333242D03*
X906486Y330524D03*
X910330Y363490D03*
X908340Y360430D03*
X909423Y354393D03*
X898059Y343029D03*
X902184Y347219D03*
X906616Y351586D03*
X922800Y362400D03*
X922700Y358100D03*
X945408Y378761D03*
X950843Y378827D03*
X871591Y431161D03*
X870400Y454315D03*
X867299Y493300D03*
Y497200D03*
X922525Y519833D03*
X873000Y494100D03*
X929096Y517567D03*
X873200Y487300D03*
X944387Y520100D03*
X941557Y547005D03*
X955000Y540800D03*
X935477Y524023D03*
X938338Y529107D03*
X938579Y551379D03*
X938623Y556600D03*
X956100Y516500D03*
X867299Y508600D03*
Y504700D03*
X935490Y519550D03*
X878740Y655190D03*
Y647190D03*
X884801Y630225D03*
X892400Y633700D03*
X878740Y643190D03*
Y651190D03*
X870200Y631500D03*
X867260Y608600D03*
X883030Y611940D03*
X878600Y615600D03*
X879600Y621600D03*
X878400Y626200D03*
X932986Y752682D03*
X874858Y757002D03*
X874706Y752583D03*
X905100Y777000D03*
X915580Y857420D03*
X942500Y797867D03*
X876255Y818998D03*
X880983Y804420D03*
X874500Y774500D03*
X936543Y762518D03*
X957500Y842400D03*
X944000D03*
X924484Y812558D03*
X921047Y811463D03*
X869989Y818847D03*
X931800Y791500D03*
X870001Y822862D03*
X934800Y795300D03*
X916855Y810934D03*
X909144Y803346D03*
X903700Y803200D03*
X912762Y792801D03*
X903221Y793938D03*
X912030Y787650D03*
X907800Y788700D03*
X913059Y810367D03*
X906166Y812784D03*
X902560Y813313D03*
X876862Y842155D03*
X881702Y838859D03*
X874593Y763800D03*
X874821Y767690D03*
X931380Y821500D03*
X935485Y821400D03*
X903572Y773740D03*
X931206Y845756D03*
X920170Y857430D03*
X903500Y769900D03*
X939500Y842400D03*
X924670Y857430D03*
X953000Y842400D03*
X911080Y857420D03*
X948500Y842400D03*
X881216Y813813D03*
X910807Y766589D03*
X904484Y786109D03*
X876256Y798895D03*
X874500Y779100D03*
X866655Y855100D03*
X870200Y852203D03*
X872600Y798700D03*
X943294Y838833D03*
X903300Y763200D03*
X879205Y873548D03*
X918369Y923258D03*
X914208Y924279D03*
X883072Y886211D03*
X889458Y907846D03*
X877877Y891277D03*
X940750Y886000D03*
X928250Y885250D03*
X934500Y885156D03*
X894317Y865406D03*
X890117D03*
X894317Y861206D03*
X890117D03*
X879667Y877303D03*
X884684Y877406D03*
X927260Y922470D03*
X909760Y925445D03*
X922760Y922470D03*
X958256Y894438D03*
X930310Y858550D03*
X879770Y868369D03*
X895500Y1038000D03*
X891600Y980000D03*
X888000D03*
X886400Y976500D03*
X893600D03*
X897200D03*
X895200Y980000D03*
X890000Y976500D03*
X944500Y1134500D03*
X952500D03*
X951500Y1117500D03*
X947000D03*
X943000D03*
X949500Y1114500D03*
X954500D03*
X956500Y1117500D03*
X948298Y1215500D03*
X943500Y1233000D03*
X951500D03*
X959500D03*
X957000Y1207500D03*
X953100Y1211400D03*
X953000Y1203600D03*
X904000Y1191700D03*
X877400D03*
X928500Y1220700D03*
X890500Y1201200D03*
X885930Y1210537D03*
X892460Y1211340D03*
X887200Y1216460D03*
X893200Y1203660D03*
X888825Y1208263D03*
X889965Y1213936D03*
X884677Y1219029D03*
X947700Y1185500D03*
X947500Y1233000D03*
X955500D03*
X926700Y1199000D03*
X952500Y1193300D03*
X884056Y1283981D03*
X871556D03*
X888000Y1424000D03*
X926000Y1420000D03*
X876500Y1410843D03*
X888776Y1402228D03*
X901435Y1402196D03*
X866500Y1392892D03*
X913935Y1402196D03*
X869937Y1400312D03*
X941559Y1408198D03*
Y1403198D03*
X866000Y1398000D03*
X945415Y1429318D03*
X945414Y1412818D03*
X866000Y1452000D03*
X900000Y1450000D03*
X944019Y1452220D03*
X1033046Y379981D03*
X1035000Y370500D03*
X1032924Y374988D03*
X1038067Y441886D03*
X1021890Y439717D03*
X965700Y519617D03*
X962118Y534117D03*
X988341Y563811D03*
X968200Y547200D03*
X985631Y559671D03*
X984197Y533383D03*
X991538Y522018D03*
X1000051Y547644D03*
X974530Y559550D03*
X974550Y563690D03*
X1003591Y552081D03*
X996998Y539555D03*
X971420Y537950D03*
X975910Y537770D03*
X990200Y544250D03*
X995213Y529837D03*
X998905Y529824D03*
X986638Y519684D03*
X991360Y529780D03*
X963870Y754152D03*
X964200Y855600D03*
X1009600Y851054D03*
X986471Y829716D03*
X1009950Y838000D03*
X1025636Y854819D03*
X962000Y842400D03*
X966861Y772518D03*
X1050774Y815327D03*
X1050650Y825420D03*
X1022838Y829101D03*
X1042545Y832026D03*
X1015950Y838000D03*
X1026932Y841614D03*
X1050082Y843729D03*
X993400Y833250D03*
X969926Y847638D03*
X971197Y775799D03*
X977676Y828513D03*
X1005272Y837091D03*
X1000827Y837072D03*
X973070Y828512D03*
X1012125Y925875D03*
X1025251Y893000D03*
X1025065Y896965D03*
X1028500Y879500D03*
X1014807Y899075D03*
X1015007Y895000D03*
X997083Y895935D03*
X986728Y891100D03*
X974120Y858920D03*
X976242Y884600D03*
X980442Y882900D03*
X993942D03*
X1027524Y948954D03*
X1039500Y891100D03*
X1037110Y859471D03*
X989100Y899600D03*
X972042Y884600D03*
X985542Y882900D03*
X989742D03*
X996938Y901170D03*
X1034200Y945000D03*
X1040200D03*
X1046272Y944928D03*
X1039500Y874700D03*
X1024129Y946152D03*
X1044800Y893750D03*
X1030862Y951946D03*
X1022080Y960728D03*
X1032361Y1114039D03*
X1021970Y1096850D03*
X960500Y1134500D03*
X982500Y1136500D03*
X986500Y1131500D03*
X1013231Y1089300D03*
X1001687Y1111499D03*
X961000Y1117500D03*
X1029500Y1104900D03*
X1030178Y1134165D03*
X1029000Y1122400D03*
X1020000Y1230000D03*
X971700Y1193100D03*
X963500Y1233000D03*
X967500D03*
X982500Y1217000D03*
Y1209000D03*
X960900Y1211400D03*
Y1203600D03*
X982500Y1144500D03*
X1026100Y1145996D03*
X1014500Y1153500D03*
X1012000Y1150000D03*
X1017500D03*
X1020000Y1153500D03*
X982500Y1201000D03*
Y1197000D03*
Y1213000D03*
Y1221000D03*
Y1225000D03*
Y1205000D03*
X964550Y1190200D03*
X1054918Y1330439D03*
Y1325739D03*
X1035943Y1424649D03*
X1031443Y1426899D03*
X1040127Y1422500D03*
X1033287Y1410500D03*
X1022818Y1393489D03*
X1024193Y1422899D03*
X1010943Y1413899D03*
X1005943Y1406700D03*
X975443Y1407700D03*
X992443Y1406700D03*
X1000443D03*
X988443D03*
X996443Y1406800D03*
X983943Y1407399D03*
X979443Y1406999D03*
X964810Y1421172D03*
X1037400Y1400600D03*
X1031400Y1399200D03*
X1054918Y1386039D03*
Y1353539D03*
Y1358239D03*
Y1381339D03*
X966985Y1393900D03*
X961857D03*
X996693Y1421399D03*
X988693D03*
X1047000Y1421800D03*
X1039900Y1417000D03*
X1038303Y1441709D03*
X1021818Y1470865D03*
X1021693Y1444649D03*
X993100Y1456550D03*
X1007618Y1477365D03*
X1013418Y1470865D03*
X1027288Y1467441D03*
X1034100Y1500564D03*
X1024175Y1482189D03*
X1002118Y1471365D03*
X998325Y1471434D03*
X992443Y1441399D03*
X1002443D03*
X997443Y1436399D03*
Y1446399D03*
Y1441399D03*
X965443Y1436399D03*
X987576Y1451454D03*
Y1455054D03*
X982343Y1446620D03*
Y1440115D03*
X961877Y1445347D03*
Y1441451D03*
X999443Y1458006D03*
X1049260Y1466691D03*
X1017618Y1470865D03*
X993830Y1471364D03*
X1017618Y1460865D03*
X1043606Y1437906D03*
X962136Y1431831D03*
X1033253Y1444649D03*
X1048553Y1448399D03*
X1035526Y1455899D03*
X1041176Y1455500D03*
X1020500Y1500014D03*
X1037550Y1475814D03*
X1089000Y217500D03*
X1150000Y250000D03*
X1100000D03*
X1098000Y378000D03*
X1136000D03*
X1100000Y350000D03*
Y300000D03*
X1150000D03*
X1144000Y418000D03*
X1136100Y460288D03*
X1147440Y473040D03*
X1143720Y468520D03*
X1143420Y472900D03*
X1139590Y468380D03*
X1139330Y472820D03*
X1135410Y468380D03*
X1135310Y472820D03*
X1130800Y472900D03*
X1131800Y446800D03*
X1136000Y446849D03*
X1092000Y448400D03*
X1088000Y448500D03*
X1103100Y457300D03*
X1095100Y455800D03*
X1113593Y476094D03*
X1093000Y502000D03*
X1149964Y481623D03*
X1102677Y487116D03*
X1119242Y477261D03*
X1083000Y620000D03*
X1095000D03*
X1112298Y618498D03*
X1134600Y618747D03*
X1118505Y658863D03*
X1114905Y658882D03*
X1129500Y619200D03*
X1138900Y584900D03*
X1125025Y621993D03*
X1056116Y697100D03*
X1057826Y680233D03*
X1059927Y688329D03*
X1064216Y683751D03*
X1067554Y694447D03*
X1071179Y682315D03*
X1112682Y681223D03*
X1107674Y677776D03*
X1141230Y673825D03*
X1103770Y675413D03*
X1075706Y941261D03*
X1141370Y905550D03*
X1058800Y893750D03*
X1130000Y994000D03*
X1106000D03*
X1138000Y970000D03*
X1093588Y972000D03*
X1110600Y964200D03*
X1108500Y960600D03*
X1104600Y967800D03*
X1101950Y962900D03*
X1101600Y953700D03*
X1087962Y959252D03*
X1084000Y1092000D03*
X1130000Y1154000D03*
X1078000Y1166000D03*
X1080000Y1230000D03*
X1068569Y1191530D03*
X1072931Y1191482D03*
X1072900Y1204500D03*
X1084571Y1200129D03*
X1072600Y1211400D03*
X1084400Y1204200D03*
X1121346Y1315676D03*
Y1319676D03*
X1100625Y1292025D03*
X1107000Y1323500D03*
X1083100Y1305600D03*
X1082080Y1299375D03*
X1126820Y1288500D03*
X1075030Y1323078D03*
X1078850Y1287900D03*
X1082080Y1309495D03*
X1123000Y1297600D03*
X1096280Y1288150D03*
X1092475Y1287971D03*
X1133480Y1296700D03*
Y1291700D03*
X1121346Y1307385D03*
Y1311385D03*
X1117000Y1332500D03*
Y1328500D03*
X1072120Y1299375D03*
Y1304495D03*
Y1309495D03*
Y1292460D03*
X1114000Y1430000D03*
X1105100Y1351000D03*
Y1355000D03*
X1124612Y1388773D03*
X1130112Y1363273D03*
X1138112D03*
X1132112Y1380773D03*
X1114112Y1363273D03*
X1118112D03*
X1126112D03*
X1099112Y1387273D03*
Y1379273D03*
X1110512Y1403273D03*
X1067712Y1384766D03*
X1099112Y1391273D03*
X1099100Y1375200D03*
X1099112Y1383273D03*
X1099100Y1371200D03*
X1117362Y1406073D03*
X1134112Y1363273D03*
X1122112D03*
X1091000Y1393500D03*
X1086646Y1396419D03*
X1126112Y1401773D03*
X1130873Y1490848D03*
Y1495848D03*
X1238000Y164000D03*
X1236500Y216000D03*
X1200000Y250000D03*
X1218000Y344000D03*
X1225600Y368700D03*
X1200000Y300000D03*
X1190000Y466000D03*
X1184000Y440000D03*
X1206000Y430500D03*
X1160900Y468500D03*
X1156110Y473330D03*
X1152600Y468470D03*
X1245567Y420602D03*
X1243500Y393600D03*
X1201000Y447000D03*
X1200500Y452000D03*
X1169000Y511500D03*
X1150900Y485100D03*
X1177100Y495300D03*
X1167000Y586500D03*
X1232490Y664290D03*
X1236690D03*
X1171700Y603700D03*
X1172500Y599700D03*
X1169125Y581776D03*
X1166550Y579200D03*
X1177350Y597792D03*
X1188000Y753500D03*
X1212587Y740895D03*
Y736695D03*
Y732495D03*
X1232490Y668490D03*
X1212587Y728295D03*
X1236690Y668490D03*
X1212587Y724095D03*
X1232490Y672690D03*
X1212587Y719895D03*
X1236690Y672690D03*
X1206414Y704261D03*
X1209931Y701608D03*
X1207468Y697962D03*
X1210283Y695565D03*
X1212587Y749295D03*
Y745095D03*
X1232490Y685290D03*
X1179129Y672187D03*
X1232490Y681090D03*
X1180000Y832000D03*
Y848000D03*
X1217089Y846182D03*
X1224088Y844900D03*
X1213611Y831932D03*
X1228344Y852351D03*
X1190995Y776395D03*
X1186690Y791440D03*
X1217111Y825000D03*
X1173990Y797760D03*
X1177300Y804960D03*
X1180520Y790880D03*
X1179690Y798020D03*
X1200337Y912300D03*
X1200407Y918060D03*
X1157556Y932754D03*
X1184778Y912848D03*
X1180090Y896524D03*
X1181550Y906100D03*
X1184750Y889200D03*
Y896300D03*
X1240000Y1070000D03*
X1176000D03*
X1200000Y1100000D03*
X1155600Y1074500D03*
X1178000Y1214000D03*
X1200000Y1200000D03*
Y1150000D03*
X1223730Y1285803D03*
X1230600D03*
X1235600D03*
X1216894Y1318783D03*
Y1314783D03*
X1202394Y1285803D03*
X1197394D03*
X1190524D03*
X1183894Y1319783D03*
Y1315783D03*
X1193894Y1292533D03*
X1227100D03*
X1205624D03*
X1238830D03*
X1185324Y1286563D03*
X1220450Y1292533D03*
X1216894Y1304283D03*
Y1308283D03*
X1183894Y1304783D03*
Y1308783D03*
X1196000Y1366000D03*
X1212000D03*
X1242000Y1412000D03*
X1236600Y1346763D03*
X1232100D03*
X1217100D03*
X1183894D03*
X1203394D03*
X1198894D03*
X1178712Y1372573D03*
X1200962Y1413023D03*
X1209819Y1417377D03*
X1188894Y1346763D03*
X1222000Y1346700D03*
X1180614Y1340033D03*
X1213820D03*
X1243768Y1376953D03*
X1208394Y1346763D03*
X1193894D03*
X1227100D03*
X1203312Y1402793D03*
X1241600Y1346763D03*
X1169412Y1396873D03*
X1226000Y1436000D03*
X1238000Y1444000D03*
X1190000Y1494000D03*
X1156000D03*
X1200000Y1450000D03*
X1326000Y92000D03*
X1298655Y59926D03*
X1282106Y81319D03*
Y66319D03*
X1299800Y56000D03*
X1278038Y93821D03*
X1278698Y84340D03*
X1307200Y45000D03*
X1289106Y27697D03*
X1282106Y51319D03*
X1303500Y35000D03*
X1297000Y68500D03*
X1319100Y47400D03*
X1308000Y35000D03*
X1309500Y76500D03*
X1314500D03*
X1299500D03*
X1304500D03*
X1261100Y16600D03*
X1264700Y16400D03*
X1262000Y174000D03*
X1313000Y185500D03*
X1314000Y150500D03*
X1282106Y161319D03*
Y151319D03*
X1302500Y152000D03*
X1305000Y185500D03*
X1298500D03*
X1282106Y131319D03*
Y121319D03*
X1266600Y119500D03*
X1262468Y103268D03*
X1256800Y132400D03*
X1322500Y113500D03*
X1317500D03*
X1327000D03*
X1262600Y119700D03*
X1272500Y213000D03*
X1307500Y205000D03*
X1338000Y225000D03*
X1289106Y199941D03*
X1252000Y358000D03*
X1294500Y331500D03*
X1278500Y313000D03*
X1259445Y379019D03*
X1337824Y379176D03*
X1262945Y377600D03*
X1294624Y358802D03*
X1317500Y435500D03*
X1316000Y419000D03*
X1269926Y400687D03*
X1262964Y400469D03*
X1281693Y473218D03*
X1274396Y407915D03*
X1247949Y423302D03*
X1250648Y425686D03*
X1245959Y435527D03*
X1265295Y421223D03*
X1257000Y434600D03*
X1248500Y393600D03*
X1298500Y562500D03*
X1317500Y533500D03*
X1277606Y546575D03*
Y556024D03*
Y537126D03*
X1307500Y501500D03*
X1299900Y534200D03*
X1311200Y511500D03*
X1282106Y519075D03*
Y534075D03*
Y504075D03*
X1303800Y522500D03*
X1327000Y487000D03*
X1325500Y504750D03*
X1323000Y566500D03*
X1318000D03*
X1328000D03*
X1300100Y530000D03*
X1326500Y514000D03*
X1312000Y501500D03*
X1272182Y571361D03*
X1334500Y549500D03*
Y554500D03*
Y539500D03*
Y544500D03*
X1318000Y660000D03*
X1332000Y646000D03*
X1312973Y643128D03*
X1282106Y614075D03*
X1273979Y652690D03*
X1305000Y638500D03*
X1298000Y638300D03*
X1314000Y603500D03*
X1282106Y574075D03*
Y604075D03*
Y584075D03*
X1302500Y605000D03*
X1272211Y575575D03*
X1254000Y748000D03*
X1312000Y812000D03*
X1278000Y810000D03*
X1250000Y820000D03*
X1337824Y832935D03*
X1247588Y842190D03*
X1310000Y860000D03*
X1270000Y868000D03*
X1274000Y933209D03*
X1325500Y907000D03*
X1298000Y1014000D03*
X1318000Y986000D03*
X1266000Y1046000D03*
X1252000Y1010000D03*
X1266400Y1024700D03*
X1282106Y1036831D03*
Y1026831D03*
X1300600Y986800D03*
X1307500Y954000D03*
X1311200Y964000D03*
X1282106Y956831D03*
X1303800Y975000D03*
X1277606Y1008780D03*
Y999331D03*
Y989882D03*
X1282106Y986831D03*
Y971831D03*
X1325500Y957250D03*
X1323000Y1019000D03*
X1318000D03*
X1328000D03*
X1300900Y981800D03*
X1326500Y966500D03*
X1262400Y1024700D03*
X1312000Y954000D03*
X1260000Y993500D03*
X1334500Y1002000D03*
Y1007000D03*
Y992000D03*
Y997000D03*
X1266000Y1128000D03*
X1264000Y1082000D03*
X1250000Y1100000D03*
X1289106Y1105453D03*
X1314000Y1056000D03*
X1313000Y1091000D03*
X1298500D03*
X1302500Y1057500D03*
X1305000Y1091000D03*
X1282106Y1066831D03*
Y1056831D03*
X1250000Y1200000D03*
Y1150000D03*
X1288000Y1296000D03*
X1274000Y1314000D03*
X1300000Y1388000D03*
X1274000Y1374000D03*
X1318540Y1424331D03*
X1273874Y1423000D03*
X1314375Y1424375D03*
X1327900Y1416500D03*
X1266914Y1394873D03*
X1258187Y1389753D03*
X1281624Y1409209D03*
X1253165Y1384633D03*
X1246949Y1379513D03*
X1263642Y1392313D03*
X1261224Y1387193D03*
X1277624Y1409209D03*
X1250347Y1382073D03*
X1306625Y1434000D03*
X1303874Y1453750D03*
X1292374Y1452500D03*
X1301534Y1431345D03*
X1289124Y1430700D03*
X1253374Y1459300D03*
X1260874Y1481400D03*
X1264774Y1470700D03*
X1266574Y1452300D03*
X1289574Y1483700D03*
X1252674Y1496800D03*
X1266474Y1487500D03*
X1278574Y1488700D03*
X1282374Y1445500D03*
Y1464000D03*
X1296374Y1430700D03*
X1297089Y1450307D03*
X1322000Y1430700D03*
X1284624Y1476400D03*
X1253374Y1470000D03*
X1260574Y1445600D03*
X1256474Y1446000D03*
X1432000Y30000D03*
X1358000Y91000D03*
X1406319Y66319D03*
Y81319D03*
X1401819Y93819D03*
Y84370D03*
X1435200Y58500D03*
X1427800Y69500D03*
X1406319Y51319D03*
X1413319Y27697D03*
X1431500Y48500D03*
X1435750Y73750D03*
X1436000Y48500D03*
X1392500Y173000D03*
X1389000Y148500D03*
X1422000Y98000D03*
X1346000Y179000D03*
X1351500Y144500D03*
X1406319Y151319D03*
Y161319D03*
X1426500Y152000D03*
X1422500Y185500D03*
X1429000D03*
X1406319Y121319D03*
Y131319D03*
X1401819Y103268D03*
X1391200Y119500D03*
X1376700Y136000D03*
X1394200Y113700D03*
X1428000Y238000D03*
X1388500Y230000D03*
X1394000Y249000D03*
X1397937Y199951D03*
X1373000Y234500D03*
X1388000Y378000D03*
X1400000Y350000D03*
X1341324Y372244D03*
X1378000Y430000D03*
X1376000Y414000D03*
X1436500Y430000D03*
X1341343Y400626D03*
X1348305Y400844D03*
X1352557Y399595D03*
X1367514Y397100D03*
X1362514D03*
X1384000Y554000D03*
X1352000Y516000D03*
X1432000Y482000D03*
X1364000Y492000D03*
X1401819Y546575D03*
Y556024D03*
Y537126D03*
X1406319Y534075D03*
Y519075D03*
Y504075D03*
X1413319Y480453D03*
X1424400Y534200D03*
X1431500Y501500D03*
X1435200Y511500D03*
X1427800Y522500D03*
X1424500Y529100D03*
X1436000Y501500D03*
X1345215Y533601D03*
X1382000Y592000D03*
X1384000Y646000D03*
X1358000Y600000D03*
X1413319Y652697D03*
X1406319Y614075D03*
X1422500Y638500D03*
X1429000D03*
X1406319Y604075D03*
Y584075D03*
Y574075D03*
X1394110Y575530D03*
X1426500Y605000D03*
X1383952Y573102D03*
X1430000Y752000D03*
X1346000Y704000D03*
X1382000Y688000D03*
X1384000Y782000D03*
X1400000Y850000D03*
X1348305Y853600D03*
X1341343Y853382D03*
X1352557Y852351D03*
X1341324Y825000D03*
X1367500Y851922D03*
X1362500D03*
X1413319Y933209D03*
X1342000Y976000D03*
X1356000Y998000D03*
X1424100Y987000D03*
X1391000Y1024800D03*
X1406319Y1036831D03*
Y1026831D03*
Y956831D03*
X1431500Y954000D03*
X1435200Y964000D03*
X1427800Y975000D03*
X1401819Y1008780D03*
Y999331D03*
Y989882D03*
X1406319Y986831D03*
Y971831D03*
X1424400Y982000D03*
X1386900Y1024600D03*
X1383200Y992700D03*
X1436000Y954000D03*
X1360000Y1054000D03*
X1350000Y1100000D03*
X1413319Y1105453D03*
X1426500Y1057500D03*
X1422500Y1091000D03*
X1429000D03*
X1406319Y1066831D03*
Y1056831D03*
X1350000Y1150000D03*
X1400000D03*
Y1200000D03*
X1350000D03*
X1366000Y1388000D03*
X1347400Y1416200D03*
X1406000Y1444000D03*
X1474000Y78000D03*
X1508000Y36000D03*
X1468000Y42000D03*
X1482000Y66000D03*
X1530531Y66319D03*
Y81319D03*
X1526031Y93819D03*
Y84370D03*
X1439500Y81000D03*
X1530531Y51319D03*
X1450500Y61000D03*
X1458500Y86500D03*
Y91500D03*
X1508500Y102500D03*
X1441100Y130800D03*
X1494000Y98000D03*
X1484000Y158000D03*
X1530531Y151319D03*
X1526823Y161308D03*
X1437000Y185500D03*
X1438000Y150500D03*
X1530531Y121319D03*
Y131319D03*
X1526031Y103268D03*
X1515400Y119400D03*
X1501300Y136100D03*
X1447000Y113500D03*
X1442000D03*
X1452000D03*
X1511400Y119500D03*
X1458500Y96500D03*
Y101500D03*
X1523100Y193700D03*
X1502000Y196000D03*
X1457500Y289000D03*
X1508500Y292500D03*
X1450000Y350000D03*
X1462036Y379176D03*
X1465536Y372244D03*
X1484000Y432000D03*
X1476769Y399595D03*
X1465555Y400626D03*
X1472517Y400844D03*
X1492014Y397100D03*
X1487014D03*
X1442500Y532000D03*
X1480000Y546000D03*
X1510000Y488000D03*
X1476000Y518000D03*
X1526031Y546575D03*
Y556024D03*
Y537126D03*
X1530531Y534075D03*
Y519075D03*
Y504075D03*
X1449500Y504750D03*
X1447000Y566500D03*
X1442000D03*
X1452000D03*
X1450500Y514000D03*
X1458500Y544500D03*
Y539500D03*
Y554500D03*
Y549500D03*
X1451800Y583800D03*
X1498000Y586000D03*
X1490000Y598000D03*
X1500000Y640000D03*
X1460000Y646000D03*
X1530531Y614075D03*
X1437000Y638500D03*
X1530531Y604075D03*
Y584075D03*
Y574075D03*
X1515200Y572200D03*
X1438000Y603500D03*
X1511200Y572300D03*
X1508000Y748000D03*
X1472517Y853600D03*
X1465555Y853382D03*
X1462036Y831932D03*
X1476769Y852351D03*
X1465536Y825000D03*
X1493500Y853100D03*
X1487000Y851600D03*
X1443992Y904962D03*
X1442500Y984500D03*
X1478000Y976000D03*
X1480000Y1020000D03*
X1515400Y1025000D03*
X1530531Y1036831D03*
Y1026831D03*
Y956831D03*
X1526031Y1008780D03*
Y999331D03*
Y989882D03*
X1530531Y986831D03*
Y971831D03*
X1450100Y959500D03*
X1447000Y1019000D03*
X1442000D03*
X1452000D03*
X1450500Y966500D03*
X1511400Y1024600D03*
X1506000Y993000D03*
X1458500Y1002000D03*
Y1007000D03*
Y992000D03*
Y997000D03*
X1500000Y1100000D03*
X1530531Y1066831D03*
Y1056831D03*
X1437000Y1091000D03*
X1438000Y1056000D03*
X1450000Y1150000D03*
X1500000D03*
Y1200000D03*
X1450000D03*
X1500000Y1300000D03*
X1450000D03*
Y1350000D03*
X1500000D03*
Y1450000D03*
X1450000D03*
X1594000Y56000D03*
X1574000Y26000D03*
X1608000Y62000D03*
Y50000D03*
X1549300Y56000D03*
X1548500Y62900D03*
X1553000Y35000D03*
X1556700Y45000D03*
X1537531Y27697D03*
X1548279Y69309D03*
X1575400Y50750D03*
X1557500Y35000D03*
X1549000Y76500D03*
X1554000D03*
X1564000D03*
X1559000D03*
X1593500Y160500D03*
X1546000Y112000D03*
X1547000Y156222D03*
Y185500D03*
X1562500Y150500D03*
X1561500Y185500D03*
X1553500Y189500D03*
X1625300Y136000D03*
X1596400Y135600D03*
Y131100D03*
Y126100D03*
X1598000Y206000D03*
X1568000Y204000D03*
X1592000Y236000D03*
X1616100Y203786D03*
X1550000Y350000D03*
X1586249Y379176D03*
X1589749Y372244D03*
X1553500Y431500D03*
X1604000Y432500D03*
X1600982Y399595D03*
X1596730Y400844D03*
X1589768Y400626D03*
X1611014Y397100D03*
X1616014D03*
X1566500Y533000D03*
X1604000Y536000D03*
X1594000Y506000D03*
X1558000Y482000D03*
X1559700Y511500D03*
X1556000Y501500D03*
X1548600Y534900D03*
X1552300Y522500D03*
X1537531Y480453D03*
X1574000Y504750D03*
X1571500Y566500D03*
X1566500D03*
X1576500D03*
X1548400Y528800D03*
X1575000Y514000D03*
X1560500Y501500D03*
X1583000Y544500D03*
Y539500D03*
Y554500D03*
Y549500D03*
X1570100Y583800D03*
X1568000Y660000D03*
X1584000Y648000D03*
X1553500Y638500D03*
X1561500Y639860D03*
X1537500Y656000D03*
X1551000Y605000D03*
X1562500Y603500D03*
X1602000Y684000D03*
X1566000Y772000D03*
X1550000Y850000D03*
X1596730Y853600D03*
X1589768Y853382D03*
X1586249Y831932D03*
X1597000Y857500D03*
X1591400Y825000D03*
X1616000Y850100D03*
X1611000D03*
X1599000Y941000D03*
X1579000Y940000D03*
X1564000Y876000D03*
X1537531Y933209D03*
X1572900Y902900D03*
X1604000Y1022000D03*
X1544000Y1004500D03*
X1566500Y985500D03*
X1600500Y975000D03*
X1612000Y980000D03*
X1548900Y987600D03*
X1556000Y954000D03*
X1559700Y964000D03*
X1552300Y975000D03*
X1574000Y957250D03*
X1571500Y1019000D03*
X1566500D03*
X1576500D03*
X1575000Y966500D03*
X1548900Y981500D03*
X1560500Y954000D03*
X1583000Y997000D03*
Y992000D03*
Y1007000D03*
Y1002000D03*
X1561500Y1091000D03*
X1553500D03*
X1600000Y1100000D03*
X1537531Y1105453D03*
X1551000Y1057500D03*
X1547000Y1091000D03*
X1562500Y1056000D03*
X1600000Y1200000D03*
Y1150000D03*
X1550000Y1300000D03*
X1600000D03*
X1550000Y1350000D03*
X1600000D03*
Y1450000D03*
X1550000D03*
X1718000Y66000D03*
X1680000Y26000D03*
X1632000D03*
X1676300Y69500D03*
X1683700Y58500D03*
X1686730Y80991D03*
X1654744Y66319D03*
Y81319D03*
X1650244Y93819D03*
Y84370D03*
X1680000Y48500D03*
X1654744Y51319D03*
X1661744Y27697D03*
X1699000Y61000D03*
X1672900Y76400D03*
X1684500Y48500D03*
X1692200Y86200D03*
Y91200D03*
X1636000Y176000D03*
X1677500Y185500D03*
X1686500Y150500D03*
X1675000Y152000D03*
X1654744Y151319D03*
Y161319D03*
X1685500Y185500D03*
X1654744Y121319D03*
X1653206Y134559D03*
X1650244Y103268D03*
X1639300Y119500D03*
X1690400Y114100D03*
X1695400D03*
X1700400D03*
X1635300Y119600D03*
X1692300Y96100D03*
X1707000Y103500D03*
X1648000Y212000D03*
X1682000Y206000D03*
X1661744Y199941D03*
X1671003Y190635D03*
X1712525Y191268D03*
X1650000Y380000D03*
X1638500Y311500D03*
X1715000Y305500D03*
X1648000Y468000D03*
X1714000Y391000D03*
X1721762Y458436D03*
Y454436D03*
X1696359Y452707D03*
X1689359D03*
X1691859Y460207D03*
X1687359Y457207D03*
X1681859Y452707D03*
X1709496Y463382D03*
X1717859Y463907D03*
X1714026Y464191D03*
X1708359Y449207D03*
X1706859Y445207D03*
X1682000Y484000D03*
X1720000Y506000D03*
X1650244Y546575D03*
Y556024D03*
Y537126D03*
X1654744Y534075D03*
Y519075D03*
Y504075D03*
X1661744Y480453D03*
X1680000Y501500D03*
X1673200Y535100D03*
X1683700Y511500D03*
X1676300Y522500D03*
X1698000Y504750D03*
X1695500Y566500D03*
X1690500D03*
X1700500D03*
X1673200Y529000D03*
X1699000Y514000D03*
X1684500Y501500D03*
X1707083Y543435D03*
Y538435D03*
X1706800Y556300D03*
X1706935Y548158D03*
X1706000Y646000D03*
X1632000Y648000D03*
X1634000Y618000D03*
X1661744Y652697D03*
X1654744Y614075D03*
X1671000Y638500D03*
X1685500D03*
X1677500D03*
X1654744Y604075D03*
Y584075D03*
X1652808Y574040D03*
X1686500Y603500D03*
X1675000Y605000D03*
X1638200Y572200D03*
X1634200D03*
X1700000Y700000D03*
X1650000D03*
Y750000D03*
X1700000D03*
X1650000Y850000D03*
X1720942Y853600D03*
X1713980Y853382D03*
X1710461Y831932D03*
X1713961Y825000D03*
X1690200Y937700D03*
X1718000Y938000D03*
X1716000Y878000D03*
X1661800Y933400D03*
X1709500Y900700D03*
X1668000Y1004000D03*
X1690500Y986000D03*
X1672800Y987300D03*
X1639100Y1024900D03*
X1654744Y1036831D03*
Y1026831D03*
Y956831D03*
X1676300Y975000D03*
X1683700Y964000D03*
X1680000Y954000D03*
X1650244Y1008780D03*
Y999331D03*
Y989882D03*
X1654744Y986831D03*
Y971831D03*
X1698000Y957250D03*
X1695500Y1019000D03*
X1690500D03*
X1700500D03*
X1699000Y966500D03*
X1672800Y981200D03*
X1635100Y1024700D03*
X1631500Y994000D03*
X1684500Y954000D03*
X1707000Y997000D03*
Y992000D03*
Y1007000D03*
Y1002000D03*
X1638000Y1082000D03*
X1696000Y1106000D03*
X1661744Y1105453D03*
X1677500Y1091000D03*
X1686500Y1056000D03*
X1671000Y1091000D03*
X1675000Y1057500D03*
X1685500Y1091000D03*
X1654744Y1066831D03*
Y1056831D03*
X1650000Y1150000D03*
X1700000D03*
Y1200000D03*
X1650000D03*
Y1300000D03*
X1676511Y1292495D03*
X1674000Y1410000D03*
X1650000Y1350000D03*
X1669376Y1429200D03*
X1651906Y1428973D03*
X1719726Y1402700D03*
X1716026Y1416500D03*
X1663906Y1428973D03*
X1659906D03*
X1694751Y1434000D03*
X1683926Y1453750D03*
X1672626Y1452500D03*
X1686226Y1432500D03*
X1656250Y1461250D03*
X1662626Y1464000D03*
Y1445500D03*
X1674926Y1447400D03*
X1676626Y1432000D03*
X1702501Y1434000D03*
X1661626Y1480000D03*
X1756000Y25500D03*
X1730000Y58000D03*
X1811700Y59550D03*
X1808600Y78200D03*
X1803500Y82200D03*
X1778956Y66319D03*
Y81319D03*
X1774456Y93819D03*
Y84370D03*
X1785956Y27697D03*
X1778956Y51319D03*
X1795600Y44900D03*
X1817500Y32700D03*
X1814850Y21500D03*
X1799094Y82033D03*
X1811600Y32800D03*
X1794300Y63400D03*
X1796300Y85600D03*
X1806300D03*
X1811300D03*
X1801300D03*
X1803620Y57000D03*
X1807500Y57400D03*
X1730500Y177500D03*
X1730000Y136000D03*
X1746000Y106000D03*
X1809500Y185500D03*
X1801500D03*
X1811305Y147994D03*
X1799000Y152000D03*
X1795000Y185500D03*
X1778956Y151319D03*
Y161319D03*
Y121319D03*
Y131319D03*
X1774456Y103268D03*
X1763600Y119400D03*
X1749700Y135600D03*
X1759600Y119500D03*
X1804000Y205000D03*
X1724000Y232000D03*
X1754000Y234000D03*
X1750000Y200000D03*
X1785956Y199941D03*
X1768000Y310000D03*
X1781500Y366000D03*
X1801642Y379532D03*
X1805142Y372600D03*
X1724000Y422000D03*
X1745737Y400643D03*
X1800436Y412804D03*
X1804436D03*
X1809633Y420927D03*
Y416927D03*
X1795433D03*
Y420927D03*
X1759904Y400647D03*
X1812123Y401200D03*
X1805142Y400982D03*
X1814359Y473207D03*
X1725596Y447182D03*
X1729596Y443182D03*
X1725596D03*
X1729596Y455182D03*
X1725596D03*
X1729596Y459182D03*
X1725596D03*
Y451182D03*
X1729596Y447182D03*
Y451182D03*
X1731710Y475473D03*
X1749952Y405830D03*
X1764168Y405501D03*
X1816375Y399951D03*
X1723896Y474582D03*
X1753631Y405830D03*
X1735014Y397100D03*
X1740014D03*
X1740906Y465239D03*
X1746859Y465707D03*
X1724096Y464344D03*
X1813700Y548300D03*
X1796000Y566500D03*
X1728000Y554000D03*
X1757200Y558900D03*
X1730000Y568000D03*
X1809559Y482507D03*
Y486507D03*
X1795359D03*
Y482507D03*
X1800556Y490630D03*
X1804556D03*
X1774456Y556024D03*
X1767342Y533721D03*
X1774456Y546575D03*
X1785956Y480453D03*
X1804000Y501500D03*
X1807700Y511500D03*
X1800300Y522500D03*
X1798100Y537973D03*
X1785728Y538736D03*
X1778956Y519075D03*
Y504075D03*
X1814500Y566500D03*
X1797400Y528800D03*
X1742859Y484707D03*
X1808500Y501500D03*
X1818000Y656000D03*
X1762000Y628000D03*
X1756000Y646000D03*
X1785956Y652697D03*
X1795000Y638500D03*
X1801500D03*
X1809500D03*
X1778956Y614075D03*
X1810500Y603500D03*
X1799000Y605000D03*
X1778956Y604075D03*
Y584075D03*
Y574075D03*
X1759750Y576000D03*
Y587000D03*
X1758000Y748000D03*
X1756000Y684000D03*
X1808000Y848000D03*
X1760000Y846000D03*
X1800000Y800000D03*
X1725194Y852351D03*
X1740000Y850100D03*
X1735000D03*
X1778500Y917500D03*
X1738000Y904000D03*
X1796166Y892754D03*
Y888754D03*
X1785956Y933209D03*
X1804000Y885500D03*
Y881500D03*
X1800000Y885500D03*
Y893500D03*
X1804000D03*
X1800000Y889500D03*
X1804000D03*
X1800000Y877500D03*
X1804000D03*
X1800000Y881500D03*
X1806114Y909791D03*
X1770763Y887025D03*
X1763763D03*
X1766263Y894525D03*
X1761763Y891525D03*
X1756263Y887025D03*
X1798300Y908900D03*
X1817263Y919025D03*
X1815310Y899557D03*
X1783900Y897700D03*
X1792263Y898225D03*
X1798500Y898662D03*
X1788430Y898509D03*
X1782763Y883525D03*
X1781263Y879525D03*
X1794500Y1007000D03*
X1814500Y985500D03*
X1724000Y974000D03*
X1728000Y1002000D03*
X1796900Y987200D03*
X1763300Y1024800D03*
X1778956Y1036831D03*
Y1026831D03*
X1800300Y975000D03*
X1804000Y954000D03*
X1807700Y964000D03*
X1778956Y956831D03*
X1774456Y1008780D03*
Y999331D03*
Y989882D03*
X1778956Y986831D03*
Y971831D03*
X1814500Y1019000D03*
X1796900Y981100D03*
X1759300Y1024900D03*
X1808500Y954000D03*
X1756000Y993500D03*
X1730000Y1050000D03*
X1762000Y1080000D03*
X1785956Y1105453D03*
X1809500Y1091000D03*
X1801500D03*
X1810500Y1056000D03*
X1795000Y1091000D03*
X1799000Y1057500D03*
X1778956Y1066831D03*
Y1056831D03*
X1750000Y1150000D03*
Y1200000D03*
X1800000Y1300000D03*
Y1250000D03*
X1760000Y1394000D03*
X1800000Y1350000D03*
X1735126Y1416300D03*
X1790226Y1458600D03*
X1803426Y1452600D03*
X1804326Y1480500D03*
X1794226Y1473300D03*
X1810426Y1476200D03*
X1790226Y1469300D03*
X1800326Y1445800D03*
X1794426Y1446400D03*
X1820200Y70140D03*
X1898669Y93819D03*
Y84370D03*
X1903169Y66319D03*
Y81319D03*
X1885200Y81000D03*
X1871400Y82000D03*
X1903169Y51319D03*
X1910169Y27697D03*
X1887900Y41300D03*
X1878000Y29300D03*
X1884600Y49000D03*
X1821850Y35400D03*
X1824200Y23400D03*
Y19000D03*
X1868600Y68922D03*
X1872900Y49000D03*
X1870607Y75897D03*
X1823300Y88600D03*
X1845900Y77300D03*
X1840900D03*
X1850800Y77200D03*
X1860500Y38100D03*
X1863950Y45400D03*
X1859050Y19000D03*
X1885508Y77413D03*
X1891300Y49400D03*
X1880500Y48900D03*
X1842400Y29500D03*
X1875500Y87000D03*
X1880500D03*
X1865500D03*
X1870500D03*
X1851500Y171500D03*
X1867600Y104300D03*
X1903169Y151319D03*
Y161319D03*
X1881000Y162200D03*
X1883000Y181500D03*
X1841000Y140000D03*
X1903169Y121319D03*
Y131319D03*
X1898669Y103268D03*
X1860817Y120141D03*
X1864800Y132500D03*
X1834018Y169783D03*
X1823500Y113500D03*
X1819134Y109132D03*
X1819000Y113500D03*
X1840500Y237500D03*
X1850000Y200000D03*
X1900000Y250000D03*
X1910169Y199941D03*
X1829500Y311000D03*
X1900000Y300000D03*
Y350000D03*
X1830000Y424000D03*
X1838000Y415500D03*
X1850000Y400000D03*
X1900000D03*
Y450000D03*
X1818359Y473207D03*
X1822359D03*
X1826359D03*
X1830359D03*
X1834359D03*
X1827114Y397900D03*
X1832114D03*
X1836476Y467034D03*
X1884000Y488000D03*
X1854000Y482000D03*
X1875000Y558000D03*
X1898669Y546575D03*
Y556024D03*
Y537126D03*
X1883200Y534600D03*
X1855750Y551000D03*
X1903169Y534075D03*
Y519075D03*
Y504075D03*
X1910169Y480453D03*
X1866700Y512800D03*
X1866500Y507250D03*
X1859300Y524500D03*
X1822000Y504750D03*
X1848500Y504000D03*
X1819500Y566500D03*
X1824500D03*
X1855750Y540000D03*
X1839750Y530250D03*
X1841500Y558000D03*
X1846000D03*
X1850500D03*
X1823000Y514000D03*
X1883300Y530000D03*
X1853000Y504000D03*
X1870500Y540500D03*
X1865500D03*
X1880500D03*
X1875500D03*
X1831000Y544500D03*
Y539500D03*
Y554500D03*
Y549500D03*
X1851400Y623800D03*
X1850000Y650000D03*
X1910169Y652697D03*
X1903169Y614075D03*
X1880500Y615200D03*
X1887000Y638500D03*
X1903169Y604075D03*
Y584075D03*
Y574075D03*
X1865000Y573000D03*
X1864700Y585500D03*
X1841000Y593000D03*
X1846000Y686000D03*
X1900000Y750000D03*
Y700000D03*
Y800000D03*
X1874540Y847322D03*
X1878540D03*
X1883737Y855445D03*
Y851445D03*
X1869537D03*
Y855445D03*
X1849407Y852351D03*
X1845155Y853600D03*
X1838193Y853382D03*
X1834674Y831932D03*
X1838174Y825000D03*
X1859500Y850100D03*
X1864500D03*
X1883663Y917025D03*
Y921025D03*
X1874660Y925148D03*
X1878660D03*
X1869463Y921025D03*
Y917025D03*
X1910169Y933209D03*
X1888763Y907525D03*
X1892763D03*
X1896763D03*
X1900763D03*
X1904763D03*
X1908763D03*
X1820700Y940600D03*
X1848500Y940200D03*
X1828763Y865025D03*
X1821263Y900025D03*
X1872500Y1010500D03*
X1826000Y1036500D03*
X1864500Y1038500D03*
X1865000Y1026000D03*
X1903169Y1036831D03*
Y1026831D03*
X1841000Y1046000D03*
X1903169Y956831D03*
X1859600Y960250D03*
X1883100Y984750D03*
X1870800Y973100D03*
X1898669Y1008780D03*
Y999331D03*
Y989882D03*
X1903169Y986831D03*
Y971831D03*
X1855750Y1004000D03*
X1859300Y977500D03*
X1822000Y957250D03*
X1848500Y957000D03*
X1850500Y1011000D03*
X1846000D03*
X1841500D03*
X1819500Y1019000D03*
X1824500D03*
X1855750Y993000D03*
X1823000Y966500D03*
X1839750Y983000D03*
X1875800Y981000D03*
X1853000Y957000D03*
X1865500Y993000D03*
X1881814Y993136D03*
X1876814D03*
X1871814D03*
X1831000Y1002000D03*
Y1007000D03*
Y992000D03*
Y997000D03*
X1827600Y970700D03*
X1850000Y1078000D03*
X1910169Y1105453D03*
X1887000Y1091500D03*
X1880500Y1068200D03*
X1903169Y1066831D03*
Y1056831D03*
X1850000Y1200000D03*
X1900000D03*
Y1150000D03*
X1850000D03*
X1900000Y1300000D03*
X1850000D03*
X1900000Y1250000D03*
X1850000D03*
X1900000Y1400000D03*
X1850000D03*
Y1350000D03*
X1900000D03*
X1904000Y1504000D03*
X1878000Y1484000D03*
X1822000Y1444000D03*
X1900000Y1450000D03*
X1824826Y1470900D03*
X1822326Y1481600D03*
X1919000Y51000D03*
X1922400Y470400D03*
X1923600Y913525D03*
X1914500Y902000D03*
X1918800Y1112100D03*
G54D109*
G01X837390Y650110D02*
Y645840D01*
X837240Y645690D01*
G01X833200Y744920D02*
X839400D01*
G01X859590Y678270D02*
Y680954D01*
X859664Y681028D01*
Y683428D01*
G01X838400Y856920D02*
X833300D01*
G01X861100Y838080D02*
X854930D01*
X853900Y839110D01*
Y839200D01*
G01X855400Y773080D02*
X865630D01*
X867050Y774500D01*
G01X838900Y809920D02*
X834950Y805970D01*
Y804500D01*
G01X827550Y940330D02*
X830670D01*
X833820Y937180D01*
X834470D01*
G01X799390Y962530D02*
X796851D01*
X796301Y961980D01*
Y959795D01*
G01X947600Y797880D02*
X944080D01*
X944067Y797867D01*
X942500D01*
G01X889460Y902564D02*
Y907844D01*
X889458Y907846D01*
G01X920600Y1219020D02*
X926820D01*
X928500Y1220700D01*
G01X1178712Y1376953D02*
Y1372573D01*
G54D52*
X137501Y24706D03*
X134941D03*
X132381D03*
X129821D03*
Y40886D03*
X132381D03*
X134941D03*
X137501D03*
X799390Y940330D03*
X801950D03*
X804510D03*
X807070D03*
X809630D03*
X812190D03*
X814750D03*
X817310D03*
X819870D03*
X822430D03*
X824990D03*
X827550D03*
Y962530D03*
X824990D03*
X822430D03*
X819870D03*
X817310D03*
X814750D03*
X812190D03*
X809630D03*
X807070D03*
X804510D03*
X801950D03*
X799390D03*
X917620Y902564D03*
X915060D03*
X912500D03*
X909940D03*
X907380D03*
X904820D03*
X902260D03*
X899700D03*
X897140D03*
X894580D03*
X892020D03*
X889460D03*
Y880364D03*
X892020D03*
X894580D03*
X897140D03*
X899700D03*
X902260D03*
X904820D03*
X907380D03*
X909940D03*
X912500D03*
X915060D03*
X917620D03*
X946310Y861030D03*
X948870D03*
X951430D03*
X953990D03*
X956550D03*
Y883230D03*
X953990D03*
X951430D03*
X948870D03*
X946310D03*
X1002940Y856130D03*
X1005500D03*
X1008060D03*
X1010620D03*
X1013180D03*
X1015740D03*
X1018300D03*
X1020860D03*
X959110Y861030D03*
X961670D03*
X964230D03*
Y883230D03*
X961670D03*
X959110D03*
X1020860Y878330D03*
X1018300D03*
X1015740D03*
X1013180D03*
X1010620D03*
X1008060D03*
X1005500D03*
X1002940D03*
X1805021Y23406D03*
X1802461D03*
X1799901D03*
X1797341D03*
Y39586D03*
X1799901D03*
X1802461D03*
X1805021D03*
G54D61*
X111174Y1474560D03*
Y1472000D03*
Y1469440D03*
X118574D03*
Y1472000D03*
Y1474560D03*
X203300Y68060D03*
Y65500D03*
Y62940D03*
X210700D03*
Y65500D03*
Y68060D03*
X450300D03*
Y65500D03*
Y62940D03*
X457700D03*
Y65500D03*
Y68060D03*
X700300D03*
Y65500D03*
Y62940D03*
X707700D03*
Y65500D03*
Y68060D03*
X735932Y1459794D03*
Y1457234D03*
Y1454674D03*
X743332D03*
Y1457234D03*
Y1459794D03*
X1299800Y53060D03*
Y50500D03*
Y47940D03*
X1307200D03*
Y50500D03*
Y53060D03*
X1303800Y519560D03*
Y517000D03*
Y514440D03*
X1311200D03*
Y517000D03*
Y519560D03*
X1303800Y972060D03*
Y969500D03*
Y966940D03*
X1311200D03*
Y969500D03*
Y972060D03*
X1257374Y1478960D03*
Y1476400D03*
Y1473840D03*
X1264774D03*
Y1476400D03*
Y1478960D03*
X1427800Y66560D03*
Y64000D03*
Y61440D03*
X1435200D03*
Y64000D03*
Y66560D03*
X1427800Y519560D03*
Y517000D03*
Y514440D03*
X1435200D03*
Y517000D03*
Y519560D03*
X1427800Y972060D03*
Y969500D03*
Y966940D03*
X1435200D03*
Y969500D03*
Y972060D03*
X1549300Y53060D03*
Y50500D03*
Y47940D03*
X1556700D03*
Y50500D03*
Y53060D03*
X1552300Y519560D03*
Y517000D03*
Y514440D03*
X1559700D03*
Y517000D03*
Y519560D03*
X1552300Y972060D03*
Y969500D03*
Y966940D03*
X1559700D03*
Y969500D03*
Y972060D03*
X1676300Y66560D03*
Y64000D03*
Y61440D03*
X1683700D03*
Y64000D03*
Y66560D03*
X1676300Y519560D03*
Y517000D03*
Y514440D03*
X1683700D03*
Y517000D03*
Y519560D03*
X1676300Y972060D03*
Y969500D03*
Y966940D03*
X1683700D03*
Y969500D03*
Y972060D03*
X1808600Y75260D03*
Y72700D03*
Y70140D03*
X1816000D03*
Y72700D03*
Y75260D03*
X1800300Y519560D03*
Y517000D03*
Y514440D03*
X1807700D03*
Y517000D03*
Y519560D03*
X1800300Y972060D03*
Y969500D03*
Y966940D03*
X1807700D03*
Y969500D03*
Y972060D03*
X1866700Y516440D03*
Y519000D03*
Y521560D03*
X1859300D03*
Y519000D03*
Y516440D03*
X1866700Y969440D03*
Y972000D03*
Y974560D03*
X1859300D03*
Y972000D03*
Y969440D03*
G54D16*
X60000Y73200D03*
Y525700D03*
X81700Y905280D03*
X77563Y905225D03*
X60000Y978700D03*
X131600Y126100D03*
X179527Y467544D03*
X175390Y467489D03*
X184000Y525700D03*
X184500Y978700D03*
X138974Y1429100D03*
X149374Y1457200D03*
Y1438700D03*
X207000Y77200D03*
X217000Y45200D03*
X254900Y126300D03*
X308500Y73200D03*
X379500Y126300D03*
X308500Y525700D03*
Y978700D03*
X454000Y80600D03*
X465500Y45200D03*
X432500Y525700D03*
Y978700D03*
X557000Y73200D03*
X503900Y126200D03*
X557000Y525700D03*
Y978700D03*
X502999Y1451632D03*
X628000Y126200D03*
X583550Y516250D03*
X655795Y1429619D03*
X628500Y1464700D03*
X704000Y77200D03*
X714000Y45200D03*
X707800Y516900D03*
X681000Y525700D03*
X752200Y579000D03*
X681000Y978700D03*
X676500Y1479700D03*
X841939Y389815D03*
X846939D03*
X822470Y927630D03*
Y977630D03*
X830470D03*
X839970Y969870D03*
X955000Y547800D03*
X952100Y520000D03*
X922100Y760700D03*
X948500Y849200D03*
X953000D03*
X911080Y864070D03*
X918380Y919114D03*
X914260Y919070D03*
X951500Y1229700D03*
X868900Y1188200D03*
X888000Y1197300D03*
X986200Y547700D03*
X983300Y522000D03*
X966093Y849200D03*
X993942Y879500D03*
X976242Y881200D03*
X980442Y879500D03*
X1000500Y910700D03*
X1005500D03*
X959500Y1229700D03*
X963238Y1417518D03*
X998325Y1467634D03*
X1013618Y1467565D03*
X1043606Y1448349D03*
X975438Y1453608D03*
X1122112Y1369973D03*
X1134112D03*
X1114112D03*
X1118112D03*
X1138112D03*
X1203394Y1343483D03*
X1222100D03*
X1236600D03*
X1232100D03*
X1217100D03*
X1183894D03*
X1188894D03*
X1198894D03*
X1203487Y1424641D03*
X1308000Y41700D03*
X1318000D03*
X1317800Y54000D03*
X1311700Y69100D03*
X1313700Y54000D03*
X1262600Y126300D03*
X1312000Y508200D03*
X1322000D03*
X1326500Y520700D03*
X1322000D03*
X1262600Y579000D03*
X1262400Y1031700D03*
X1312000Y960700D03*
X1322000D03*
X1326500Y973200D03*
X1322000D03*
X1296374Y1457200D03*
Y1438700D03*
X1436000Y55200D03*
X1387200Y126300D03*
X1436000Y508200D03*
X1386400Y579000D03*
X1387000Y1031800D03*
X1436000Y960700D03*
X1446000Y55200D03*
X1450500Y67700D03*
X1446000D03*
X1511400Y126300D03*
X1446000Y508200D03*
X1450500Y520700D03*
X1446000D03*
X1511200Y579000D03*
X1446000Y960700D03*
X1450500Y973200D03*
X1446000D03*
X1511400Y1031800D03*
X1557500Y41700D03*
X1567500D03*
X1572000Y54200D03*
X1563500Y69200D03*
X1567500Y54200D03*
X1560500Y508200D03*
X1570500D03*
X1575000Y520700D03*
X1570500D03*
X1560500Y960700D03*
X1570500D03*
X1575000Y973200D03*
X1570500D03*
X1684500Y55200D03*
X1694500D03*
X1699000Y67700D03*
X1694500D03*
X1635300Y126300D03*
X1722296Y470962D03*
X1718159Y470907D03*
X1684500Y508200D03*
X1694500D03*
X1699000Y520700D03*
X1694500D03*
X1634200Y579000D03*
X1635100Y1031800D03*
X1684500Y960700D03*
X1694500D03*
X1699000Y973200D03*
X1694500D03*
X1676626Y1457200D03*
Y1438700D03*
X1759600Y126300D03*
X1808500Y508200D03*
X1792563Y905225D03*
X1796700Y905280D03*
X1759300Y1031800D03*
X1808500Y960700D03*
X1884600Y45700D03*
X1862300Y30000D03*
X1818500Y508200D03*
X1823000Y520700D03*
X1818500D03*
X1853000Y510700D03*
X1848500D03*
X1843000Y541200D03*
X1818500Y960700D03*
X1823000Y973200D03*
X1818500D03*
X1875800Y988200D03*
X1853000Y963700D03*
X1848500D03*
X1843000Y994200D03*
G54D43*
X51209Y393253D03*
X58709Y389378D03*
Y397128D03*
X38942Y845907D03*
X46442Y842032D03*
Y849782D03*
X185342Y392907D03*
X192842Y389032D03*
Y396782D03*
X160342Y840907D03*
X167842Y837032D03*
Y844782D03*
X287042Y393207D03*
Y845907D03*
X294542Y389332D03*
Y397082D03*
Y842032D03*
Y849782D03*
X411542Y392907D03*
X419042Y389032D03*
Y396782D03*
X411242Y845607D03*
X418742Y841732D03*
Y849482D03*
X535742Y393207D03*
X543242Y389332D03*
Y397082D03*
X575148Y846130D03*
X646742Y392907D03*
X654242Y389032D03*
Y396782D03*
X652142Y845607D03*
X659642Y841732D03*
Y849482D03*
X582648Y842255D03*
Y850005D03*
X1209611Y845907D03*
X1217111Y842032D03*
Y849782D03*
X1255445Y392994D03*
X1262945Y389119D03*
Y396869D03*
X1333824Y393151D03*
X1341324Y389276D03*
Y397026D03*
X1333824Y845907D03*
X1341324Y842032D03*
Y849782D03*
X1458036Y393151D03*
X1465536Y389276D03*
Y397026D03*
X1458036Y845907D03*
X1465536Y842032D03*
Y849782D03*
X1582249Y393151D03*
X1589749Y389276D03*
Y397026D03*
X1582249Y845907D03*
X1589749Y842032D03*
Y849782D03*
X1706461Y845907D03*
X1713961Y842032D03*
Y849782D03*
X1797642Y393507D03*
X1805142Y389632D03*
Y397382D03*
X1830674Y845907D03*
X1838174Y842032D03*
Y849782D03*
G54D25*
X100412Y6000D03*
X95412D03*
X90412D03*
X85412D03*
X80412D03*
X75412D03*
X70412D03*
X65412D03*
X60412D03*
X55412D03*
X50412D03*
X45412D03*
X40412D03*
X35412D03*
X30412D03*
X25412D03*
X20412D03*
X15412D03*
X10412D03*
X6000Y6588D03*
Y11588D03*
Y16588D03*
Y21588D03*
Y26588D03*
Y31588D03*
Y36588D03*
Y41588D03*
Y46588D03*
Y51588D03*
Y56588D03*
Y61588D03*
Y66588D03*
Y71588D03*
Y76588D03*
Y81588D03*
Y86588D03*
Y91588D03*
Y96588D03*
Y101588D03*
Y106588D03*
Y111588D03*
Y116588D03*
Y121588D03*
Y126588D03*
Y131588D03*
Y136588D03*
Y141588D03*
Y146588D03*
Y151588D03*
Y156588D03*
Y161588D03*
Y166588D03*
Y171588D03*
Y176588D03*
Y181588D03*
Y186588D03*
Y191588D03*
Y196588D03*
Y201588D03*
Y206588D03*
Y211588D03*
Y216588D03*
Y221588D03*
Y226588D03*
Y231588D03*
Y236588D03*
Y241588D03*
Y246588D03*
Y251588D03*
Y256588D03*
Y261588D03*
Y266588D03*
Y271588D03*
Y276588D03*
Y281588D03*
Y286588D03*
Y291588D03*
Y296588D03*
Y301588D03*
Y306588D03*
Y311588D03*
Y316588D03*
Y321588D03*
Y326588D03*
Y331588D03*
Y336588D03*
Y341588D03*
Y346588D03*
Y351588D03*
Y356588D03*
Y361588D03*
Y366588D03*
Y371588D03*
Y376588D03*
Y441588D03*
Y436588D03*
Y431588D03*
Y426588D03*
Y421588D03*
Y416588D03*
Y411588D03*
Y406588D03*
Y386588D03*
Y391588D03*
Y396588D03*
Y401588D03*
Y446588D03*
Y451588D03*
Y456588D03*
Y461588D03*
Y381588D03*
Y466588D03*
Y471588D03*
Y476588D03*
Y481588D03*
Y486588D03*
Y491588D03*
Y496588D03*
Y501588D03*
Y506588D03*
Y511588D03*
Y516588D03*
Y521588D03*
Y526588D03*
Y531588D03*
Y536588D03*
Y541588D03*
Y546588D03*
Y551588D03*
Y556588D03*
Y561588D03*
Y566588D03*
Y571588D03*
Y576588D03*
Y581588D03*
Y586588D03*
Y591588D03*
Y596588D03*
Y601588D03*
Y606588D03*
Y611588D03*
Y616588D03*
Y621588D03*
Y626588D03*
Y631588D03*
Y636588D03*
Y641588D03*
Y646588D03*
Y651588D03*
Y656588D03*
Y661588D03*
Y666588D03*
Y671588D03*
Y676588D03*
Y681588D03*
Y686588D03*
Y691588D03*
Y696588D03*
Y701588D03*
Y706588D03*
Y711588D03*
Y716588D03*
Y721588D03*
Y726588D03*
Y731588D03*
Y736588D03*
Y741588D03*
Y746588D03*
Y751588D03*
Y756588D03*
Y761588D03*
Y766588D03*
Y771588D03*
Y776588D03*
Y781588D03*
Y786588D03*
Y791588D03*
Y796588D03*
Y801588D03*
Y806588D03*
Y811588D03*
Y816588D03*
Y821588D03*
Y826588D03*
Y831588D03*
Y836588D03*
Y841588D03*
Y846588D03*
Y851588D03*
Y856588D03*
Y861588D03*
Y866588D03*
Y871588D03*
Y876588D03*
Y881588D03*
Y886588D03*
Y891588D03*
Y896588D03*
Y901588D03*
Y906588D03*
Y911588D03*
Y916588D03*
Y921588D03*
Y926588D03*
Y931588D03*
Y936588D03*
Y941588D03*
Y946588D03*
Y951588D03*
X26300Y873700D03*
Y864100D03*
Y868900D03*
X21500Y873700D03*
Y864100D03*
Y868900D03*
X6000Y956588D03*
Y961588D03*
Y966588D03*
Y971588D03*
Y976588D03*
Y981588D03*
Y986588D03*
Y991588D03*
Y996588D03*
Y1001588D03*
Y1006588D03*
Y1011588D03*
Y1016588D03*
Y1021588D03*
Y1026588D03*
Y1031588D03*
Y1036588D03*
Y1041588D03*
Y1046588D03*
Y1051588D03*
Y1056588D03*
Y1061588D03*
Y1066588D03*
Y1071588D03*
Y1076588D03*
Y1081588D03*
Y1086588D03*
Y1091588D03*
Y1096588D03*
Y1101588D03*
Y1106588D03*
Y1111588D03*
Y1116588D03*
Y1121588D03*
Y1126588D03*
Y1131588D03*
Y1136588D03*
Y1141588D03*
Y1146588D03*
Y1151588D03*
Y1156588D03*
Y1161588D03*
Y1166588D03*
Y1171588D03*
Y1176588D03*
Y1181588D03*
Y1186588D03*
Y1191588D03*
Y1196588D03*
Y1201588D03*
Y1206588D03*
Y1211588D03*
Y1216588D03*
Y1221588D03*
Y1226588D03*
Y1231588D03*
Y1236588D03*
Y1321588D03*
Y1326588D03*
Y1331588D03*
Y1286588D03*
Y1291588D03*
Y1296588D03*
Y1301588D03*
Y1306588D03*
Y1311588D03*
Y1316588D03*
Y1241588D03*
Y1246588D03*
Y1251588D03*
Y1256588D03*
Y1261588D03*
Y1266588D03*
Y1271588D03*
Y1276588D03*
Y1281588D03*
Y1421588D03*
Y1416588D03*
Y1411588D03*
Y1406588D03*
Y1401588D03*
Y1396588D03*
Y1391588D03*
Y1386588D03*
Y1381588D03*
Y1376588D03*
Y1371588D03*
Y1366588D03*
Y1361588D03*
Y1356588D03*
Y1351588D03*
Y1346588D03*
Y1341588D03*
Y1426588D03*
Y1336588D03*
Y1451588D03*
Y1446588D03*
Y1441588D03*
Y1436588D03*
Y1431588D03*
X99000Y1501000D03*
X61500Y1502000D03*
X87539Y1499118D03*
X82539D03*
X77539D03*
X72539D03*
X67539D03*
X92539D03*
X11000Y1455500D03*
X15500Y1458500D03*
X17811Y1462693D03*
Y1467693D03*
Y1472693D03*
Y1477693D03*
Y1482693D03*
Y1487693D03*
Y1492693D03*
Y1497693D03*
Y1502693D03*
Y1507693D03*
X17500Y1512000D03*
X21819Y1513685D03*
X26819D03*
X31819D03*
X36819D03*
X41819D03*
X46819D03*
X51819D03*
X56819D03*
X58500Y1508000D03*
X195412Y6000D03*
X190412D03*
X185412D03*
X180412D03*
X175412D03*
X170412D03*
X165412D03*
X160412D03*
X155412D03*
X150412D03*
X145412D03*
X140412D03*
X135412D03*
X130412D03*
X125412D03*
X120412D03*
X115412D03*
X110412D03*
X105412D03*
X127600Y437500D03*
Y432700D03*
X122800Y437500D03*
Y432700D03*
X127600Y427900D03*
X122800D03*
X169215Y876085D03*
Y880885D03*
X154215D03*
Y876085D03*
X169215Y895685D03*
Y890885D03*
X154215Y895685D03*
Y890885D03*
X164200Y885700D03*
X158900D03*
X192963Y888625D03*
Y883625D03*
X188163Y888625D03*
X183363D03*
X178563D03*
Y883625D03*
X173763D03*
Y888625D03*
X183363Y883625D03*
X188163D03*
X113363Y884925D03*
X180000Y1424000D03*
Y1430000D03*
X186000Y1424000D03*
Y1430000D03*
X152000Y1377000D03*
Y1383000D03*
X158000Y1377000D03*
Y1383000D03*
X170000D03*
Y1377000D03*
X164000Y1383000D03*
Y1377000D03*
X102000Y1505500D03*
X177433Y1513685D03*
X182433D03*
X187433D03*
X192433D03*
X147433D03*
X152433D03*
X157433D03*
X162433D03*
X167433D03*
X172433D03*
X103000Y1511000D03*
X107433Y1513685D03*
X112433D03*
X117433D03*
X122433D03*
X127433D03*
X132433D03*
X137433D03*
X142433D03*
X290412Y6000D03*
X285412D03*
X280412D03*
X275412D03*
X270412D03*
X265412D03*
X260412D03*
X255412D03*
X250412D03*
X245412D03*
X240412D03*
X235412D03*
X230412D03*
X225412D03*
X220412D03*
X215412D03*
X210412D03*
X205412D03*
X200412D03*
X251200Y457900D03*
Y438300D03*
Y443100D03*
Y453100D03*
X291500Y451100D03*
Y446100D03*
X286700D03*
Y451100D03*
X281900D03*
Y446100D03*
X272300D03*
Y451100D03*
X277100Y446100D03*
Y451100D03*
X267752Y458160D03*
Y438560D03*
Y443360D03*
Y453360D03*
X257127Y448364D03*
X261927D03*
X211590Y427289D03*
X211190Y447189D03*
X197763Y888625D03*
Y883625D03*
X233074Y1429500D03*
X239274Y1429600D03*
X237235Y1419039D03*
X236974Y1425000D03*
X283000Y1492000D03*
X279000Y1498500D03*
X197433Y1513685D03*
X202433D03*
X207433D03*
X212433D03*
X217433D03*
X222433D03*
X227433D03*
X232433D03*
X237433D03*
X242433D03*
X247433D03*
X252433D03*
X257433D03*
X262433D03*
X267433D03*
X272433D03*
X277433D03*
X278646Y1509398D03*
Y1504398D03*
X288685Y1490063D03*
X385412Y6000D03*
X380412D03*
X375412D03*
X370412D03*
X365412D03*
X360412D03*
X355412D03*
X350412D03*
X345412D03*
X340412D03*
X335412D03*
X330412D03*
X325412D03*
X320412D03*
X315412D03*
X310412D03*
X305412D03*
X300412D03*
X295412D03*
X296300Y446100D03*
Y451100D03*
X380780Y1428599D03*
Y1422599D03*
Y1416599D03*
Y1410599D03*
X374780Y1428599D03*
Y1422599D03*
Y1416599D03*
Y1410599D03*
X293685Y1490063D03*
X298685D03*
X303685D03*
X308685D03*
X313685D03*
X318685D03*
X323685D03*
X328685D03*
X333685D03*
X338685D03*
X343685D03*
X348685D03*
X353685D03*
X358685D03*
X363685D03*
X368685D03*
X373685D03*
X378685D03*
X383685D03*
X380780Y1434599D03*
X374780D03*
X480412Y6000D03*
X475412D03*
X470412D03*
X465412D03*
X460412D03*
X455412D03*
X450412D03*
X445412D03*
X440412D03*
X435412D03*
X430412D03*
X425412D03*
X420412D03*
X415412D03*
X410412D03*
X405412D03*
X400412D03*
X395412D03*
X390412D03*
X388685Y1490063D03*
X393685D03*
X398685D03*
X403685D03*
X408685D03*
X413685D03*
X418685D03*
X423685D03*
X428685D03*
X433685D03*
X438685D03*
X443685D03*
X448685D03*
X453685D03*
X458685D03*
X463685D03*
X468685D03*
X473685D03*
X478685D03*
X575412Y6000D03*
X570412D03*
X565412D03*
X560412D03*
X555412D03*
X550412D03*
X545412D03*
X540412D03*
X535412D03*
X530412D03*
X525412D03*
X520412D03*
X515412D03*
X510412D03*
X505412D03*
X500412D03*
X495412D03*
X490412D03*
X485412D03*
X501000Y1494000D03*
X503000Y1499000D03*
X494500Y1490500D03*
X574937Y1513685D03*
X569937D03*
X564937D03*
X559937D03*
X554937D03*
X549937D03*
X544937D03*
X539937D03*
X534937D03*
X529937D03*
X524937D03*
X483685Y1490063D03*
X488685D03*
X503244Y1504378D03*
Y1509378D03*
X504937Y1513685D03*
X509937D03*
X514937D03*
X519937D03*
X513917Y1447297D03*
X507917D03*
X519717D03*
X670412Y6000D03*
X665412D03*
X660412D03*
X655412D03*
X650412D03*
X645412D03*
X640412D03*
X635412D03*
X630412D03*
X625412D03*
X620412D03*
X615412D03*
X610412D03*
X605412D03*
X600412D03*
X595412D03*
X590412D03*
X585412D03*
X580412D03*
X669937Y1513685D03*
X659937D03*
X654937D03*
X649937D03*
X644937D03*
X639937D03*
X634937D03*
X629937D03*
X624937D03*
X619937D03*
X614937D03*
X609937D03*
X604937D03*
X599937D03*
X594937D03*
X589937D03*
X584937D03*
X579937D03*
X664937D03*
X765412Y6000D03*
X760412D03*
X755412D03*
X750412D03*
X745412D03*
X740412D03*
X735412D03*
X730412D03*
X725412D03*
X720412D03*
X715412D03*
X710412D03*
X705412D03*
X700412D03*
X695412D03*
X690412D03*
X685412D03*
X680412D03*
X675412D03*
X722000Y1503500D03*
X718500Y1500000D03*
X680500Y1503500D03*
X674937Y1513685D03*
X688012Y1499118D03*
X693012D03*
X698012D03*
X703012D03*
X708012D03*
X713012D03*
X724000Y1509500D03*
X725551Y1513685D03*
X730551D03*
X735551D03*
X740551D03*
X745551D03*
X750551D03*
X755551D03*
X760551D03*
X765551D03*
X678500Y1510500D03*
X777465Y93947D03*
Y88947D03*
Y83947D03*
Y78947D03*
Y73947D03*
Y68947D03*
Y63947D03*
Y58947D03*
Y53947D03*
Y48947D03*
Y43947D03*
Y38947D03*
Y33947D03*
Y28947D03*
Y23947D03*
Y18947D03*
Y13947D03*
X778000Y9500D03*
X775412Y6000D03*
X770412D03*
X777465Y183947D03*
Y178947D03*
Y173947D03*
Y168947D03*
Y163947D03*
Y158947D03*
Y153947D03*
Y148947D03*
Y143947D03*
Y138947D03*
Y133947D03*
Y128947D03*
Y123947D03*
Y118947D03*
Y113947D03*
Y108947D03*
Y103947D03*
Y98947D03*
X809500Y197500D03*
X805522Y195764D03*
X808961Y201678D03*
Y206678D03*
Y211678D03*
Y216678D03*
Y236678D03*
Y231678D03*
Y226678D03*
Y221678D03*
Y241678D03*
X779022Y190764D03*
X784022Y194764D03*
X800522Y195764D03*
X795522D03*
X790522D03*
X826843Y409096D03*
Y404296D03*
Y399496D03*
X822043D03*
Y404296D03*
Y409096D03*
X807643Y408996D03*
Y404196D03*
Y399396D03*
X802843D03*
Y404196D03*
Y408996D03*
X826843Y419764D03*
Y424564D03*
Y429364D03*
X802843Y419664D03*
X807643D03*
X822043Y419764D03*
X802843Y429264D03*
Y424464D03*
X807643D03*
Y429264D03*
X822043Y429364D03*
Y424564D03*
X822400Y567100D03*
Y562300D03*
Y557500D03*
X817600D03*
Y562300D03*
Y567100D03*
X803200Y557400D03*
Y562200D03*
Y567000D03*
X798400Y557400D03*
Y562200D03*
Y567000D03*
X822400Y587368D03*
Y582568D03*
X817600D03*
Y587368D03*
X803200Y587268D03*
Y582468D03*
X798400D03*
Y587268D03*
X822400Y577768D03*
X817600D03*
X803200Y577668D03*
X798400D03*
X808300Y1197300D03*
X813100D03*
Y1206900D03*
Y1202100D03*
X808300D03*
Y1206900D03*
X794100Y1197300D03*
X789300D03*
X794100Y1202100D03*
Y1206900D03*
X789300Y1202100D03*
Y1206900D03*
X808300Y1227168D03*
Y1222368D03*
X813100D03*
Y1227168D03*
X794100D03*
Y1222368D03*
X789300D03*
Y1227168D03*
X813100Y1217568D03*
X808300D03*
X789300D03*
X794100D03*
X779500Y1491000D03*
X775000Y1495500D03*
X770551Y1513685D03*
X773528Y1510662D03*
Y1505662D03*
Y1500662D03*
X786803Y1490063D03*
X791803D03*
X796803D03*
X801803D03*
X806803D03*
X811803D03*
X816803D03*
X821803D03*
X826803D03*
X831803D03*
X836803D03*
X841803D03*
X846803D03*
X851803D03*
X856803D03*
X861803D03*
X887127Y254031D03*
X944200Y1083100D03*
X938900Y1103700D03*
X938800Y1109300D03*
X945200Y1398300D03*
Y1393500D03*
X950200Y1394500D03*
X866803Y1490063D03*
X871803D03*
X876803D03*
X881803D03*
X886803D03*
X891803D03*
X896803D03*
X901803D03*
X906803D03*
X911803D03*
X916803D03*
X921803D03*
X926803D03*
X931803D03*
X936803D03*
X941803D03*
X946803D03*
X951803D03*
X956803D03*
X1012000Y371369D03*
X1015537Y365911D03*
X1038200Y762300D03*
X1021194Y766883D03*
X1035594Y766983D03*
X1040394D03*
X1021194Y771683D03*
Y776483D03*
X1035594Y776583D03*
Y771783D03*
X1040394D03*
Y776583D03*
X1016394Y766883D03*
Y776483D03*
Y771683D03*
X997000Y1496000D03*
X993000Y1491500D03*
X961803Y1490063D03*
X966803D03*
X971803D03*
X976803D03*
X981803D03*
X986803D03*
X998126Y1503614D03*
Y1508614D03*
Y1513614D03*
X1003126D03*
X1008126D03*
X1013126D03*
X1018126D03*
X1023126D03*
X1028126D03*
X1033126D03*
X1038126D03*
X1043126D03*
X1048126D03*
X1053126D03*
X1068734Y195764D03*
X1064500Y197500D03*
X1065055Y201895D03*
Y206895D03*
Y211895D03*
Y216895D03*
Y226895D03*
Y231895D03*
Y236895D03*
Y241895D03*
Y221895D03*
X1148734Y195764D03*
X1143734D03*
X1138734D03*
X1133734D03*
X1128734D03*
X1123734D03*
X1118734D03*
X1113734D03*
X1103734D03*
X1098734D03*
X1093734D03*
X1088734D03*
X1083734D03*
X1078734D03*
X1073734D03*
X1075627Y374973D03*
X1075829Y380885D03*
X1119877Y408072D03*
Y403272D03*
Y398472D03*
X1124677D03*
Y403272D03*
Y408072D03*
X1100677Y407972D03*
Y403172D03*
Y398372D03*
X1105477D03*
Y403172D03*
Y407972D03*
X1119877Y423540D03*
Y428340D03*
Y418740D03*
X1124677Y428340D03*
Y423540D03*
Y418740D03*
X1105477Y428240D03*
Y423440D03*
X1100677D03*
Y428240D03*
X1105477Y418640D03*
X1100677D03*
X1076142Y386839D03*
X1057400Y771600D03*
X1057600Y776500D03*
X1067200Y786500D03*
X1062400D03*
Y781500D03*
X1057600Y786500D03*
Y781500D03*
X1067200Y791500D03*
X1062400D03*
X1067200Y796500D03*
X1062400D03*
X1057600D03*
Y791500D03*
X1128700Y1206500D03*
X1133500D03*
Y1201700D03*
X1128700D03*
X1133500Y1196900D03*
X1128700D03*
X1109600Y1197100D03*
X1114400D03*
X1109600Y1201900D03*
X1114400D03*
Y1206700D03*
X1109600D03*
X1128500Y1225700D03*
X1133300D03*
X1109400Y1221100D03*
X1114200D03*
Y1225900D03*
X1109400D03*
X1133300Y1220900D03*
X1128500D03*
X1133300Y1216100D03*
X1128500D03*
X1109400Y1216300D03*
X1114200D03*
X1087933Y1411323D03*
X1082933D03*
X1077933D03*
X1095567Y1426057D03*
X1117200Y1346700D03*
X1058126Y1513614D03*
X1061675Y1510352D03*
X1065210Y1506817D03*
X1066638Y1472408D03*
Y1467408D03*
Y1462408D03*
Y1457408D03*
Y1452408D03*
Y1447408D03*
Y1442408D03*
X1095567Y1431057D03*
Y1436057D03*
Y1441057D03*
Y1446057D03*
Y1451057D03*
Y1456057D03*
Y1461057D03*
Y1466057D03*
X1096039Y1505861D03*
X1099575Y1509397D03*
X1103110Y1512932D03*
X1107798Y1513685D03*
X1112798D03*
X1117798D03*
X1122798D03*
X1127798D03*
X1132798D03*
X1137798D03*
X1142798D03*
X1147798D03*
X1095567Y1471057D03*
X1066638Y1502408D03*
X1115000Y1485000D03*
X1118000Y1480500D03*
X1112000D03*
X1234500Y6000D03*
X1243844D03*
X1238844D03*
X1230409Y7565D03*
Y12565D03*
Y17565D03*
Y22565D03*
Y27565D03*
Y32565D03*
Y37565D03*
Y42565D03*
Y47565D03*
Y52565D03*
Y57565D03*
Y62565D03*
Y67565D03*
Y72565D03*
Y77565D03*
Y82565D03*
Y87565D03*
Y92565D03*
X1229000Y189500D03*
X1230409Y97565D03*
Y102565D03*
Y107565D03*
Y112565D03*
Y117565D03*
Y122565D03*
Y127565D03*
Y132565D03*
Y137565D03*
Y142565D03*
Y147565D03*
Y152565D03*
Y157565D03*
Y162565D03*
Y167565D03*
Y172565D03*
Y177565D03*
Y182565D03*
X1225000Y194000D03*
X1218734Y195764D03*
X1213734D03*
X1208734D03*
X1203734D03*
X1198734D03*
X1193734D03*
X1188734D03*
X1183734D03*
X1178734D03*
X1173734D03*
X1168734D03*
X1163734D03*
X1158734D03*
X1153734D03*
X1151100Y1179300D03*
X1155900D03*
X1151100Y1184100D03*
X1155900D03*
Y1188900D03*
X1151100D03*
X1245500Y1500500D03*
X1208000Y1502500D03*
X1234783Y1499118D03*
X1229783D03*
X1224783D03*
X1219783D03*
X1214783D03*
X1239783D03*
X1152798Y1513685D03*
X1157798D03*
X1162798D03*
X1167798D03*
X1172798D03*
X1177798D03*
X1182798D03*
X1187798D03*
X1192798D03*
X1197798D03*
X1202798D03*
X1205500Y1509000D03*
X1338844Y6000D03*
X1333844D03*
X1328844D03*
X1323844D03*
X1318844D03*
X1313844D03*
X1308844D03*
X1303844D03*
X1298844D03*
X1293844D03*
X1288844D03*
X1283844D03*
X1278844D03*
X1273844D03*
X1268844D03*
X1263844D03*
X1258844D03*
X1253844D03*
X1248844D03*
X1249000Y1504500D03*
X1328464Y1513685D03*
X1333464D03*
X1338464D03*
X1293464D03*
X1298464D03*
X1303464D03*
X1308464D03*
X1313464D03*
X1318464D03*
X1323464D03*
X1250500Y1510500D03*
X1253464Y1513685D03*
X1258464D03*
X1263464D03*
X1268464D03*
X1273464D03*
X1278464D03*
X1283464D03*
X1288464D03*
X1433844Y6000D03*
X1428844D03*
X1423844D03*
X1418844D03*
X1413844D03*
X1408844D03*
X1403844D03*
X1398844D03*
X1393844D03*
X1388844D03*
X1383844D03*
X1378844D03*
X1373844D03*
X1368844D03*
X1363844D03*
X1358844D03*
X1353844D03*
X1348844D03*
X1343844D03*
X1385474Y1429500D03*
X1380074D03*
X1383374Y1425000D03*
X1383674Y1419000D03*
X1433500Y1490500D03*
X1428500Y1494000D03*
X1403500Y1513500D03*
X1398500D03*
X1363464Y1513685D03*
X1368464D03*
X1373464D03*
X1378464D03*
X1383464D03*
X1388464D03*
X1393464D03*
X1353464D03*
X1358464D03*
X1343464D03*
X1348464D03*
X1408464D03*
X1413464D03*
X1418464D03*
X1423464D03*
X1425890Y1510111D03*
Y1505111D03*
Y1500111D03*
X1528844Y6000D03*
X1523844D03*
X1518844D03*
X1513844D03*
X1508844D03*
X1503844D03*
X1498844D03*
X1493844D03*
X1488844D03*
X1483844D03*
X1478844D03*
X1473844D03*
X1468844D03*
X1463844D03*
X1458844D03*
X1453844D03*
X1448844D03*
X1443844D03*
X1438844D03*
X1439716Y1490063D03*
X1444716D03*
X1449716D03*
X1454716D03*
X1459716D03*
X1464716D03*
X1469716D03*
X1474716D03*
X1479716D03*
X1484716D03*
X1489716D03*
X1494716D03*
X1499716D03*
X1504716D03*
X1509716D03*
X1514716D03*
X1519716D03*
X1524716D03*
X1529716D03*
X1623844Y6000D03*
X1618844D03*
X1613844D03*
X1608844D03*
X1603844D03*
X1598844D03*
X1593844D03*
X1588844D03*
X1583844D03*
X1578844D03*
X1573844D03*
X1568844D03*
X1563844D03*
X1558844D03*
X1553844D03*
X1548844D03*
X1543844D03*
X1538844D03*
X1533844D03*
X1534716Y1490063D03*
X1539716D03*
X1544716D03*
X1549716D03*
X1554716D03*
X1559716D03*
X1564716D03*
X1569716D03*
X1574716D03*
X1579716D03*
X1584716D03*
X1589716D03*
X1594716D03*
X1599716D03*
X1604716D03*
X1609716D03*
X1614716D03*
X1619716D03*
X1624716D03*
X1718844Y6000D03*
X1713844D03*
X1708844D03*
X1703844D03*
X1698844D03*
X1693844D03*
X1688844D03*
X1683844D03*
X1678844D03*
X1673844D03*
X1668844D03*
X1663844D03*
X1658844D03*
X1653844D03*
X1648844D03*
X1643844D03*
X1638844D03*
X1633844D03*
X1628844D03*
X1667359Y434407D03*
Y439207D03*
Y429607D03*
X1662559D03*
Y434407D03*
Y439207D03*
X1649500Y1497500D03*
X1646000Y1492000D03*
X1720968Y1513685D03*
X1715968D03*
X1710968D03*
X1705968D03*
X1700968D03*
X1695968D03*
X1690968D03*
X1685968D03*
X1680968D03*
X1670968D03*
X1675968D03*
X1629716Y1490063D03*
X1634716D03*
X1639716D03*
X1650488Y1504165D03*
Y1509165D03*
X1650968Y1513685D03*
X1655968D03*
X1660968D03*
X1665968D03*
X1813844Y6000D03*
X1808844D03*
X1803844D03*
X1798844D03*
X1793844D03*
X1788844D03*
X1783844D03*
X1778844D03*
X1773844D03*
X1768844D03*
X1763844D03*
X1758844D03*
X1753844D03*
X1748844D03*
X1743844D03*
X1738844D03*
X1733844D03*
X1728844D03*
X1723844D03*
X1814463Y449725D03*
Y454725D03*
X1804900Y451800D03*
X1809915Y461785D03*
Y446985D03*
Y456985D03*
Y442185D03*
X1799600Y451800D03*
X1794915Y461785D03*
Y446985D03*
Y456985D03*
Y442185D03*
X1751774Y430510D03*
X1753959Y450607D03*
X1741159Y873707D03*
X1736359D03*
X1741159Y864107D03*
X1736359D03*
X1741159Y868907D03*
X1736359D03*
X1766526Y1429400D03*
X1760326Y1429500D03*
X1763926Y1419000D03*
X1763626Y1425000D03*
X1786004Y1513500D03*
X1780968Y1513685D03*
X1775968D03*
X1770968D03*
X1765968D03*
X1760968D03*
X1755968D03*
X1750968D03*
X1745968D03*
X1740968D03*
X1796004Y1513500D03*
X1801004D03*
X1806004D03*
X1811004D03*
X1816004D03*
X1730968Y1513685D03*
X1725968D03*
X1791004Y1513500D03*
X1735968Y1513685D03*
X1913844Y6000D03*
X1908844D03*
X1903844D03*
X1898844D03*
X1893844D03*
X1888844D03*
X1883844D03*
X1878844D03*
X1873844D03*
X1868844D03*
X1863844D03*
X1858844D03*
X1853844D03*
X1848844D03*
X1843844D03*
X1838844D03*
X1833844D03*
X1828844D03*
X1823844D03*
X1818844D03*
X1838463Y454725D03*
Y449725D03*
X1819263D03*
Y454725D03*
X1833663D03*
Y449725D03*
X1828863D03*
Y454725D03*
X1824063D03*
Y449725D03*
X1912663Y888925D03*
Y883925D03*
X1869115Y876385D03*
Y891185D03*
Y881185D03*
Y895985D03*
X1873800Y886300D03*
X1884115Y876385D03*
X1898263Y883925D03*
Y888925D03*
X1903063D03*
Y883925D03*
X1907863D03*
Y888925D03*
X1884115Y891185D03*
Y881185D03*
Y895985D03*
X1893463Y888925D03*
Y883925D03*
X1879100Y886300D03*
X1888663Y888925D03*
Y883925D03*
X1828363Y884925D03*
X1869500Y1503500D03*
X1865500Y1500000D03*
X1829500Y1501500D03*
X1826500Y1506500D03*
X1855256Y1499118D03*
X1850256D03*
X1845256D03*
X1840256D03*
X1826040Y1513315D03*
X1821040D03*
X1835256Y1499118D03*
X1860256D03*
X1871157Y1509110D03*
X1871582Y1513685D03*
X1876582D03*
X1881582D03*
X1886582D03*
X1891582D03*
X1896582D03*
X1901582D03*
X1906582D03*
X1911582D03*
X1928843Y8985D03*
Y93985D03*
Y88985D03*
Y83985D03*
Y78985D03*
Y73985D03*
Y68985D03*
Y63985D03*
Y58985D03*
Y53985D03*
Y48985D03*
Y43985D03*
Y38985D03*
Y28985D03*
Y23985D03*
Y18985D03*
Y13985D03*
Y33985D03*
X1923844Y6000D03*
X1918844D03*
X1928843Y98985D03*
Y188985D03*
Y183985D03*
Y178985D03*
Y173985D03*
Y168985D03*
Y163985D03*
Y158985D03*
Y153985D03*
Y148985D03*
Y143985D03*
Y138985D03*
Y133985D03*
Y128985D03*
Y123985D03*
Y118985D03*
Y113985D03*
Y108985D03*
Y103985D03*
Y283985D03*
Y278985D03*
Y273985D03*
Y268985D03*
Y263985D03*
Y258985D03*
Y253985D03*
Y248985D03*
Y243985D03*
Y238985D03*
Y233985D03*
Y228985D03*
Y223985D03*
Y218985D03*
Y213985D03*
Y208985D03*
Y203985D03*
Y198985D03*
Y193985D03*
Y378985D03*
Y373985D03*
Y368985D03*
Y363985D03*
Y358985D03*
Y353985D03*
Y348985D03*
Y343985D03*
Y338985D03*
Y333985D03*
Y328985D03*
Y323985D03*
Y318985D03*
Y313985D03*
Y308985D03*
Y303985D03*
Y298985D03*
Y293985D03*
Y288985D03*
Y418985D03*
Y433985D03*
Y428985D03*
Y423985D03*
Y473985D03*
Y468985D03*
Y463985D03*
Y458985D03*
Y453985D03*
Y448985D03*
Y443985D03*
Y438985D03*
Y413985D03*
Y408985D03*
Y403985D03*
Y398985D03*
Y393985D03*
Y388985D03*
Y383985D03*
Y568985D03*
Y563985D03*
Y558985D03*
Y553985D03*
Y548985D03*
Y543985D03*
Y538985D03*
Y533985D03*
Y528985D03*
Y523985D03*
Y518985D03*
Y513985D03*
Y508985D03*
Y503985D03*
Y498985D03*
Y493985D03*
Y488985D03*
Y483985D03*
Y478985D03*
Y663985D03*
Y658985D03*
Y653985D03*
Y648985D03*
Y643985D03*
Y638985D03*
Y633985D03*
Y628985D03*
Y623985D03*
Y618985D03*
Y613985D03*
Y608985D03*
Y603985D03*
Y598985D03*
Y593985D03*
Y588985D03*
Y583985D03*
Y578985D03*
Y573985D03*
Y758985D03*
Y753985D03*
Y748985D03*
Y743985D03*
Y738985D03*
Y733985D03*
Y728985D03*
Y723985D03*
Y718985D03*
Y713985D03*
Y708985D03*
Y703985D03*
Y698985D03*
Y693985D03*
Y688985D03*
Y683985D03*
Y678985D03*
Y673985D03*
Y668985D03*
Y853985D03*
Y848985D03*
Y843985D03*
Y838985D03*
Y833985D03*
Y828985D03*
Y823985D03*
Y818985D03*
Y813985D03*
Y808985D03*
Y803985D03*
Y798985D03*
Y793985D03*
Y788985D03*
Y783985D03*
Y778985D03*
Y773985D03*
Y768985D03*
Y763985D03*
Y918985D03*
Y913985D03*
Y908985D03*
Y903985D03*
Y898985D03*
Y893985D03*
Y888985D03*
Y883985D03*
Y878985D03*
Y873985D03*
Y868985D03*
Y863985D03*
Y858985D03*
Y948985D03*
Y943985D03*
Y938985D03*
Y933985D03*
Y928985D03*
Y923985D03*
Y1043985D03*
Y1038985D03*
Y1033985D03*
Y1028985D03*
Y1023985D03*
Y1018985D03*
Y1013985D03*
Y1008985D03*
Y1003985D03*
Y998985D03*
Y993985D03*
Y988985D03*
Y983985D03*
Y978985D03*
Y973985D03*
Y968985D03*
Y963985D03*
Y958985D03*
Y953985D03*
Y1143985D03*
Y1138985D03*
Y1133985D03*
Y1128985D03*
Y1123985D03*
Y1118985D03*
Y1113985D03*
Y1108985D03*
Y1103985D03*
Y1098985D03*
Y1093985D03*
Y1088985D03*
Y1083985D03*
Y1078985D03*
Y1073985D03*
Y1068985D03*
Y1063985D03*
Y1058985D03*
Y1053985D03*
Y1048985D03*
Y1238985D03*
Y1233985D03*
Y1228985D03*
Y1223985D03*
Y1218985D03*
Y1213985D03*
Y1208985D03*
Y1203985D03*
Y1198985D03*
Y1193985D03*
Y1188985D03*
Y1183985D03*
Y1178985D03*
Y1173985D03*
Y1168985D03*
Y1163985D03*
Y1158985D03*
Y1153985D03*
Y1148985D03*
Y1288985D03*
Y1293985D03*
Y1298985D03*
Y1303985D03*
Y1308985D03*
Y1313985D03*
Y1318985D03*
Y1323985D03*
Y1328985D03*
Y1333985D03*
Y1283985D03*
Y1278985D03*
Y1273985D03*
Y1268985D03*
Y1263985D03*
Y1258985D03*
Y1253985D03*
Y1248985D03*
Y1243985D03*
Y1348985D03*
Y1353985D03*
Y1358985D03*
Y1363985D03*
Y1368985D03*
Y1373985D03*
Y1378985D03*
Y1383985D03*
Y1388985D03*
Y1393985D03*
Y1398985D03*
Y1403985D03*
Y1408985D03*
Y1413985D03*
Y1418985D03*
Y1423985D03*
Y1428985D03*
Y1338985D03*
Y1343985D03*
Y1448985D03*
Y1443985D03*
Y1433985D03*
Y1438985D03*
X1920000Y1458000D03*
X1917500Y1463500D03*
X1916582Y1513685D03*
X1917031Y1509134D03*
Y1504134D03*
Y1499134D03*
Y1494134D03*
Y1489134D03*
Y1484134D03*
Y1479134D03*
Y1474134D03*
Y1469134D03*
X1926500Y1455000D03*
G54D70*
X537234Y1422529D03*
Y1434129D03*
G54D34*
X95500Y176200D03*
Y628700D03*
Y1081700D03*
X140500Y126300D03*
X219500Y176200D03*
X265000Y126400D03*
X219500Y628700D03*
X220000Y1081700D03*
X344000Y176200D03*
Y628700D03*
Y1081700D03*
X468000Y176200D03*
X389000Y126600D03*
X468000Y628700D03*
Y1081700D03*
X513600Y126500D03*
X528334Y1427929D03*
X528200Y1456800D03*
X592500Y176200D03*
X637300Y126500D03*
X592500Y628700D03*
Y1081700D03*
X651295Y1425119D03*
X716500Y176200D03*
X748400Y137300D03*
X716500Y628700D03*
X752500Y588200D03*
Y1048700D03*
X716500Y1081700D03*
X838470Y936630D03*
X958738Y1413018D03*
X1131215Y1310270D03*
X1213033Y1308144D03*
X1180009Y1308353D03*
X1298500Y146200D03*
Y175700D03*
X1253000Y126600D03*
X1298500Y599200D03*
Y628700D03*
X1252800Y579300D03*
Y1031900D03*
X1298500Y1051700D03*
Y1081200D03*
X1422500Y146200D03*
Y175700D03*
X1376700Y126600D03*
X1422500Y599200D03*
Y628700D03*
Y1051700D03*
Y1081200D03*
X1501300Y126600D03*
X1547000Y146200D03*
Y175700D03*
X1625300Y126600D03*
X1547000Y599200D03*
Y628700D03*
Y1051700D03*
Y1081200D03*
X1671000Y146200D03*
Y175700D03*
Y599200D03*
Y628700D03*
Y1051700D03*
Y1081200D03*
X1795000Y146200D03*
Y175700D03*
X1749700Y126100D03*
X1795000Y599200D03*
Y628700D03*
Y1051700D03*
Y1081200D03*
X1887000Y175700D03*
Y628700D03*
Y1081700D03*
G54D53*
X173228Y55118D03*
X421653Y94488D03*
X670078Y55118D03*
X1343701D03*
X1592126Y94488D03*
X1840551Y55118D03*
G54D71*
X517500Y1471924D03*
Y1458624D03*
X535200Y1447950D03*
Y1461250D03*
G54D62*
X153524Y1464000D03*
X140224D03*
X153524Y1445500D03*
X140224D03*
X1300524Y1464000D03*
X1287224D03*
X1300524Y1445500D03*
X1287224D03*
X1680776Y1464000D03*
X1667476D03*
X1680776Y1445500D03*
X1667476D03*
G54D35*
X73500Y126000D03*
X84500D03*
X69000Y140500D03*
X80000D03*
X73500Y578500D03*
X84500D03*
X69000Y593000D03*
X80000D03*
X73500Y1031500D03*
X84500D03*
X69000Y1046000D03*
X80000D03*
X193000Y140500D03*
Y593000D03*
X193500Y1046000D03*
X197500Y126000D03*
X208500D03*
X204000Y140500D03*
X197500Y578500D03*
X208500D03*
X204000Y593000D03*
X198000Y1031500D03*
X209000D03*
X204500Y1046000D03*
X322000Y126000D03*
X333000D03*
X317500Y140500D03*
X328500D03*
X322000Y578500D03*
X333000D03*
X317500Y593000D03*
X328500D03*
X322000Y1031500D03*
X333000D03*
X317500Y1046000D03*
X328500D03*
X446000Y126000D03*
X457000D03*
X441500Y140500D03*
X452500D03*
X446000Y578500D03*
X457000D03*
X441500Y593000D03*
X452500D03*
X446000Y1031500D03*
X457000D03*
X441500Y1046000D03*
X452500D03*
X570500Y126000D03*
X566000Y140500D03*
X577000D03*
X570500Y578500D03*
X566000Y593000D03*
X577000D03*
X570500Y1031500D03*
X566000Y1046000D03*
X577000D03*
X581500Y126000D03*
Y578500D03*
Y1031500D03*
X694500Y126000D03*
X705500D03*
X690000Y140500D03*
X701000D03*
X694500Y578500D03*
X705500D03*
X690000Y593000D03*
X701000D03*
X694500Y1031500D03*
X705500D03*
X690000Y1046000D03*
X701000D03*
X1310500Y126000D03*
X1299500D03*
X1319000Y159800D03*
X1308000D03*
X1310500Y579000D03*
X1299500D03*
X1318700Y612600D03*
X1307700D03*
X1310500Y1031500D03*
X1299500D03*
X1319000Y1065300D03*
X1308000D03*
X1434500Y126000D03*
X1423500D03*
X1431600Y159800D03*
X1434500Y579000D03*
X1423500D03*
X1432000Y612600D03*
X1434500Y1031500D03*
X1423500D03*
X1432000Y1065300D03*
X1442600Y159800D03*
X1443000Y612600D03*
Y1065300D03*
X1559000Y126000D03*
X1548000D03*
X1567400Y159800D03*
X1556400D03*
X1559000Y579000D03*
X1548000D03*
X1567300Y612600D03*
X1556300D03*
X1559000Y1031500D03*
X1548000D03*
X1567600Y1065500D03*
X1556600D03*
X1683000Y126000D03*
X1672000D03*
X1690400Y160000D03*
X1679400D03*
X1683000Y579000D03*
X1672000D03*
X1691600Y612500D03*
X1680600D03*
X1683000Y1031500D03*
X1672000D03*
X1691400Y1065300D03*
X1680400D03*
X1807000Y126000D03*
X1796000D03*
X1815500Y159700D03*
X1804500D03*
X1807000Y579000D03*
X1796000D03*
X1815800Y612500D03*
X1804800D03*
X1807000Y1031500D03*
X1796000D03*
X1815700Y1065300D03*
X1804700D03*
X1865000Y125500D03*
X1876000D03*
X1860500Y140000D03*
X1871500D03*
X1865000Y578500D03*
X1876000D03*
X1860500Y593000D03*
X1871500D03*
X1865000Y1031500D03*
X1876000D03*
X1860500Y1046000D03*
X1871500D03*
G54D80*
X685079Y1463250D03*
X687047D03*
X689016D03*
X690984D03*
X692953D03*
X694921D03*
Y1443750D03*
X692953D03*
X690984D03*
X689016D03*
X687047D03*
X685079D03*
X992522Y1451149D03*
X994490D03*
X996459D03*
X998427D03*
X1000396D03*
X1002364D03*
Y1431649D03*
X1000396D03*
X998427D03*
X996459D03*
X994490D03*
X992522D03*
G54D17*
X60000Y69800D03*
Y522300D03*
X81700Y901880D03*
X77563Y901825D03*
X60000Y975300D03*
X131600Y122700D03*
X179527Y464144D03*
X175390Y464089D03*
X184000Y522300D03*
X184500Y975300D03*
X138974Y1425700D03*
X149374Y1453800D03*
Y1435300D03*
X207000Y73800D03*
X217000Y41800D03*
X254900Y122900D03*
X308500Y69800D03*
X379500Y122900D03*
X308500Y522300D03*
Y975300D03*
X454000Y77200D03*
X465500Y41800D03*
X432500Y522300D03*
Y975300D03*
X557000Y69800D03*
X503900Y122800D03*
X557000Y522300D03*
Y975300D03*
X502999Y1448232D03*
X628000Y122800D03*
X583550Y512850D03*
X655795Y1426219D03*
X628500Y1461300D03*
X704000Y73800D03*
X714000Y41800D03*
X707800Y513500D03*
X681000Y522300D03*
X752200Y575600D03*
X681000Y975300D03*
X676500Y1476300D03*
X841939Y386415D03*
X846939D03*
X822470Y924230D03*
Y974230D03*
X830470D03*
X839970Y966470D03*
X955000Y544400D03*
X952100Y516600D03*
X922100Y757300D03*
X948500Y845800D03*
X953000D03*
X911080Y860670D03*
X918380Y915714D03*
X914260Y915670D03*
X951500Y1226300D03*
X868900Y1184800D03*
X888000Y1193900D03*
X986200Y544300D03*
X983300Y518600D03*
X966093Y845800D03*
X993942Y876100D03*
X976242Y877800D03*
X980442Y876100D03*
X1000500Y907300D03*
X1005500D03*
X959500Y1226300D03*
X963238Y1414118D03*
X998325Y1464234D03*
X1013618Y1464165D03*
X1043606Y1444949D03*
X975438Y1450208D03*
X1122112Y1366573D03*
X1134112D03*
X1114112D03*
X1118112D03*
X1138112D03*
X1203394Y1340083D03*
X1222100D03*
X1236600D03*
X1232100D03*
X1217100D03*
X1183894D03*
X1188894D03*
X1198894D03*
X1203487Y1421241D03*
X1308000Y38300D03*
X1318000D03*
X1317800Y50600D03*
X1311700Y65700D03*
X1313700Y50600D03*
X1262600Y122900D03*
X1312000Y504800D03*
X1322000D03*
X1326500Y517300D03*
X1322000D03*
X1262600Y575600D03*
X1262400Y1028300D03*
X1312000Y957300D03*
X1322000D03*
X1326500Y969800D03*
X1322000D03*
X1296374Y1453800D03*
Y1435300D03*
X1436000Y51800D03*
X1387200Y122900D03*
X1436000Y504800D03*
X1386400Y575600D03*
X1387000Y1028400D03*
X1436000Y957300D03*
X1446000Y51800D03*
X1450500Y64300D03*
X1446000D03*
X1511400Y122900D03*
X1446000Y504800D03*
X1450500Y517300D03*
X1446000D03*
X1511200Y575600D03*
X1446000Y957300D03*
X1450500Y969800D03*
X1446000D03*
X1511400Y1028400D03*
X1557500Y38300D03*
X1567500D03*
X1572000Y50800D03*
X1563500Y65800D03*
X1567500Y50800D03*
X1560500Y504800D03*
X1570500D03*
X1575000Y517300D03*
X1570500D03*
X1560500Y957300D03*
X1570500D03*
X1575000Y969800D03*
X1570500D03*
X1684500Y51800D03*
X1694500D03*
X1699000Y64300D03*
X1694500D03*
X1635300Y122900D03*
X1722296Y467562D03*
X1718159Y467507D03*
X1684500Y504800D03*
X1694500D03*
X1699000Y517300D03*
X1694500D03*
X1634200Y575600D03*
X1635100Y1028400D03*
X1684500Y957300D03*
X1694500D03*
X1699000Y969800D03*
X1694500D03*
X1676626Y1453800D03*
Y1435300D03*
X1759600Y122900D03*
X1808500Y504800D03*
X1792563Y901825D03*
X1796700Y901880D03*
X1759300Y1028400D03*
X1808500Y957300D03*
X1884600Y42300D03*
X1862300Y26600D03*
X1818500Y504800D03*
X1823000Y517300D03*
X1818500D03*
X1853000Y507300D03*
X1848500D03*
X1843000Y537800D03*
X1818500Y957300D03*
X1823000Y969800D03*
X1818500D03*
X1875800Y984800D03*
X1853000Y960300D03*
X1848500D03*
X1843000Y990800D03*
G54D26*
X77300Y67250D03*
X60000Y80000D03*
X67750Y84500D03*
X77100Y62800D03*
X85600Y67700D03*
X83000Y147500D03*
X69000Y148000D03*
X86700Y133000D03*
X58709Y376696D03*
X72049Y349667D03*
X72600Y365900D03*
X53713Y367631D03*
X69567Y380781D03*
X77300Y519750D03*
X60000Y532500D03*
X68100Y537000D03*
X77200Y515100D03*
X86850Y520600D03*
X83000Y600000D03*
X69000Y600500D03*
X86500Y585400D03*
X57300Y751562D03*
X46442Y829350D03*
X72049Y808105D03*
X68109Y785607D03*
X44000Y819500D03*
X79563Y910125D03*
X97263Y913025D03*
X86263D03*
X77263Y894425D03*
X71313Y904525D03*
X70603Y887495D03*
X65763Y875525D03*
X86500Y1038500D03*
X77300Y972750D03*
X60000Y985500D03*
X69000Y989000D03*
X63000Y964500D03*
X83000Y970000D03*
Y1053000D03*
X69000Y1053500D03*
X188841Y79022D03*
X195250Y73500D03*
X151160Y18699D03*
X168100Y25300D03*
X168200Y20500D03*
X140200Y48400D03*
X144400Y40500D03*
X136200Y126150D03*
X193000Y148000D03*
X192842Y376350D03*
X180300Y330300D03*
X184060Y300300D03*
X187450Y445273D03*
X177390Y472389D03*
X195090Y475289D03*
X184090D03*
X175090Y456689D03*
X169140Y466789D03*
X168430Y449759D03*
X164418Y438162D03*
X184000Y532500D03*
X192499Y536649D03*
X137250Y588500D03*
X193000Y600500D03*
X169442Y829050D03*
X192321Y785355D03*
X165500Y822058D03*
X180300Y769500D03*
X129298Y888025D03*
X114563Y904041D03*
X112763Y869025D03*
X106363Y893425D03*
X102763Y873035D03*
X102207Y890524D03*
X102863Y880125D03*
X184500Y985500D03*
X193949Y989097D03*
X137250Y1041500D03*
X193500Y1053500D03*
X168674Y1414200D03*
X137634Y1416776D03*
X184874Y1412600D03*
X116374Y1497100D03*
X109774Y1480300D03*
X124174Y1466600D03*
X104974Y1485200D03*
X124574Y1488200D03*
X119074Y1442100D03*
X113314Y1445840D03*
X105974Y1469500D03*
X124134Y1474900D03*
X211000Y57400D03*
X211162Y45100D03*
X211086Y73750D03*
X207000Y147500D03*
X260400Y126350D03*
X210960Y132800D03*
X218200Y360600D03*
X204300Y351300D03*
X227434Y450289D03*
X212390Y466305D03*
X210596Y431445D03*
X204190Y455689D03*
X199590Y434639D03*
X200022Y452941D03*
X201190Y442389D03*
X201300Y519750D03*
X201000Y515300D03*
X211150Y520500D03*
X207000Y600000D03*
X261250Y588500D03*
X211000Y585600D03*
X196261Y807853D03*
X261500Y1042000D03*
X211000Y1038200D03*
X201800Y972750D03*
X201600Y968400D03*
X210850Y973800D03*
X208000Y1053000D03*
X244829Y1241403D03*
X218384Y1411500D03*
X325800Y67250D03*
X308500Y80000D03*
X316800Y84000D03*
X325900Y62900D03*
X335100Y67800D03*
X331500Y147500D03*
X384549Y126350D03*
X317500Y148000D03*
X335299Y133000D03*
X320474Y364117D03*
X316534Y341619D03*
X294542Y376650D03*
X294000Y366300D03*
X305400Y317825D03*
X325800Y519750D03*
X308500Y532500D03*
X320958Y533200D03*
X325800Y514700D03*
X335050Y520700D03*
X331500Y600000D03*
X385750Y588500D03*
X317500Y600500D03*
X335290Y585300D03*
X294542Y829350D03*
X320474Y812669D03*
X316534Y790171D03*
X294000Y819000D03*
X305400Y764768D03*
X312418Y868254D03*
X385750Y1041500D03*
X335100Y1038500D03*
X325800Y972750D03*
X308500Y985500D03*
X317542Y988731D03*
X325600Y968400D03*
X334750Y973200D03*
X331500Y1053000D03*
X317500Y1053500D03*
X372774Y1438648D03*
X459000Y57500D03*
X448200Y40150D03*
X445500Y74300D03*
X459511Y44500D03*
X458900Y76700D03*
X455500Y147500D03*
X441500Y148000D03*
X459400Y133100D03*
X429900Y278468D03*
X444687Y358540D03*
X440747Y336042D03*
X419042Y376350D03*
X418500Y366000D03*
X435190Y408695D03*
X449800Y519750D03*
X432500Y532500D03*
X440855Y536014D03*
X449800Y515400D03*
X459350Y520600D03*
X455500Y600000D03*
X441500Y600500D03*
X459500Y585400D03*
X429600Y761281D03*
X418742Y828794D03*
X444687Y807662D03*
X440747Y785164D03*
X415000Y819000D03*
X448289Y917775D03*
X434890Y861395D03*
X459100Y1038400D03*
X449800Y972750D03*
X432500Y985500D03*
X441398Y989368D03*
X449700Y968500D03*
X459150Y973500D03*
X455500Y1053000D03*
X441500Y1053500D03*
X478444Y1240034D03*
X428500Y1423500D03*
Y1430500D03*
X574300Y67250D03*
X557000Y80000D03*
X565757Y83609D03*
X574300Y62900D03*
X508761Y126250D03*
X566000Y148000D03*
X548228Y100997D03*
X536715Y271785D03*
X568899Y355752D03*
X564959Y333254D03*
X493899Y320895D03*
X488448Y338766D03*
X482745Y351821D03*
X543242Y376650D03*
X498968Y296814D03*
X505052Y368552D03*
X511136Y352328D03*
X517473Y332556D03*
X523810Y312530D03*
X531987Y294450D03*
X554100Y294300D03*
X557975Y412093D03*
X574300Y519750D03*
X557000Y532500D03*
X565500Y537000D03*
X574300Y515500D03*
X509750Y588500D03*
X566000Y600500D03*
X569000Y814761D03*
X564959Y791755D03*
X575148Y827910D03*
X509750Y1041500D03*
X574300Y972750D03*
X557000Y985500D03*
X566574Y988327D03*
X574200Y968300D03*
X566000Y1053500D03*
X547198Y1420600D03*
X497000Y1408500D03*
X539500Y1408000D03*
X553500D03*
X572000D03*
X583700Y68200D03*
X580000Y147500D03*
X632974Y126250D03*
X583724Y132900D03*
X665100Y275593D03*
X654242Y376350D03*
X653700Y366000D03*
X670390Y408695D03*
X583550Y520300D03*
Y508800D03*
X672050Y552553D03*
X580000Y600000D03*
X634250Y588500D03*
X583600Y585200D03*
X646680Y647138D03*
X582648Y829573D03*
X659642Y829050D03*
X652142Y822416D03*
X593680Y827400D03*
X670500Y829616D03*
X594056Y909112D03*
X598970Y862595D03*
X610207Y900960D03*
X634250Y1041500D03*
X583600Y1038500D03*
X583050Y973400D03*
X671359Y1006366D03*
X580000Y1053000D03*
X607000Y1291500D03*
X663263Y1427653D03*
X590500Y1408500D03*
X646226Y1433033D03*
X663109Y1433549D03*
X663726Y1438933D03*
X672500Y1485000D03*
X667500Y1476250D03*
X707937Y57400D03*
X687700Y79300D03*
X692250Y74000D03*
X710000Y44500D03*
X707937Y73750D03*
X701300Y147700D03*
X690000Y148000D03*
X707937Y132800D03*
X693112Y342443D03*
X689172Y319945D03*
X698300Y519750D03*
X681000Y532500D03*
X690116Y535877D03*
X698100Y515100D03*
X707800Y520800D03*
X703200Y512000D03*
X704000Y600000D03*
X757300Y582800D03*
X690000Y600500D03*
X707900Y585200D03*
X749541Y717011D03*
X685500Y773631D03*
X680500Y790616D03*
X758562Y925283D03*
X675790Y861395D03*
X740364Y901060D03*
X758250Y1043000D03*
X707800Y1038200D03*
X698300Y972750D03*
X681000Y985500D03*
X690141Y989210D03*
X698000Y968300D03*
X707450Y973600D03*
X704000Y1053000D03*
X690000Y1053500D03*
X745367Y1239122D03*
X703411Y1387198D03*
X744132Y1426834D03*
X719000Y1453500D03*
X701000Y1438000D03*
X708500Y1438500D03*
X706000Y1453500D03*
X684750Y1435250D03*
X692750Y1435500D03*
X673500Y1448500D03*
X687900Y1471800D03*
X704000Y1469800D03*
X705890Y1446000D03*
X676500Y1472150D03*
X698500Y1431000D03*
X673964Y1434848D03*
X734032Y1465634D03*
X705500Y1463000D03*
X711363Y1458500D03*
X746064Y1494250D03*
X752132Y1450534D03*
X745406Y1486450D03*
X750232Y1472534D03*
X739532Y1430734D03*
X730332Y1457534D03*
X748732Y1460134D03*
X855100Y258531D03*
X841000D03*
X826700D03*
X845968Y380023D03*
X842786Y374795D03*
X836451Y444751D03*
X844585Y451535D03*
X832417Y459017D03*
X829490Y657790D03*
X830990Y652690D03*
X829490Y647190D03*
X816068Y625673D03*
X796484Y648490D03*
X800684Y652390D03*
X805128Y646475D03*
X862500Y760000D03*
X817373Y744099D03*
X816104Y679776D03*
X806535Y676210D03*
X831000Y817600D03*
X861986Y804305D03*
X832500Y812500D03*
X830000Y807000D03*
X824500Y775000D03*
X824000Y769000D03*
X863100Y765200D03*
X862600Y769500D03*
X824500Y780500D03*
X819870Y932430D03*
X824970Y933930D03*
X830300Y932470D03*
X832000Y887000D03*
Y881500D03*
X796396Y879084D03*
X785560Y876549D03*
X844940Y915701D03*
X768449Y929466D03*
X769130Y919152D03*
X853398Y914258D03*
X860219Y912294D03*
X833500Y895500D03*
X859200Y891900D03*
X830470Y970430D03*
X822430Y968470D03*
X834871Y966706D03*
X814330Y1026361D03*
X810751Y1028560D03*
X797473Y1041318D03*
X844120Y974180D03*
X779222Y1116604D03*
X802162Y1075032D03*
X771236Y1096959D03*
X810000Y1327000D03*
X810500Y1377000D03*
X817277Y1402673D03*
X847000Y1407000D03*
X838500D03*
X852493Y1392918D03*
X869300Y258531D03*
X945656Y547005D03*
X951860Y524737D03*
X951739Y530020D03*
X951915Y556600D03*
X866276Y650103D03*
X865530Y655230D03*
X892391Y622635D03*
X898676Y631324D03*
X865945Y643688D03*
X875007Y601293D03*
X916951Y757250D03*
X917600Y778500D03*
X955482Y772968D03*
Y778168D03*
Y767768D03*
X917700Y774200D03*
Y769200D03*
X946167Y853833D03*
X952500Y854500D03*
X957095Y854128D03*
X935250Y854000D03*
X940000D03*
X869000Y807000D03*
X867040Y815040D03*
X883750Y822250D03*
X874562Y825063D03*
X913597Y800899D03*
X906008Y799372D03*
X917211Y793314D03*
X908543Y792632D03*
X917211Y788194D03*
X917600Y783500D03*
X896283Y829425D03*
X886342Y834927D03*
X888100Y827700D03*
X880209Y831210D03*
X920461Y824079D03*
X917052Y831472D03*
X953742Y818977D03*
X941564Y821964D03*
X920170Y849500D03*
X925073Y840417D03*
X909940Y871500D03*
X918380Y911780D03*
X913000Y911500D03*
X923645Y911630D03*
X915250Y870750D03*
X920712Y870212D03*
X867700Y873500D03*
Y878200D03*
X867350Y883000D03*
X895346Y871309D03*
X900346D03*
X902749Y864327D03*
X898596Y858067D03*
X954208Y894134D03*
X949371Y898442D03*
X923468Y875044D03*
X940499Y905125D03*
X951500Y1222500D03*
X943500Y1221000D03*
X899919Y1176183D03*
X934200Y1190700D03*
X934271Y1198029D03*
X942955Y1200945D03*
X940168Y1211332D03*
X868900Y1192600D03*
X885118Y1202182D03*
X931900Y1206220D03*
X927500Y1211340D03*
X933200Y1216460D03*
X869937Y1395977D03*
X953652Y1420748D03*
X1026521Y387770D03*
X1036100Y410500D03*
X1045300Y420400D03*
X1033200Y423228D03*
X1017500Y426131D03*
X1047900Y432500D03*
X1041600Y435700D03*
X980100Y413700D03*
X1005846Y429434D03*
X1016557Y437230D03*
X995633Y547651D03*
X1004460Y533819D03*
X981500Y512300D03*
X984200Y539000D03*
X1015143Y577288D03*
X1003166Y574208D03*
X1011037Y736868D03*
X1015618Y700908D03*
X1019284Y721708D03*
X1023243Y732861D03*
X1028089Y707561D03*
X1032654Y697436D03*
X979107Y839078D03*
X974163Y839165D03*
X983000Y837500D03*
X989120D03*
X1005450Y849166D03*
X999500Y849500D03*
X1033807Y847865D03*
X989933Y872000D03*
X982500Y871400D03*
X971982Y873647D03*
X983311Y904195D03*
X978033Y902083D03*
X972854Y900520D03*
X964170Y895500D03*
X993483Y899206D03*
X1039500Y878500D03*
X1004300Y889275D03*
X1009800Y887100D03*
X1016400Y886500D03*
X1021500D03*
X1028500Y862000D03*
X1003000Y916000D03*
X1025500Y919500D03*
X1008739Y1096000D03*
X1028500Y1118601D03*
X965500Y1128000D03*
X1012800Y1122100D03*
X1002671Y1124700D03*
X977643Y1132490D03*
X1007431Y1122900D03*
X987300Y1179800D03*
X982172Y1176631D03*
X959500Y1221000D03*
X970500Y1205000D03*
X972000Y1223400D03*
Y1201000D03*
X970500Y1197000D03*
X967500Y1221000D03*
X972000Y1209000D03*
X970500Y1213000D03*
X963500Y1222500D03*
X1035882Y1327084D03*
X981700Y1315900D03*
X1045536Y1316578D03*
X975332Y1239578D03*
X1035676Y1383286D03*
X1036877Y1356115D03*
X1008443Y1425899D03*
X1015943Y1426399D03*
X1035100Y1397300D03*
X970552Y1421448D03*
X971169Y1426832D03*
X992800Y1422300D03*
X1000193Y1423399D03*
X979900Y1426800D03*
X1005943Y1418899D03*
X987600Y1425200D03*
X994884Y1393370D03*
X1049437Y1367213D03*
X1048400Y1339700D03*
X1036918Y1391589D03*
X1052485Y1421680D03*
X1018943Y1438899D03*
X979599Y1436399D03*
X995617Y1459516D03*
X1021618Y1460000D03*
X1013333Y1433899D03*
X979179Y1450158D03*
X1015550Y1496214D03*
X1028650Y1494714D03*
X1039450Y1501914D03*
X1037350Y1487714D03*
X1046850Y1485514D03*
X1050050Y1496014D03*
X966465Y1454578D03*
X966438Y1450158D03*
X1015443Y1452399D03*
X1016943Y1446320D03*
X973617Y1445912D03*
Y1440912D03*
X1035943Y1436649D03*
X1067872Y422624D03*
X1074400Y419124D03*
X1137600Y527100D03*
X1137446Y541317D03*
Y555490D03*
Y569663D03*
X1120959Y621993D03*
X1137446Y698798D03*
Y712971D03*
Y727144D03*
Y741317D03*
Y755490D03*
Y769663D03*
Y783836D03*
Y798010D03*
Y812183D03*
Y826356D03*
Y840529D03*
Y854703D03*
Y868876D03*
Y883049D03*
Y897222D03*
Y911396D03*
Y925569D03*
Y939742D03*
X1063591Y1008944D03*
X1056428Y998612D03*
X1059569Y1017555D03*
X1093332Y1037457D03*
X1124848Y1034859D03*
X1087100Y1304820D03*
X1086062Y1294580D03*
X1085962Y1309495D03*
X1055536Y1393731D03*
X1063920Y1385019D03*
X1130112Y1374773D03*
X1123037Y1374473D03*
X1111012Y1391273D03*
X1109612Y1371600D03*
Y1395273D03*
X1111112Y1399273D03*
X1114112Y1374773D03*
X1109612Y1387273D03*
X1111112Y1383273D03*
X1118301Y1374458D03*
X1138112Y1375273D03*
X1100300Y1359247D03*
X1133412Y1407173D03*
X1141554Y1399660D03*
X1147312Y1387193D03*
X1147512Y1382073D03*
X1144564Y1392821D03*
X1140175Y1389710D03*
X1140512Y1381273D03*
X1112673Y1500348D03*
X1242718Y335091D03*
X1238778Y312593D03*
X1234254Y442080D03*
X1216078Y465349D03*
X1232660Y453858D03*
X1188800Y507600D03*
X1216040Y625269D03*
X1207265Y709641D03*
X1212703Y758435D03*
X1206937Y755002D03*
X1214657Y681090D03*
X1232675Y738300D03*
X1217111Y829350D03*
X1242718Y820846D03*
X1238778Y798348D03*
X1216569Y819000D03*
X1189224Y912756D03*
X1188509Y918850D03*
X1160314Y1032608D03*
X1223634Y1052998D03*
X1211764Y1320310D03*
X1172318Y1320640D03*
X1218529Y1242316D03*
X1197394Y1298415D03*
X1230600D03*
X1202394D03*
X1235600D03*
X1192394D03*
X1225600D03*
X1202394Y1335151D03*
X1235600D03*
X1192394D03*
X1225600D03*
X1187394D03*
X1220600D03*
X1197394D03*
X1230600D03*
X1212460Y1422825D03*
X1209500Y1397433D03*
X1306950Y59950D03*
X1312100Y58300D03*
X1313000Y41750D03*
X1307000Y166100D03*
X1257533Y126350D03*
X1324900Y154100D03*
X1310500Y133000D03*
X1334250Y104300D03*
X1257000Y355500D03*
X1261060Y300000D03*
X1338423Y429770D03*
X1248784Y442826D03*
X1317000Y517000D03*
X1336500Y533500D03*
X1306800Y525500D03*
X1324500Y533500D03*
X1317000Y508250D03*
X1307100Y618800D03*
X1257500Y579050D03*
X1334000Y616500D03*
X1310500Y586000D03*
X1340324Y928894D03*
X1257100Y1031750D03*
X1310500Y1038500D03*
X1317000Y969500D03*
X1337500Y986000D03*
X1307850Y977800D03*
X1324500Y986000D03*
X1317000Y960750D03*
X1307100Y1071600D03*
X1334000Y1069000D03*
X1305500Y1413500D03*
X1324000Y1412600D03*
X1281624Y1425618D03*
X1277624Y1416318D03*
X1279484Y1471500D03*
X1255974Y1484800D03*
X1259374Y1501400D03*
X1269974Y1469300D03*
X1251574Y1490800D03*
X1270574Y1493300D03*
X1262774Y1449300D03*
X1257874Y1450500D03*
X1252274Y1477000D03*
X1270674Y1479500D03*
X1431300Y72150D03*
X1431100Y166000D03*
X1381756Y126350D03*
X1434500Y133000D03*
X1364600Y189600D03*
X1366931Y359435D03*
X1362991Y336937D03*
X1342880Y363931D03*
X1358498Y307500D03*
X1431350Y525000D03*
X1344024Y483916D03*
X1431300Y618900D03*
X1381600Y579200D03*
X1434500Y586000D03*
X1350982Y737700D03*
X1341324Y829350D03*
X1366931Y820844D03*
X1362991Y798346D03*
X1354742Y764100D03*
X1381500Y1031800D03*
X1434500Y1038500D03*
X1431350Y978200D03*
X1431313Y1071600D03*
X1341268Y1326727D03*
X1386424Y1415469D03*
X1365374Y1412500D03*
X1441000Y64000D03*
X1460500Y80500D03*
X1441200Y68200D03*
X1441000Y55250D03*
X1505968Y126350D03*
X1458000Y163500D03*
X1449286Y109468D03*
X1453052Y199552D03*
X1491143Y364938D03*
X1487203Y342440D03*
X1464994Y366244D03*
X1478954Y299400D03*
X1462350Y428169D03*
X1441000Y517000D03*
X1460500Y533500D03*
X1448500D03*
X1441000Y508250D03*
X1465195Y482118D03*
X1449416Y562671D03*
X1505900Y578800D03*
X1458000Y616500D03*
X1465536Y829350D03*
X1491143Y821350D03*
X1487203Y798852D03*
X1464994Y819000D03*
X1476400Y827900D03*
X1472646Y930795D03*
X1505700Y1031850D03*
X1441000Y969500D03*
X1461500Y986000D03*
X1448500D03*
X1441000Y960750D03*
X1458000Y1069000D03*
X1483629Y1240035D03*
X1562500Y50500D03*
X1576800Y69000D03*
X1555450Y59500D03*
X1563500Y61000D03*
X1562500Y41750D03*
X1555400Y166000D03*
X1568900Y148700D03*
X1559000Y133000D03*
X1615356Y363164D03*
X1611416Y340666D03*
X1589207Y366244D03*
X1603167Y304800D03*
X1578333Y431523D03*
X1587023Y474261D03*
X1565500Y517000D03*
X1585000Y533500D03*
X1555450Y524900D03*
X1573000Y533500D03*
X1565500Y508250D03*
X1555500Y618800D03*
X1582500Y616500D03*
X1559000Y586000D03*
X1589749Y829350D03*
X1615356Y822490D03*
X1611416Y799992D03*
X1597607Y763144D03*
X1600607Y824639D03*
X1607884Y925219D03*
X1559000Y1038500D03*
X1565500Y969500D03*
X1586000Y986000D03*
X1555750Y978600D03*
X1573000Y986000D03*
X1565500Y960750D03*
X1574019Y1015221D03*
X1555525Y1071600D03*
X1582500Y1069000D03*
X1689500Y64000D03*
X1709000Y80500D03*
X1679600Y72500D03*
X1697000Y80500D03*
X1689500Y55250D03*
X1679600Y166100D03*
X1630181Y126350D03*
X1706500Y163500D03*
X1683000Y133000D03*
X1697942Y109938D03*
X1720159Y475807D03*
X1721381Y411596D03*
X1717859Y460107D03*
X1711909Y470207D03*
X1711199Y453177D03*
X1706359Y441207D03*
X1689500Y517000D03*
X1709000Y533500D03*
X1680050Y525200D03*
X1697000Y533500D03*
X1689500Y508250D03*
X1701720Y497999D03*
X1698111Y562671D03*
X1679488Y618800D03*
X1630100Y579050D03*
X1706500Y616500D03*
X1683000Y586000D03*
X1713961Y829350D03*
X1629800Y1031850D03*
X1683000Y1038500D03*
X1689500Y969500D03*
X1709000Y986000D03*
X1679650Y978000D03*
X1697000Y986000D03*
X1689500Y960750D03*
X1697864Y1015165D03*
X1679738Y1071600D03*
X1706500Y1069000D03*
X1694626Y1414000D03*
X1712126Y1412600D03*
X1651906Y1447500D03*
X1659906Y1435500D03*
X1803200Y70600D03*
X1804800Y63100D03*
X1811800Y17700D03*
X1803900Y46100D03*
X1808200D03*
X1804000Y166100D03*
X1754300Y125900D03*
X1807000Y133000D03*
X1739568Y361896D03*
X1735628Y339398D03*
X1749650Y376854D03*
X1804600Y365600D03*
X1763791Y374891D03*
X1786451Y408530D03*
X1755159Y469723D03*
X1751774Y434652D03*
X1746959Y459107D03*
X1743359Y438057D03*
X1742758Y456059D03*
X1743959Y445807D03*
X1813500Y517000D03*
X1804050Y525100D03*
X1813500Y508250D03*
X1737859Y478707D03*
X1726859D03*
X1803700Y618800D03*
X1763000Y589000D03*
X1807000Y586000D03*
X1739568Y828517D03*
X1735628Y802019D03*
X1723619Y777600D03*
X1727379Y764235D03*
X1794563Y910125D03*
X1726771Y922050D03*
X1812263Y913025D03*
X1801263D03*
X1792263Y894425D03*
X1816263Y872375D03*
X1786313Y904525D03*
X1817739Y889758D03*
X1817863Y880125D03*
X1785603Y887495D03*
X1780763Y875525D03*
X1754300Y1031850D03*
X1807000Y1038500D03*
X1813500Y969500D03*
X1803750Y978100D03*
X1813500Y960750D03*
X1803950Y1071600D03*
X1729500Y1312000D03*
X1765596Y1414627D03*
X1748126Y1411500D03*
X1807626Y1485700D03*
X1797426Y1470400D03*
X1813826Y1471000D03*
X1800326Y1449600D03*
X1794426Y1450328D03*
X1799626Y1489800D03*
X1802526Y1471300D03*
X1874500Y73700D03*
X1822428Y77200D03*
X1878600Y24150D03*
X1862900Y34200D03*
X1862750Y73500D03*
X1818900Y88800D03*
X1878700Y19000D03*
X1876700Y42250D03*
X1835000Y25500D03*
Y20700D03*
X1874000Y146000D03*
X1830500Y163500D03*
X1860500Y147500D03*
X1878600Y132600D03*
X1830000Y101000D03*
X1836769Y355648D03*
X1839077Y346085D03*
X1852223Y303000D03*
X1876150Y525950D03*
X1853250Y522200D03*
X1833000Y533500D03*
X1857500Y558000D03*
X1859250Y531162D03*
X1821000Y533500D03*
X1849750Y518000D03*
X1858000Y510750D03*
X1860109Y497977D03*
X1874000Y599000D03*
X1830500Y616500D03*
X1860500Y600500D03*
X1878600Y585100D03*
X1846032Y746970D03*
X1838174Y829350D03*
X1863781Y821477D03*
X1859841Y798979D03*
X1849032Y827393D03*
X1866318Y948540D03*
X1829563Y904041D03*
X1827763Y869025D03*
X1821363Y893425D03*
X1871900Y988200D03*
X1878300Y1038300D03*
X1853250Y975200D03*
X1834000Y986000D03*
X1857500Y1010000D03*
X1859250Y983276D03*
X1821000Y986000D03*
X1849750Y971000D03*
X1858000Y963750D03*
X1874000Y1052000D03*
X1830500Y1069000D03*
X1860500Y1053500D03*
X1825059Y1476665D03*
X1825826Y1486750D03*
G54D44*
X90709Y1485118D03*
X80709D03*
X70709D03*
X711181D03*
X701181D03*
X691181D03*
X1237953D03*
X1227953D03*
X1217953D03*
X1858425D03*
X1848425D03*
X1838425D03*
G54D27*
X67800Y95000D03*
Y547500D03*
Y1000500D03*
X148100Y25200D03*
X191800Y547500D03*
X111228Y873035D03*
X192300Y1000500D03*
X209055Y435299D03*
X316300Y95000D03*
Y547500D03*
Y1000500D03*
X440300Y547500D03*
Y1000500D03*
X405800Y1408000D03*
X564800Y95000D03*
Y547500D03*
Y1000500D03*
X510800Y1474500D03*
X528500Y1448100D03*
X688800Y547500D03*
Y1000500D03*
X943800Y890000D03*
X1013300Y846500D03*
X1004107Y895075D03*
X993724Y891165D03*
X1117412Y1402773D03*
X1305100Y63900D03*
X1306900Y534000D03*
X1307900Y986200D03*
X1431400Y533900D03*
Y986400D03*
X1555500Y63300D03*
Y533800D03*
X1555800Y986600D03*
X1680100Y534100D03*
X1679700Y986300D03*
X1814900Y24800D03*
X1751824Y438717D03*
X1804100Y534100D03*
X1763300Y579500D03*
X1803800Y986200D03*
X1859300Y547500D03*
X1826228Y873035D03*
X1859300Y1000500D03*
G54D18*
X72500Y63800D03*
Y516300D03*
Y969300D03*
X102263Y912325D03*
X162374Y1428000D03*
X180374Y1416800D03*
X162274Y1419400D03*
X180374Y1409150D03*
X139374Y1478300D03*
X105474Y1473285D03*
X215500Y73800D03*
X220000D03*
X202800Y37500D03*
X200090Y474589D03*
X196500Y516300D03*
X197000Y969300D03*
X321000Y63800D03*
Y516300D03*
Y969300D03*
X464000Y73800D03*
X468500D03*
X444400Y35800D03*
X435100Y118900D03*
X445000Y516300D03*
Y969300D03*
X569500Y63800D03*
Y516300D03*
Y969300D03*
X500000Y1465300D03*
X672000Y1422300D03*
X655795Y1436719D03*
X653000Y1481300D03*
X712500Y73800D03*
X717000D03*
X699600Y37400D03*
X693500Y516300D03*
Y969300D03*
X689000Y1422300D03*
X681000D03*
X703500Y1429300D03*
X680500Y1476300D03*
X730232Y1461319D03*
X752832Y1458319D03*
X860298Y410392D03*
X862766Y421192D03*
X850947Y410392D03*
X830470Y924230D03*
X826470D03*
X818470D03*
X826470Y974230D03*
X839970D03*
X834470D03*
X872137Y421192D03*
X950639Y547041D03*
X947587Y520682D03*
X871240Y635740D03*
X868500Y799600D03*
X957500Y845800D03*
X944000D03*
X935000D03*
X939500D03*
X927260Y915670D03*
X915580Y860670D03*
X922760Y915670D03*
X909760D03*
X924670Y860640D03*
X920170D03*
X955500Y1226300D03*
X947500D03*
X943500D03*
X869937Y1386929D03*
X944016Y1445572D03*
X991129Y547701D03*
X987333Y523068D03*
X962000Y845800D03*
X977570Y831728D03*
X973070D03*
X983070Y829790D03*
X1005450Y842060D03*
X1000950D03*
X1029600Y853600D03*
X985542Y876100D03*
X989742D03*
X972042Y877800D03*
X1030515Y883281D03*
X1033315Y890881D03*
X1039500Y883300D03*
X1048000Y890300D03*
X967500Y1226300D03*
X963500D03*
X1010943Y1417199D03*
X979443Y1411199D03*
X988443Y1410199D03*
X996443D03*
X963238Y1424618D03*
X1017618Y1464165D03*
X994271Y1464217D03*
X1021618Y1464165D03*
X1038303Y1444949D03*
X1040663Y1464441D03*
X1115825Y618543D03*
X1055500Y890300D03*
X1060118Y1381389D03*
X1126112Y1366573D03*
X1130112D03*
X1223730Y1289083D03*
X1235600D03*
X1230600D03*
X1190524D03*
X1197394D03*
X1202394D03*
X1241600Y1340083D03*
X1227100D03*
X1208394D03*
X1193894D03*
X1303500Y38300D03*
X1307500Y504800D03*
Y957300D03*
X1319500Y1416800D03*
Y1409150D03*
X1251874Y1480985D03*
X1431500Y51800D03*
Y504800D03*
Y957300D03*
X1553000Y38300D03*
X1556000Y504800D03*
Y957300D03*
X1680000Y51800D03*
Y504800D03*
Y957300D03*
X1707626Y1416800D03*
Y1409150D03*
X1652510Y1453300D03*
X1799100Y75100D03*
X1808500Y61000D03*
X1803400Y50400D03*
X1808300Y50500D03*
X1804000Y504800D03*
X1742859Y478007D03*
X1817263Y912325D03*
X1804000Y957300D03*
X1807676Y1478360D03*
X1880500Y42300D03*
X1872900D03*
X1874900Y21800D03*
X1863000Y507300D03*
Y960300D03*
G54D81*
X690000Y1453500D03*
X997443Y1441399D03*
G54D63*
X113314Y1452450D03*
X115874D03*
X118434D03*
Y1458950D03*
X113314D03*
X741572Y1438184D03*
X744132D03*
X746692D03*
Y1444684D03*
X741572D03*
X1030003Y1444649D03*
X1027443D03*
X1024883D03*
Y1438149D03*
X1030003D03*
X1259614Y1457550D03*
X1262174D03*
X1264734D03*
Y1464050D03*
X1259614D03*
X1796666Y1456950D03*
X1799226D03*
X1801786D03*
Y1463450D03*
X1796666D03*
G54D36*
X93500Y136500D03*
Y125500D03*
Y589000D03*
Y578000D03*
Y1042000D03*
Y1031000D03*
X217500Y136500D03*
Y125500D03*
Y589000D03*
Y578000D03*
X218000Y1042000D03*
Y1031000D03*
X342000Y136500D03*
Y125500D03*
Y589000D03*
Y578000D03*
Y1042000D03*
Y1031000D03*
X466000Y136500D03*
Y125500D03*
Y589000D03*
Y578000D03*
Y1042000D03*
Y1031000D03*
X590500Y136500D03*
Y125500D03*
Y589000D03*
Y578000D03*
Y1042000D03*
Y1031000D03*
X714500Y136500D03*
Y125500D03*
Y589000D03*
Y578000D03*
Y1042000D03*
Y1031000D03*
X1308500Y150500D03*
Y139500D03*
Y603500D03*
Y592500D03*
Y1045000D03*
Y1056000D03*
X1432500Y150500D03*
Y139500D03*
Y603500D03*
Y592500D03*
Y1045000D03*
Y1056000D03*
X1557000Y150500D03*
Y139500D03*
Y603500D03*
Y592500D03*
Y1045000D03*
Y1056000D03*
X1681000Y150500D03*
Y139500D03*
Y603500D03*
Y592500D03*
Y1045000D03*
Y1056000D03*
X1805000Y150500D03*
Y139500D03*
Y603500D03*
Y592500D03*
Y1045000D03*
Y1056000D03*
X1885000Y136000D03*
Y125000D03*
Y589000D03*
Y578000D03*
Y1042000D03*
Y1031000D03*
G54D54*
X127600Y126200D03*
X158474Y1422900D03*
X153374Y1457300D03*
Y1438800D03*
X250900Y126400D03*
X375500D03*
X440849Y118900D03*
X499900Y126300D03*
X624000D03*
X668000Y1425800D03*
X672500Y1479800D03*
X748200Y579100D03*
X698500Y1425800D03*
X685000D03*
X693000D03*
X735232Y1447134D03*
X990100Y833300D03*
X1026515Y886781D03*
X1000443Y1413699D03*
X992443D03*
X975443Y1414699D03*
X1005943Y1413699D03*
X971438Y1453708D03*
X1035943Y1431699D03*
X1207440Y1424654D03*
X1266600Y126400D03*
Y579100D03*
X1266400Y1031800D03*
X1300374Y1457300D03*
Y1438800D03*
X1253374Y1466700D03*
X1391200Y126400D03*
X1390400Y579100D03*
X1391000Y1031900D03*
X1515400Y126400D03*
X1515200Y579100D03*
X1515400Y1031900D03*
X1639300Y126400D03*
X1638200Y579100D03*
X1639100Y1031900D03*
X1680626Y1457300D03*
Y1438800D03*
X1763600Y126400D03*
X1763300Y1031900D03*
X1790226Y1465900D03*
X1879800Y988300D03*
G54D90*
X903125Y758850D03*
X910875D03*
X907000Y766350D03*
X874000Y1205650D03*
X870125Y1198150D03*
X877875D03*
G54D72*
X627499Y1306804D03*
X659901D03*
Y1398896D03*
X627499D03*
X948099Y1340696D03*
X980501D03*
G54D45*
G01X99823Y84370D02*
X106937D01*
G01X99823Y93819D02*
X106937D01*
G01X92250Y77000D02*
Y80500D01*
G01X56750Y65500D02*
Y62000D01*
G01X64250Y91000D02*
Y87500D01*
G01X92250Y72400D02*
X95200D01*
X95800Y71800D01*
G01X95500Y182000D02*
Y186000D01*
G01X94000Y162700D02*
X89000D01*
G01X54200Y140500D02*
X49500D01*
G01X99823Y103268D02*
X106937D01*
G01X64250Y95000D02*
Y98500D01*
G01X73500Y120500D02*
Y126000D01*
G01X76500Y133000D02*
X72900D01*
G01X56750Y96500D02*
Y100500D01*
G01X55209Y383528D02*
Y379278D01*
G01X69942Y403305D02*
Y406555D01*
G01X58709Y397128D02*
Y393187D01*
X58728Y393206D01*
G01X65692Y392187D02*
Y396596D01*
G01X84567Y394346D02*
Y397932D01*
X84581Y397946D01*
G01X79567Y394346D02*
Y397932D01*
X79581Y397946D01*
G01X99823Y556024D02*
X106937D01*
G01X99823Y537126D02*
X106937D01*
G01X99823Y546575D02*
X106937D01*
G01X64250Y547500D02*
Y551000D01*
G01X92250Y529500D02*
Y533000D01*
G01X64250Y543500D02*
Y540000D01*
G01X56750Y549000D02*
Y553000D01*
G01Y518000D02*
X53250D01*
G01X92050Y525300D02*
X95300D01*
X95500Y525500D01*
G01Y634500D02*
Y638500D01*
G01X94000Y615200D02*
X89000D01*
G01X73500Y573000D02*
Y578500D01*
G01X54200Y593000D02*
X49500D01*
G01X76400Y585500D02*
X72800D01*
G01X42942Y836182D02*
Y831932D01*
G01X53425Y853600D02*
Y849250D01*
G01X57675Y851609D02*
Y855959D01*
G01X46442Y849782D02*
Y853363D01*
X46461Y853382D01*
G01X73500Y846500D02*
Y850074D01*
X73526Y850100D01*
G01X68500Y846500D02*
Y850074D01*
X68526Y850100D01*
G01X94513Y908025D02*
Y903775D01*
X94263Y903525D01*
G01X94513Y908025D02*
X92747Y909791D01*
X91114D01*
G01X94263Y903525D02*
X93605Y902867D01*
Y899023D01*
G01X94794Y872375D02*
X102103D01*
X102763Y873035D01*
G01X95263Y886125D02*
X99538Y890400D01*
X102083D01*
X102207Y890524D01*
G01X102863Y880125D02*
X95263D01*
G01X73500Y1026000D02*
Y1031500D01*
G01X54200Y1046000D02*
X49500D01*
G01X64250Y1000500D02*
Y1004000D01*
G01X92250Y982500D02*
Y986000D01*
G01X99823Y1008780D02*
X106937D01*
G01X99823Y989882D02*
X106937D01*
G01X99823Y999331D02*
X106937D01*
G01X76300Y1038400D02*
X72600D01*
G01X56750Y1002000D02*
Y1006000D01*
G01X64250Y996500D02*
Y993000D01*
G01X56750Y971000D02*
X53250D01*
G01X92250Y972500D02*
X95500D01*
G01Y1087500D02*
Y1091500D01*
G01X94000Y1068200D02*
X89000D01*
G01X118209Y81319D02*
X111437D01*
G01X118209Y66319D02*
X111437D01*
G01X118209Y51319D02*
X111437D01*
G01X111024Y27697D02*
X118437D01*
G01X150700Y29300D02*
Y33100D01*
G01X148050Y25200D02*
Y20971D01*
G01X157050Y32100D02*
Y35450D01*
X157400Y35800D01*
G01X160750Y25100D02*
X158200D01*
X157600Y24500D01*
G01X160750Y21100D02*
Y20750D01*
X157900Y17900D01*
G01X171850Y29200D02*
X175050D01*
X175650Y28600D01*
G01Y20900D02*
Y25100D01*
G01D02*
Y28600D01*
G01X118209Y161319D02*
X111437D01*
G01X118209Y151319D02*
X111437D01*
G01X178200Y140500D02*
X173500D01*
G01X118209Y131319D02*
X111437D01*
G01X118209Y121319D02*
X111437D01*
G01X127600Y122650D02*
Y119300D01*
G01X131600Y122650D02*
Y119100D01*
G01X111024Y199941D02*
X118437D01*
G01X189342Y383182D02*
Y378932D01*
G01X192842Y396782D02*
Y400463D01*
X192861Y400482D01*
G01X192340Y470289D02*
Y466039D01*
X192090Y465789D01*
G01X192340Y470289D02*
X190574Y472055D01*
X188941D01*
G01X192090Y465789D02*
X191432Y465131D01*
Y461287D01*
G01X199590Y434639D02*
X192621D01*
G01X193090Y448389D02*
X193390D01*
X197942Y452941D01*
X200022D01*
G01X201190Y442389D02*
X193090D01*
G01X118209Y534075D02*
X111437D01*
G01X118209Y519075D02*
X111437D01*
G01X118209Y504075D02*
X111437D01*
G01X111024Y480453D02*
X118437D01*
G01X188250Y547500D02*
Y550951D01*
G01Y543500D02*
Y540000D01*
G01X180750Y518000D02*
X179100D01*
X176439Y520661D01*
Y524992D01*
G01X180750Y549000D02*
Y553000D01*
G01X111024Y652697D02*
X118437D01*
G01X118209Y614075D02*
X111437D01*
G01X118209Y604075D02*
X111437D01*
G01X118209Y584075D02*
X111437D01*
G01X118209Y574075D02*
X111437D01*
G01X178200Y593000D02*
X173500D01*
G01X140750Y579000D02*
Y575500D01*
G01Y583000D02*
Y584750D01*
X143000Y587000D01*
G01X176425Y853700D02*
Y849250D01*
G01X167842Y844782D02*
X172318D01*
G01X177058Y835918D02*
Y831500D01*
X176558Y831000D01*
G01X180675Y855659D02*
Y852575D01*
X180400Y852300D01*
G01X191000Y846500D02*
Y850074D01*
X191026Y850100D01*
G01X111024Y933209D02*
X118437D01*
G01X102263Y919025D02*
Y915775D01*
G01X109772Y903550D02*
Y901016D01*
X122763Y888025D01*
X129298D01*
G01X158900Y885700D02*
X131623D01*
X129298Y888025D01*
G01X111178Y873035D02*
Y870610D01*
X112763Y869025D01*
G01X113763Y865025D02*
Y868025D01*
X112763Y869025D01*
G01X107678Y873035D02*
X102763D01*
G01X107706Y878062D02*
X104926D01*
X102863Y880125D01*
G01X178700Y1046000D02*
X174000D01*
G01X118209Y1036831D02*
X111437D01*
G01X118209Y1026831D02*
X111437D01*
G01X188750Y1000500D02*
Y1004000D01*
G01X118209Y956831D02*
X111437D01*
G01X118209Y986831D02*
X111437D01*
G01X118209Y971831D02*
X111437D01*
G01X140750Y1032000D02*
Y1028500D01*
G01X181250Y1002000D02*
Y1006000D01*
G01X188750Y996500D02*
Y993000D01*
G01X181250Y971000D02*
X180300D01*
X178200Y973100D01*
Y977700D01*
G01X140750Y1036000D02*
Y1039250D01*
G01X111024Y1105453D02*
X118437D01*
G01X118209Y1066831D02*
X111437D01*
G01X118209Y1056831D02*
X111437D01*
G01X138974Y1429150D02*
X132632D01*
X131143Y1427661D01*
G01X167499Y1434000D02*
Y1429250D01*
G01D02*
X166199Y1427950D01*
X162374D01*
G01X158474Y1419350D02*
Y1416010D01*
X158484Y1416000D01*
G01X184874Y1416500D02*
Y1412600D01*
G01D02*
Y1408800D01*
G01D02*
X183138D01*
X182838Y1409100D01*
X180374D01*
G01X174374Y1401900D02*
X177974D01*
X180374Y1404300D01*
Y1409100D01*
G01X184874Y1416500D02*
X188174D01*
X188274Y1416600D01*
G01X162274Y1422850D02*
X165624D01*
X165774Y1422700D01*
G01X158474Y1422850D02*
X162274D01*
G01X156459Y1424388D02*
X157997Y1422850D01*
X158474D01*
G01X142124Y1452500D02*
X145374D01*
G01X153374Y1435250D02*
X156509D01*
X156674Y1435085D01*
G01X142124Y1434000D02*
X142809Y1434685D01*
X145274D01*
G01X153374Y1453750D02*
X157324D01*
X157574Y1453500D01*
G01X107474Y1462150D02*
X106697D01*
X106647Y1462200D01*
X104374D01*
X104074Y1462500D01*
G01X149374Y1453750D02*
Y1452300D01*
X151874Y1449800D01*
G01X140224Y1464000D02*
X135374D01*
G01X140224Y1445500D02*
X135374D01*
G01X149374Y1435250D02*
Y1432167D01*
X149955Y1431586D01*
Y1431573D01*
G01X129124Y1484200D02*
X132674D01*
G01X142396Y1481750D02*
X139374D01*
G01D02*
Y1486100D01*
G01X104184Y1457200D02*
Y1457210D01*
X105624Y1458650D01*
X107474D01*
G01X198750Y82500D02*
X202500D01*
G01X224035Y93819D02*
X231149D01*
G01X242421Y81319D02*
X235649D01*
G01X242421Y66319D02*
X235649D01*
G01X207000Y77250D02*
Y80500D01*
G01X242421Y51319D02*
X235649D01*
G01X235236Y27697D02*
X242649D01*
G01X224035Y84370D02*
X229630D01*
X231000Y83000D01*
Y82000D01*
G01X198750Y78500D02*
X200819Y76431D01*
Y74819D01*
G01X217000Y41750D02*
Y38250D01*
G01X198800Y37450D02*
Y34000D01*
G01X202800Y37450D02*
X203078Y37172D01*
Y33972D01*
G01X215500Y77250D02*
Y80500D01*
G01X242421Y161319D02*
X235649D01*
G01X242421Y151319D02*
X235649D01*
G01X219500Y182000D02*
Y186000D01*
G01X218500Y162700D02*
X213500D01*
G01X242421Y131319D02*
X235649D01*
G01X242421Y121319D02*
X235649D01*
G01X224035Y103268D02*
X231149D01*
G01X197500Y120500D02*
Y126000D01*
G01X250900Y122850D02*
Y119500D01*
G01X200800Y133000D02*
X197000D01*
G01X254900Y122850D02*
Y119600D01*
G01X235236Y199941D02*
X242649D01*
G01X204075Y402959D02*
Y398609D01*
G01X199825Y400700D02*
Y396350D01*
G01X218200Y394000D02*
Y397586D01*
X218214Y397600D01*
G01X213200Y394000D02*
Y397586D01*
X213214Y397600D01*
G01X220590Y450289D02*
X227434D01*
G01X207599Y465814D02*
Y463280D01*
G01D02*
Y463274D01*
X220584Y450289D01*
X220590D01*
G01X227434D02*
X228470Y449253D01*
X246947D01*
G01D02*
X247836Y448364D01*
X257127D01*
G01X211590Y427289D02*
X210590Y428289D01*
Y431439D01*
X210596Y431445D01*
G01X209005Y435299D02*
X210590Y433714D01*
Y431451D01*
X210596Y431445D01*
G01X209033Y440326D02*
Y445032D01*
X211190Y447189D01*
G01X205505Y435299D02*
X204845Y434639D01*
X199590D01*
G01X205533Y440326D02*
X203470Y442389D01*
X201190D01*
G01X224035Y556024D02*
X231149D01*
G01X224035Y546575D02*
X231149D01*
G01X242421Y534075D02*
X235649D01*
G01X242421Y519075D02*
X235649D01*
G01X242421Y504075D02*
X235649D01*
G01X235236Y480453D02*
X242649D01*
G01X216250Y529500D02*
Y533000D01*
G01X224035Y537126D02*
X232433D01*
G01X200090Y481289D02*
Y478039D01*
G01X216150Y525200D02*
X218800D01*
X220000Y524000D01*
G01X235236Y652697D02*
X242649D01*
G01X242421Y614075D02*
X235649D01*
G01X218500Y615200D02*
X213500D01*
G01X219500Y634500D02*
Y638500D01*
G01X242421Y604075D02*
X235649D01*
G01X242421Y584075D02*
X235649D01*
G01X242421Y574075D02*
X235649D01*
G01X197500Y573000D02*
Y578500D01*
G01X200800Y585500D02*
X197200D01*
G01X264750Y579000D02*
X264752Y578998D01*
X268187D01*
G01X264750Y583000D02*
Y586250D01*
G01X196000Y846500D02*
Y850074D01*
X196026Y850100D01*
G01X235236Y933209D02*
X242649D01*
G01X198000Y1026000D02*
Y1031500D01*
G01X242421Y1036831D02*
X235649D01*
G01X242421Y1026831D02*
X235649D01*
G01X216750Y982500D02*
Y986000D01*
G01X224035Y1008780D02*
X231149D01*
G01X224035Y989882D02*
X231149D01*
G01X224035Y999331D02*
X231149D01*
G01X242421Y986831D02*
X235649D01*
G01X242421Y971831D02*
X235649D01*
G01X264450Y1032000D02*
Y1028700D01*
X264250Y1028500D01*
G01X200900Y1038500D02*
X197300D01*
G01X242421Y956831D02*
X249831D01*
X252100Y959100D01*
G01X264450Y1036000D02*
Y1039250D01*
G01X216750Y978100D02*
X219900D01*
X220000Y978200D01*
G01X235236Y1105453D02*
X242649D01*
G01X220000Y1087500D02*
Y1091500D01*
G01X218500Y1068200D02*
X213500D01*
G01X242421Y1066831D02*
X235649D01*
G01X242421Y1056831D02*
X235649D01*
G01X209174Y1410800D02*
Y1415900D01*
X209374Y1416100D01*
Y1416300D01*
G01X217322Y1460477D02*
Y1466929D01*
G01D02*
Y1473381D01*
G01X210870Y1466929D02*
X217322D01*
G01D02*
X223774D01*
G01X217322Y1438823D02*
Y1445275D01*
G01D02*
Y1451727D01*
G01X210870Y1445275D02*
X217322D01*
G01D02*
X223774D01*
G01X348248Y84370D02*
X355362D01*
G01X348248Y93819D02*
X355362D01*
G01X366634Y81319D02*
X359862D01*
G01X366634Y66319D02*
X359862D01*
G01X340750Y77000D02*
Y80500D01*
G01X366634Y51319D02*
X359862D01*
G01X359449Y27697D02*
X366862D01*
G01X312750Y91000D02*
Y84650D01*
X311800Y83700D01*
G01X305250Y65500D02*
X301750D01*
G01X340650Y72600D02*
Y69300D01*
G01X366634Y161319D02*
X359862D01*
G01X366634Y151319D02*
X359862D01*
G01X344000Y182000D02*
Y186000D01*
G01X342500Y162700D02*
X337500D01*
G01X302700Y140500D02*
X298000D01*
G01X366634Y131319D02*
X359862D01*
G01X348248Y103268D02*
X355362D01*
G01X312750Y95000D02*
Y98500D01*
G01X322000Y120500D02*
Y126000D01*
G01X375500Y122850D02*
Y119400D01*
G01X325100Y133000D02*
X321500D01*
G01X366634Y121319D02*
X359680D01*
X357506Y123493D01*
G01X305250Y96500D02*
Y100500D01*
G01X379500Y122850D02*
Y119500D01*
G01X359449Y199941D02*
X366862D01*
G01X291042Y383482D02*
Y379232D01*
G01X305775Y403259D02*
Y398909D01*
G01X294542Y397082D02*
Y400663D01*
X294561Y400682D01*
G01X301525Y400900D02*
Y396550D01*
G01X320500Y394000D02*
Y397586D01*
X320514Y397600D01*
G01X315500Y394000D02*
Y397586D01*
X315514Y397600D01*
G01X348248Y556024D02*
X355362D01*
G01X348248Y537126D02*
X355362D01*
G01X348248Y546575D02*
X355362D01*
G01X312750Y547500D02*
Y551000D01*
G01X366634Y534075D02*
X359862D01*
G01X366634Y519075D02*
X359862D01*
G01X366634Y504075D02*
X359862D01*
G01X359449Y480453D02*
X366862D01*
G01X340750Y529500D02*
Y533000D01*
G01X312750Y543500D02*
Y536300D01*
G01X305250Y549000D02*
Y553000D01*
G01Y518000D02*
X301750D01*
G01X344000Y525300D02*
X340750D01*
G01X366634Y614075D02*
X359862D01*
G01X359449Y652697D02*
X366862D01*
G01X344000Y634500D02*
Y638500D01*
G01X342500Y615200D02*
X337500D01*
G01X366634Y604075D02*
X359862D01*
G01X366634Y584075D02*
X359862D01*
G01X322000Y573000D02*
Y578500D01*
G01X302700Y593000D02*
X298000D01*
G01X325100Y585500D02*
X323380Y587220D01*
Y589452D01*
G01X366634Y574075D02*
X373149D01*
X374261Y572963D01*
G01X291042Y836182D02*
Y831932D01*
G01X305775Y851609D02*
Y855959D01*
G01X301525Y853600D02*
Y849250D01*
G01X294542Y849782D02*
Y853363D01*
X294561Y853382D01*
G01X320500Y846500D02*
Y850074D01*
X320526Y850100D01*
G01X315500Y846500D02*
Y850074D01*
X315526Y850100D01*
G01X359449Y933209D02*
Y925451D01*
X359500Y925400D01*
G01X366634Y1036831D02*
X359862D01*
G01X366634Y1026831D02*
X359862D01*
G01X322000Y1026000D02*
Y1031500D01*
G01X302700Y1046000D02*
X298000D01*
G01X348248Y1008780D02*
X355362D01*
G01X348248Y989882D02*
X355362D01*
G01X348248Y999331D02*
X355362D01*
G01X366634Y986831D02*
X359862D01*
G01X366634Y971831D02*
X359862D01*
G01X312750Y1000500D02*
Y1004000D01*
G01X340750Y982500D02*
Y986000D01*
G01X324900Y1038500D02*
X321200D01*
G01X366634Y956831D02*
X359731D01*
X358800Y955900D01*
G01X305250Y1002000D02*
Y1006000D01*
G01X312750Y996500D02*
Y993000D01*
G01X305250Y971000D02*
X305100D01*
X302100Y974000D01*
Y978200D01*
G01X340650D02*
X344200D01*
G01X359449Y1105453D02*
X366862D01*
G01X366634Y1066831D02*
X359862D01*
G01X366634Y1056831D02*
X359862D01*
G01X344000Y1087500D02*
Y1091500D01*
G01X342500Y1068200D02*
X337500D01*
G01X466941Y-145664D02*
Y-225664D01*
G01D02*
X1593241D01*
G01X462941Y-129664D02*
G02I-12000J0D01*
G01X457791D02*
G02I-6850J0D01*
G01X450941Y-145664D02*
Y-113664D01*
G01X466941Y-129664D02*
X434941D01*
G01X466941Y-145664D02*
X1593241D01*
G01X466941Y-181164D02*
X1593241D01*
G01X472460Y84370D02*
X479574D01*
G01X472460Y93819D02*
X479574D01*
G01X454000Y80650D02*
Y83800D01*
G01X465500Y41750D02*
Y38250D01*
G01X444400Y35750D02*
Y32680D01*
X444663Y32417D01*
G01X440400Y35750D02*
Y32400D01*
G01X464000Y77250D02*
Y80500D01*
G01X467000Y162700D02*
X462000D01*
G01X468000Y182000D02*
Y186000D01*
G01X426700Y140500D02*
X422000D01*
G01X472460Y103268D02*
X479574D01*
G01X441300Y126000D02*
X446000D01*
G01X449100Y133000D02*
X445500D01*
G01X440849Y115350D02*
Y111648D01*
G01X430083Y122357D02*
X435093D01*
X435100Y122350D01*
G01X415542Y383182D02*
Y378932D01*
G01X419042Y396782D02*
Y400363D01*
X419061Y400382D01*
G01X426025Y400700D02*
Y396350D01*
G01X430275Y399351D02*
Y402959D01*
G01X445000Y394000D02*
Y397586D01*
X445014Y397600D01*
G01X440000Y394000D02*
Y397586D01*
X440014Y397600D01*
G01X472460Y556024D02*
X479574D01*
G01X472460Y537126D02*
X479574D01*
G01X472460Y546575D02*
X479574D01*
G01X436750Y547500D02*
Y551000D01*
G01X464750Y529500D02*
Y533000D01*
G01X436750Y543500D02*
Y538400D01*
G01X429250Y549000D02*
Y553000D01*
G01Y518000D02*
Y513032D01*
X429210Y512992D01*
G01X464750Y525300D02*
X464801D01*
Y521156D01*
G01X468000Y634500D02*
Y638500D01*
G01X389250Y579000D02*
Y575500D01*
G01X441641Y574141D02*
X446000Y578500D01*
G01X449400Y585500D02*
X446067D01*
X445546Y586021D01*
G01X426700Y593000D02*
X422461D01*
X421820Y593641D01*
G01X467000Y615200D02*
Y610804D01*
X467029Y610775D01*
G01X389250Y583000D02*
Y587242D01*
X390632Y588624D01*
G01X429975Y851409D02*
Y855659D01*
G01X425725Y853400D02*
Y849050D01*
G01X415242Y831882D02*
Y835876D01*
G01X418742Y849482D02*
Y853063D01*
X418761Y853082D01*
G01X440000Y846500D02*
Y850074D01*
X440026Y850100D01*
G01X445000Y846500D02*
Y850074D01*
X445026Y850100D01*
G01X446000Y1026000D02*
Y1031500D01*
G01X426700Y1046000D02*
X422000D01*
G01X436750Y1000500D02*
Y1004000D01*
G01X464750Y982500D02*
Y986000D01*
G01X472460Y1008780D02*
X479574D01*
G01X472460Y989882D02*
X479574D01*
G01X472460Y999331D02*
X479574D01*
G01X389250Y1032000D02*
Y1028500D01*
G01X448900Y1038500D02*
X445100D01*
G01X429250Y1002000D02*
Y1006000D01*
G01X436750Y996500D02*
Y993000D01*
G01X429250Y971000D02*
X428500D01*
X426300Y973200D01*
Y976800D01*
G01X389250Y1036000D02*
Y1039250D01*
G01X464650Y978000D02*
X468300D01*
G01X468000Y1087500D02*
Y1091500D01*
G01X467000Y1068200D02*
X462000D01*
G01X393600Y1409800D02*
X395400Y1408000D01*
G01D02*
X402250D01*
G01X414300Y1407700D02*
X414000Y1408000D01*
G01D02*
X405750D01*
G01X490846Y81319D02*
X484074D01*
G01X490846Y66319D02*
X484074D01*
G01X490846Y51319D02*
X484074D01*
G01X483661Y27697D02*
X491074D01*
G01X561250Y91000D02*
Y87500D01*
G01X553750Y65500D02*
X550250D01*
G01X551200Y140500D02*
X546500D01*
G01X490846Y161319D02*
X484074D01*
G01X490846Y151319D02*
X484074D01*
G01X561250Y95000D02*
Y98500D01*
G01X570500Y120500D02*
Y126000D01*
G01X490846Y131319D02*
X484074D01*
G01X490846Y121319D02*
X484074D01*
G01X499900Y122750D02*
Y119400D01*
G01X573600Y133000D02*
X569900D01*
G01X553750Y96500D02*
Y100500D01*
G01X503900Y119500D02*
Y122750D01*
G01X483661Y199941D02*
X491074D01*
G01X539742Y383482D02*
Y379232D01*
G01X543242Y400682D02*
Y397082D01*
G01X554475Y399651D02*
Y403259D01*
G01X550225Y400900D02*
Y396550D01*
G01X569000Y394000D02*
Y397586D01*
X569014Y397600D01*
G01X564000Y394000D02*
Y397586D01*
X564014Y397600D01*
G01X561250Y547500D02*
Y551000D01*
G01X490846Y504075D02*
X484074D01*
G01X483661Y480453D02*
X491074D01*
G01X490846Y519075D02*
X484074D01*
G01X490846Y534075D02*
X485350D01*
X483513Y535912D01*
G01X553750Y549000D02*
Y553000D01*
G01X561250Y543500D02*
Y540000D01*
G01X553750Y518000D02*
X550250D01*
G01X483661Y652697D02*
X491074D01*
G01X490846Y614075D02*
X484074D01*
G01X490846Y584075D02*
X484074D01*
G01X490846Y574075D02*
X484074D01*
G01X573500Y585500D02*
X569900D01*
G01X513250Y579000D02*
Y574252D01*
G01X490846Y604075D02*
X485433D01*
X483265Y606243D01*
G01X570500Y578500D02*
X565331D01*
X565279Y578552D01*
G01X551200Y593000D02*
Y597849D01*
X551276Y597925D01*
G01X513250Y583000D02*
X517984D01*
X517999Y583015D01*
G01X569000Y846500D02*
Y850074D01*
X569026Y850100D01*
G01X564000Y846500D02*
Y850074D01*
X564026Y850100D01*
G01X483661Y933209D02*
Y925676D01*
X483549Y925564D01*
G01X570500Y1026000D02*
Y1031500D01*
G01X551200Y1046000D02*
X546500D01*
G01X490846Y1036831D02*
X484074D01*
G01X490846Y1026831D02*
X484074D01*
G01X561250Y1000500D02*
Y1004000D01*
G01X490846Y986831D02*
X484074D01*
G01X490846Y971831D02*
X484074D01*
G01X513250Y1032000D02*
Y1028500D01*
G01X573500Y1038500D02*
X569900D01*
G01X490846Y956831D02*
X499800D01*
G01X553750Y1002000D02*
Y1006000D01*
G01X561250Y996500D02*
Y993000D01*
G01X553750Y971000D02*
Y972450D01*
X550700Y975500D01*
Y979500D01*
G01X513250Y1036000D02*
Y1039250D01*
G01X483661Y1105453D02*
X491074D01*
G01X490846Y1066831D02*
X484074D01*
G01X490846Y1056831D02*
X484074D01*
G01X528500Y1444600D02*
X526500D01*
X524950Y1446150D01*
Y1448100D01*
G01X524750Y1467000D02*
X524236Y1466486D01*
Y1463672D01*
G01X500000Y1468750D02*
Y1472000D01*
G01X507250Y1474500D02*
Y1478000D01*
G01X535200Y1461250D02*
Y1466100D01*
G01X502999Y1451682D02*
X503001Y1451684D01*
Y1454922D01*
G01X524950Y1452100D02*
X523500Y1453550D01*
Y1455400D01*
G01X517500Y1458624D02*
X513624D01*
G01X507250Y1470500D02*
X504000D01*
G01X502999Y1448182D02*
Y1444367D01*
X503035Y1444331D01*
G01Y1438131D02*
Y1444331D01*
G01X508896Y1497800D02*
X508867Y1497771D01*
G01X596673Y84370D02*
X603787D01*
G01X596673Y93819D02*
X603787D01*
G01X615059Y81319D02*
X608287D01*
G01X615059Y66319D02*
X608287D01*
G01X589250Y77000D02*
Y80500D01*
G01X615059Y51319D02*
X608287D01*
G01X607874Y27697D02*
X615287D01*
G01X589150Y72800D02*
Y69500D01*
G01X675200Y140500D02*
X670500D01*
G01X615059Y161319D02*
X608287D01*
G01X615059Y151319D02*
X608287D01*
G01X592500Y182000D02*
Y186000D01*
G01X591000Y162700D02*
X586000D01*
G01X615059Y131319D02*
X608287D01*
G01X615059Y121319D02*
X608287D01*
G01X596673Y103268D02*
X603787D01*
G01X624000Y122750D02*
Y119400D01*
G01X628000Y122750D02*
Y119500D01*
G01X607874Y199941D02*
X615287D01*
G01X650742Y383182D02*
Y378932D01*
G01X654242Y396782D02*
Y400363D01*
X654261Y400382D01*
G01X665475Y399378D02*
Y402959D01*
G01X661225Y400738D02*
Y396350D01*
G01X596673Y556024D02*
X603787D01*
G01X596673Y537126D02*
X603787D01*
G01X596673Y546575D02*
X603787D01*
G01X615059Y534075D02*
X608287D01*
G01X615059Y519075D02*
X608287D01*
G01X615059Y504075D02*
X608287D01*
G01X607874Y480453D02*
X615287D01*
G01X589250Y529500D02*
Y533000D01*
G01X589150Y525400D02*
X592400D01*
X592500Y525300D01*
G01X607874Y652697D02*
X615287D01*
G01X592500Y634500D02*
Y638500D01*
G01X675200Y593000D02*
X670500D01*
G01X615059Y574075D02*
X608287D01*
G01X637750Y579000D02*
Y575500D01*
G01X591000Y615200D02*
X586805D01*
X586043Y615962D01*
G01X637750Y583000D02*
Y586250D01*
G01X656142Y835882D02*
Y831632D01*
G01X594055Y852609D02*
Y856859D01*
G01X589805Y854600D02*
Y850250D01*
G01X670875Y851409D02*
Y855659D01*
G01X666625Y853400D02*
Y849050D01*
G01X579148Y832411D02*
Y836405D01*
G01X659642Y849482D02*
Y853063D01*
X659661Y853082D01*
G01X582667Y853605D02*
X582648Y853586D01*
Y850005D01*
G01X607874Y933209D02*
X615287D01*
G01X675200Y1046000D02*
X670500D01*
G01X615059Y1036831D02*
X608287D01*
G01X615059Y1026831D02*
X608287D01*
G01X589250Y982500D02*
Y986000D01*
G01X596673Y1008780D02*
X603787D01*
G01X596673Y989882D02*
X603787D01*
G01X596673Y999331D02*
X603787D01*
G01X615059Y986831D02*
X608287D01*
G01X615059Y971831D02*
X608287D01*
G01X637750Y1032000D02*
Y1028500D01*
G01X615059Y956831D02*
X602800D01*
X601800Y955831D01*
Y955500D01*
G01X589250Y978100D02*
X592800D01*
G01X637750Y1036000D02*
X641200D01*
X643100Y1034100D01*
Y1011600D01*
X624500Y993000D01*
G01X607874Y1105453D02*
X615287D01*
G01X592500Y1087500D02*
Y1091500D01*
G01X615059Y1066831D02*
X608287D01*
G01X615059Y1056831D02*
X608287D01*
G01X591000Y1068200D02*
X586000D01*
G01X643445Y1425719D02*
X638290D01*
X637971Y1425400D01*
G01X653000Y1484750D02*
Y1488500D01*
G01X665250Y1444000D02*
X668000Y1446750D01*
Y1448500D01*
G01X597637Y1460477D02*
Y1466929D01*
G01D02*
Y1473381D01*
G01X591185Y1466929D02*
X597637D01*
G01D02*
X604089D01*
G01X597637Y1438823D02*
Y1445275D01*
G01D02*
Y1451727D01*
G01X591185Y1445275D02*
X597637D01*
G01D02*
X604089D01*
G01X643545Y1441419D02*
X637972D01*
G01X661750Y1444000D02*
X658000D01*
G01X628500Y1461250D02*
X624750D01*
G01X739272Y81319D02*
X732500D01*
G01X739272Y66319D02*
X732500D01*
G01X704000Y77250D02*
Y80500D01*
G01X695750Y82500D02*
X699500D01*
G01X739272Y51319D02*
X732500D01*
G01X732087Y27697D02*
X739500D01*
G01X720886Y93819D02*
X727599D01*
X727614Y93834D01*
X727636D01*
G01X720886Y84370D02*
X726286D01*
X729201Y87285D01*
G01X695750Y78500D02*
X697787Y76463D01*
Y74488D01*
G01X714000Y41750D02*
Y38250D01*
G01X695600Y37350D02*
Y34000D01*
G01X699600Y37350D02*
Y34366D01*
X699932Y34034D01*
G01X712500Y77250D02*
X710250Y79500D01*
X709000D01*
G01X747290Y118820D02*
Y118853D01*
X751750Y123313D01*
G01X739272Y161319D02*
X732500D01*
G01X739272Y151319D02*
X732500D01*
G01X716500Y182000D02*
Y186000D01*
G01X715300Y162700D02*
X710300D01*
G01X739272Y131319D02*
X732500D01*
G01X739272Y121319D02*
X732500D01*
G01X720886Y103268D02*
X728000D01*
G01X694500Y120500D02*
Y126000D01*
G01X697800Y133000D02*
X694200D01*
G01X751750Y126500D02*
Y123313D01*
G01Y130500D02*
Y136736D01*
X753473Y138459D01*
G01X732087Y199941D02*
Y207847D01*
G01X685500Y394000D02*
Y397586D01*
X685514Y397600D01*
G01X680500Y394000D02*
Y397586D01*
X680514Y397600D01*
G01X720886Y556024D02*
X728000D01*
G01X720886Y537126D02*
X728000D01*
G01X720886Y546575D02*
X728000D01*
G01X739272Y504075D02*
X732500D01*
G01X739272Y519075D02*
X732500D01*
G01X713250Y529500D02*
Y533000D01*
G01X739272Y534075D02*
X732500D01*
G01X685250Y547500D02*
Y548577D01*
X688298Y551625D01*
G01X732087Y480453D02*
X731247D01*
X724600Y487100D01*
G01X685250Y543500D02*
Y540000D01*
G01X677750Y549000D02*
Y553000D01*
G01Y518000D02*
X674250D01*
G01X713150Y525300D02*
X716300D01*
X716400Y525200D01*
G01X732087Y652697D02*
X739500D01*
G01X715300Y615200D02*
X710300D01*
G01X739272Y574075D02*
X732500D01*
G01X739272Y584075D02*
X732500D01*
G01X694500Y573000D02*
Y578500D01*
G01X697800Y585500D02*
X694200D01*
G01X748200Y575550D02*
Y572200D01*
G01X739272Y614075D02*
X745883D01*
X747843Y612115D01*
G01X739272Y604075D02*
X746356D01*
G01X716500Y634500D02*
X711200D01*
X710300Y635400D01*
G01X752200Y572300D02*
Y575550D01*
G01X685500Y846500D02*
Y850074D01*
X685526Y850100D01*
G01X680500Y846500D02*
Y850074D01*
X680526Y850100D01*
G01X732087Y933209D02*
X739500D01*
G01X677000Y885500D02*
X673000D01*
G01X677000D02*
X681800Y890300D01*
X773599D01*
X776099Y892800D01*
X815400D01*
G01X694500Y1026000D02*
Y1031500D01*
G01X739272Y1036831D02*
X732500D01*
G01X739272Y1026831D02*
X732500D01*
G01X685250Y1000500D02*
Y1004000D01*
G01X713250Y982500D02*
Y986000D01*
G01X720886Y1008780D02*
X728000D01*
G01X720886Y989882D02*
X728000D01*
G01X720886Y999331D02*
X728000D01*
G01X739272Y986831D02*
X732500D01*
G01X739272Y971831D02*
X732500D01*
G01X753050Y1032000D02*
Y1028500D01*
G01X697700Y1038500D02*
X694000D01*
G01X739272Y956831D02*
X731900D01*
X730900Y955831D01*
Y955800D01*
G01X677750Y1002000D02*
Y1006000D01*
G01X685250Y996500D02*
Y993000D01*
G01X677750Y971000D02*
X676800D01*
X675400Y972400D01*
Y980500D01*
G01X753150Y1036000D02*
X765700D01*
X767400Y1034300D01*
Y1004200D01*
X755600Y992400D01*
X755200D01*
G01X713350Y978300D02*
X716800D01*
G01X732087Y1105453D02*
X739500D01*
G01X716500Y1087500D02*
Y1091500D01*
G01X715300Y1068200D02*
X710300D01*
G01X739272Y1066831D02*
X732500D01*
G01X739272Y1056831D02*
X732500D01*
G01X724248Y1465560D02*
X722508Y1467300D01*
X715550D01*
G01X724000Y1443500D02*
Y1439700D01*
G01X714250Y1449700D02*
X717600D01*
G01X735232Y1443584D02*
Y1439334D01*
G01X715850Y1475800D02*
X721100D01*
X722200Y1476900D01*
G01X727250Y1453500D02*
X728500D01*
X730500Y1451500D01*
G01X730341Y1446725D02*
X728066Y1449000D01*
X727250D01*
G01X866000Y1398000D02*
Y1427500D01*
X827566Y1465934D01*
X756332D01*
G01D02*
X752982D01*
G01X741482Y1466234D02*
X742732D01*
X745032Y1468534D01*
G01X715650Y1471600D02*
X717700D01*
X718900Y1472800D01*
G01X680500Y1479750D02*
Y1482800D01*
X679800Y1483500D01*
G01X735232Y1451210D02*
Y1447084D01*
G01X805741Y-145664D02*
Y-225664D01*
G01X862766Y424642D02*
Y425987D01*
X860519Y428234D01*
G01X860298Y413842D02*
Y417182D01*
X860716Y417600D01*
G01X850947Y413842D02*
Y417592D01*
G01X840740Y645690D02*
X846820D01*
X846950Y645820D01*
G01X842490Y641690D02*
X846080D01*
X846950Y640820D01*
G01X821240Y659190D02*
Y660641D01*
X822841Y662242D01*
G01X836490Y641690D02*
Y644940D01*
X837240Y645690D01*
G01X836862Y637500D02*
X836490Y637872D01*
Y641690D01*
G01X821240Y655190D02*
X815401D01*
X815148Y654937D01*
G01X814550Y776500D02*
X810700D01*
G01X861600Y779100D02*
X856310D01*
X854973Y780437D01*
G01X814550Y767500D02*
X810659D01*
G01X840200Y800500D02*
Y797753D01*
X841309Y796644D01*
G01X822750Y819000D02*
X818215D01*
X818210Y819005D01*
X818162D01*
G01X838450Y804500D02*
X841688D01*
X841689Y804499D01*
X841800D01*
G01X822750Y815000D02*
X818079D01*
X818077Y814998D01*
X818113D01*
G01X834200Y800500D02*
Y803750D01*
X834950Y804500D01*
G01X834200Y796220D02*
Y800500D01*
G01X814550Y772000D02*
X810700D01*
G01X814550Y781000D02*
X814450Y781100D01*
Y785500D01*
G01X810700Y781000D02*
X814550D01*
G01X834470Y940680D02*
Y944430D01*
G01X824250Y888500D02*
X820900D01*
G01X824137Y880256D02*
X821711D01*
X820883Y879428D01*
G01X838470Y942430D02*
X841247D01*
X841266Y942411D01*
X842270D01*
G01X818470Y924180D02*
X818460Y924170D01*
Y920011D01*
X818434Y919985D01*
G01X822470Y924180D02*
Y920352D01*
X822463Y920345D01*
G01X838470Y936430D02*
X835220D01*
X834470Y937180D01*
G01X842270Y936402D02*
X838878D01*
X838850Y936430D01*
X838470D01*
G01X824250Y897500D02*
Y893000D01*
G01X819000Y896100D02*
X820400Y897500D01*
X824250D01*
G01X824137Y884453D02*
X818959D01*
X817337Y886075D01*
G01X822470Y977680D02*
Y981470D01*
G01X830470Y977680D02*
Y982030D01*
X827000Y985500D01*
G01X826470Y977680D02*
Y981470D01*
G01X834470Y977680D02*
Y981470D01*
G01X839970Y977680D02*
Y981470D01*
G01X821900Y1173700D02*
X832300D01*
X843350Y1184750D01*
X868900D01*
G01X859113Y1290032D02*
Y1283983D01*
G01X862858Y1392892D02*
X866500D01*
G01X943241Y-145664D02*
Y-225664D01*
G01X872137Y424642D02*
Y430615D01*
X871591Y431161D01*
G01X955000Y544350D02*
Y540800D01*
G01X939477Y524023D02*
X935477D01*
G01X942338Y529107D02*
X938338D01*
G01X942579Y551379D02*
X938579D01*
G01X942623Y556600D02*
X938623D01*
G01X952100Y516550D02*
X956050D01*
X956100Y516500D01*
G01X874740Y655190D02*
X878740D01*
G01X874740Y647190D02*
X878740D01*
G01X874740Y643190D02*
X878740D01*
G01X874740Y651190D02*
X878740D01*
G01X933000Y759320D02*
Y752696D01*
X932986Y752682D01*
G01X870550Y761000D02*
X872441D01*
X874858Y758583D01*
Y757002D01*
G01X922100Y760750D02*
X918400D01*
G01X870550Y756500D02*
X870789D01*
X874706Y752583D01*
G01X870550Y774500D02*
X874500D01*
G01X957500Y845750D02*
Y842400D01*
G01X944000Y845750D02*
Y842400D01*
G01X878403Y807000D02*
X880983Y804420D01*
G01X876250Y815000D02*
Y816293D01*
X876255Y816298D01*
Y818998D01*
G01X931250Y763820D02*
X935241D01*
X936543Y762518D01*
G01X908750Y778000D02*
X906100D01*
X905100Y777000D01*
G01X953000Y845750D02*
Y842400D01*
G01X948500Y845750D02*
Y842400D01*
G01X878403Y811000D02*
X881216Y813813D01*
G01X907000Y766350D02*
X910568D01*
X910807Y766589D01*
G01X904484Y786109D02*
X904591D01*
X907900Y782800D01*
X908750D01*
G01X876250Y803000D02*
Y801601D01*
X876256Y801595D01*
Y798895D01*
G01X867600Y779100D02*
Y775050D01*
X867050Y774500D01*
G01X874500Y779100D02*
X867600D01*
G01X940750Y898500D02*
X939000Y896750D01*
Y894000D01*
G01D02*
Y891250D01*
X940250Y890000D01*
G01X915580Y860620D02*
Y857420D01*
G01X871250Y887500D02*
X878665D01*
X879881Y886284D01*
X882999D01*
X883072Y886211D01*
G01X918380Y919164D02*
Y923247D01*
X918369Y923258D01*
G01X875750Y874000D02*
X878753D01*
X879205Y873548D01*
G01X872500Y892000D02*
X876089D01*
X876812Y891277D01*
X877877D01*
G01X914260Y919120D02*
Y924075D01*
X914208Y924127D01*
Y924279D01*
G01X924000Y885250D02*
X928250D01*
G01X934500Y880000D02*
Y885156D01*
G01Y880000D02*
Y876250D01*
X933750Y875500D01*
G01X940250Y890000D02*
X940750Y889500D01*
Y886000D01*
G01X927260Y919120D02*
Y922470D01*
G01X909760Y919120D02*
Y925445D01*
G01X922760Y919120D02*
Y922470D01*
G01X958250Y898500D02*
Y904500D01*
X954750Y908000D01*
G01X958250Y898500D02*
Y894444D01*
X958256Y894438D01*
G01X911080Y860620D02*
Y857420D01*
G01X875750Y869500D02*
X877770D01*
X878901Y868369D01*
X879770D01*
G01X876950Y1188400D02*
X877400Y1188850D01*
Y1191700D01*
G01X943500Y1229750D02*
Y1233000D01*
G01X951500Y1229750D02*
Y1233000D01*
G01X900050Y1191700D02*
X904000D01*
G01X877875Y1198150D02*
Y1192175D01*
X877400Y1191700D01*
G01X947500Y1229750D02*
Y1233000D01*
G01X955500Y1229750D02*
Y1233000D01*
G01X964550Y1190200D02*
X950533Y1176183D01*
X899919D01*
G01X868900Y1184750D02*
X874942D01*
X883509Y1176183D01*
X899919D01*
G01X871556Y1290030D02*
Y1283981D01*
G01X884056Y1290030D02*
Y1283981D01*
G01X913935Y1396353D02*
Y1402196D01*
G01X901435Y1396353D02*
Y1402196D01*
G01X888776Y1396385D02*
Y1402228D01*
G01X950988Y1429318D02*
X945415D01*
G01X950988Y1412818D02*
X945414D01*
G01X944016Y1449022D02*
Y1452217D01*
X944019Y1452220D01*
G01X966118Y534117D02*
X962118D01*
G01X984341Y563811D02*
X988341D01*
G01X981631Y559671D02*
X985631D01*
G01X980197Y533383D02*
X984197D01*
G01X999591Y552081D02*
X1003591D01*
G01X992998Y539555D02*
X996998D01*
G01X986200Y544250D02*
X990200D01*
G01X983300Y518550D02*
X985504D01*
X986638Y519684D01*
G01X963870Y761010D02*
Y765510D01*
G01Y754152D02*
Y761010D01*
G01X1009950Y842360D02*
Y838000D01*
G01X962000Y845750D02*
Y842400D01*
G01X963870Y774510D02*
X964869D01*
X966861Y772518D01*
G01X963870Y770010D02*
X964353D01*
X966861Y772518D01*
G01X990100Y829750D02*
X990066Y829716D01*
X986471D01*
G01X1026412Y849214D02*
X1025636Y849990D01*
Y854819D01*
G01X1029600Y853550D02*
X1029373Y853777D01*
X1028653D01*
X1027611Y854819D01*
X1025636D01*
G01X983070Y829740D02*
X983094Y829716D01*
X986471D01*
G01X1037631Y855984D02*
Y858950D01*
X1037110Y859471D01*
G01X1037634Y851705D02*
X1037631Y851708D01*
Y855984D01*
G01X1054250Y814500D02*
X1051601D01*
X1050774Y815327D01*
G01X1054250Y824250D02*
X1051964D01*
X1050794Y825420D01*
G01D02*
X1053774Y828400D01*
X1054250D01*
G01X1050794Y825420D02*
X1050650D01*
G01X1026271Y830913D02*
X1024650D01*
X1022838Y829101D01*
G01X1033092Y825127D02*
X1035882D01*
X1042545Y831790D01*
Y832026D01*
G01X1015950Y842360D02*
Y844550D01*
X1014000Y846500D01*
X1013250D01*
G01X1015950Y838000D02*
Y842360D01*
G01X1023750Y842500D02*
X1026046D01*
X1026932Y841614D01*
G01X1054250Y837800D02*
Y839561D01*
X1050082Y843729D01*
G01X989120Y845050D02*
Y837500D01*
G01X990100Y833250D02*
X993400D01*
G01X989120Y837500D02*
Y836180D01*
X990100Y835200D01*
Y833250D01*
G01X966093Y845750D02*
X968038D01*
X969926Y847638D01*
G01X963870Y779010D02*
X967986D01*
X971197Y775799D01*
G01X974120Y865050D02*
Y858920D01*
G01X1026515Y883231D02*
Y881485D01*
X1028500Y879500D01*
G01X1030515Y883231D02*
Y881515D01*
X1028500Y879500D01*
G01X976242Y881250D02*
Y884600D01*
G01X980442Y879550D02*
Y882900D01*
G01X993942Y879550D02*
Y882900D01*
G01X1012125Y918250D02*
Y925875D01*
G01X1017007D02*
X1012125D01*
G01X1027524Y948954D02*
Y939306D01*
G01X1039500Y891100D02*
Y886750D01*
G01X972042Y881250D02*
Y884600D01*
G01X985542Y879550D02*
Y882900D01*
G01X989742Y879550D02*
Y882900D01*
G01X1000500Y907250D02*
Y903132D01*
X1000557Y903075D01*
G01X1034200Y945000D02*
Y909824D01*
X1028341Y903965D01*
X1020545D01*
X1020492Y903912D01*
X1016114D01*
X1015277Y903075D01*
X1011531D01*
G01X1040200Y945000D02*
Y910526D01*
X1030639Y900965D01*
X1021789D01*
G01X1046272Y944928D02*
Y910979D01*
X1033315Y898022D01*
Y894331D01*
G01X1048000Y893750D02*
X1044800D01*
G01X998000Y1114000D02*
X1000501Y1111499D01*
X1001687D01*
G01X1010400Y1129300D02*
X1016800D01*
X1026100Y1138600D01*
Y1145996D01*
G01X998000Y1120000D02*
Y1120029D01*
X1002671Y1124700D01*
G01X1004400Y1129300D02*
Y1126429D01*
X1002671Y1124700D01*
G01X963500Y1229750D02*
Y1233000D01*
G01X967500Y1229750D02*
Y1233000D01*
G01X959500Y1229750D02*
Y1233000D01*
G01X979250Y1217000D02*
X982500D01*
G01X979250Y1209000D02*
X982500D01*
G01X968050Y1193500D02*
X971300D01*
X971700Y1193100D01*
G01X979250Y1225000D02*
X982500D01*
G01X979250Y1205000D02*
X982500D01*
G01X964550Y1193500D02*
Y1190200D01*
G01X979250Y1221000D02*
X982500D01*
G01X979250Y1213000D02*
X982500D01*
G01X1035943Y1424649D02*
Y1428149D01*
G01X1031443Y1431399D02*
Y1426899D01*
G01X1040127Y1422500D02*
Y1426500D01*
G01X1040500Y1410500D02*
X1033287D01*
G01X1026734Y1391632D02*
X1024675D01*
X1022818Y1393489D01*
G01X1047000Y1425700D02*
Y1421800D01*
G01X1044700Y1417000D02*
X1039900D01*
G01X1038303Y1444899D02*
Y1441709D01*
G01X1021618Y1467615D02*
Y1470665D01*
X1021818Y1470865D01*
G01X1007618Y1472665D02*
Y1477365D01*
G01X1013618Y1467615D02*
Y1470665D01*
X1013418Y1470865D01*
G01X1027288Y1471891D02*
Y1467441D01*
G01X1034100Y1496914D02*
Y1500564D01*
G01X1024175Y1487064D02*
Y1482189D01*
G01X979599Y1436399D02*
X975443D01*
G01X982052D02*
X979599D01*
G01X972693Y1431899D02*
X975443Y1434649D01*
Y1436399D01*
G01X1017618Y1467615D02*
Y1470865D01*
G01X994271Y1467667D02*
Y1470923D01*
X993830Y1471364D01*
G01X969193Y1431899D02*
X962204D01*
X962136Y1431831D01*
G01X1043606Y1437906D02*
Y1444899D01*
G01X1020500Y1496814D02*
Y1500014D01*
G01X1037550Y1480314D02*
Y1475814D01*
G01X1040663Y1467891D02*
Y1472701D01*
X1037550Y1475814D01*
G01X1058241Y-145664D02*
Y-225664D01*
G01X1115825Y618493D02*
X1112303D01*
X1112298Y618498D01*
G01X1115105Y932655D02*
X1118265Y935815D01*
X1154495D01*
X1157556Y932754D01*
G01X1055500Y893750D02*
X1058800D01*
G01X1060710Y895660D02*
X1058800Y893750D01*
G01X1107000Y1327500D02*
Y1323500D01*
G01X1130250Y1296700D02*
X1133480D01*
G01X1130250Y1291700D02*
X1133480D01*
G01X1075350Y1299375D02*
X1072120D01*
G01X1075350Y1304495D02*
X1072120D01*
G01X1075350Y1309495D02*
X1072120D01*
G01X1075350Y1292460D02*
X1072120D01*
G01X1130112Y1366523D02*
Y1363273D01*
G01X1138112Y1366523D02*
Y1363273D01*
G01X1114112Y1366523D02*
Y1363273D01*
G01X1118112Y1366523D02*
Y1363273D01*
G01X1126112Y1366523D02*
Y1363273D01*
G01X1102362Y1387273D02*
X1099112D01*
G01X1102362Y1379273D02*
X1099112D01*
G01X1113862Y1402773D02*
X1111012D01*
X1110512Y1403273D01*
G01X1102362Y1391273D02*
X1099112D01*
G01X1102350Y1375200D02*
X1099100D01*
G01X1102362Y1383273D02*
X1099112D01*
G01X1102350Y1371200D02*
X1099100D01*
G01X1117362Y1402773D02*
Y1406073D01*
G01X1134112Y1366523D02*
Y1363273D01*
G01X1122112Y1366523D02*
Y1363273D01*
G01X1117362Y1406073D02*
X1132480Y1421191D01*
X1203487D01*
G01X1225741Y-145664D02*
Y-225664D01*
G01X1243500Y389500D02*
Y393600D01*
G01X1217111Y849782D02*
Y846204D01*
X1217089Y846182D01*
G01X1213611Y836182D02*
Y831932D01*
G01X1228344Y852351D02*
Y855959D01*
G01X1224094Y849250D02*
Y845019D01*
X1224088Y845013D01*
Y844900D01*
G01X1247588Y842190D02*
X1243464D01*
X1243462Y842188D01*
G01D02*
X1238462D01*
G01X1197044Y918091D02*
X1200376D01*
X1200407Y918060D01*
G01X1196974Y912331D02*
X1200306D01*
X1200337Y912300D01*
G01X1184778Y912848D02*
Y912350D01*
X1188250Y908878D01*
Y906100D01*
G01Y899500D02*
Y906100D01*
G01Y892600D02*
Y886000D01*
G01Y892600D02*
Y899500D01*
G01X1223730Y1289033D02*
Y1285803D01*
G01X1230600Y1289033D02*
Y1285803D01*
G01X1235600Y1289033D02*
Y1285803D01*
G01X1202394Y1289033D02*
Y1285803D01*
G01X1197394Y1289033D02*
Y1285803D01*
G01X1190524Y1289033D02*
Y1285803D01*
G01X1236600Y1343533D02*
Y1346763D01*
G01X1232100Y1343533D02*
Y1346763D01*
G01X1217100Y1343533D02*
Y1346763D01*
G01X1183894Y1343533D02*
Y1346763D01*
G01X1203394Y1343533D02*
Y1346763D01*
G01X1198894Y1343533D02*
Y1346763D01*
G01X1200962Y1409352D02*
Y1413023D01*
G01X1207440Y1421104D02*
X1209819Y1418725D01*
Y1417377D01*
G01X1205971Y1415053D02*
X1207495D01*
X1209819Y1417377D01*
G01X1208394Y1343533D02*
Y1346763D01*
G01X1193894Y1343533D02*
Y1346763D01*
G01X1227100Y1343533D02*
Y1346763D01*
G01X1241600Y1343533D02*
Y1346763D01*
G01X1288878Y81319D02*
X1282106D01*
G01X1288878Y66319D02*
X1282106D01*
G01X1281693Y27697D02*
X1289106D01*
G01X1288878Y51319D02*
X1282106D01*
G01X1303500Y38250D02*
Y35000D01*
G01X1301550Y63900D02*
Y62821D01*
X1298655Y59926D01*
G01X1297000Y68500D02*
X1297400Y68900D01*
X1301550D01*
G01X1317800Y50550D02*
Y48700D01*
X1319100Y47400D01*
G01X1308000Y38250D02*
Y35000D01*
G01X1313000Y180800D02*
Y185500D01*
G01X1308500Y150500D02*
X1314000D01*
G01X1288878Y161319D02*
X1282106D01*
G01X1288878Y151319D02*
X1282106D01*
G01X1302500Y152000D02*
X1298500D01*
G01X1305000Y180800D02*
Y185500D01*
G01X1298500Y181500D02*
Y185500D01*
G01X1288878Y131319D02*
X1282106D01*
G01X1288878Y121319D02*
X1282106D01*
G01X1266600Y122850D02*
Y119500D01*
G01X1262600Y119700D02*
Y122850D01*
G01X1281693Y199941D02*
X1289106D01*
G01X1259445Y383269D02*
Y379019D01*
G01X1337824Y383426D02*
Y379176D01*
G01X1269928Y396337D02*
Y400685D01*
X1269926Y400687D01*
G01X1262945Y396869D02*
Y400450D01*
X1262964Y400469D01*
G01X1281693Y480453D02*
Y473218D01*
G01X1274178Y403046D02*
Y407697D01*
X1274396Y407915D01*
G01X1248500Y389500D02*
Y393600D01*
G01X1270492Y546575D02*
X1277606D01*
G01X1270492Y556024D02*
X1277606D01*
G01X1270492Y537126D02*
X1277606D01*
G01X1307500Y504750D02*
Y501500D01*
G01X1288878Y519075D02*
X1282106D01*
G01X1288878Y534075D02*
X1282106D01*
G01X1288878Y504075D02*
X1282106D01*
G01X1303350Y534000D02*
X1300100D01*
X1299900Y534200D01*
G01X1300100Y530000D02*
X1303350D01*
G01X1326500Y517250D02*
Y514000D01*
G01X1312000Y504750D02*
Y501500D01*
G01X1262600Y575550D02*
Y573445D01*
X1264586Y571459D01*
X1272084D01*
X1272182Y571361D01*
G01X1288878Y614075D02*
X1282106D01*
G01X1305000Y633800D02*
Y638500D01*
G01X1308500Y603500D02*
X1314000D01*
G01X1288878Y574075D02*
X1282106D01*
G01X1288878Y604075D02*
X1282106D01*
G01X1288878Y584075D02*
X1282106D01*
G01X1302500Y605000D02*
X1298500D01*
G01X1313000Y633800D02*
Y643101D01*
X1312973Y643128D01*
G01X1266600Y575550D02*
X1272211D01*
Y575575D01*
G01X1298000Y638300D02*
Y635000D01*
X1298500Y634500D01*
G01X1281693Y652697D02*
X1273986D01*
X1273979Y652690D01*
G01X1337824Y836182D02*
Y832935D01*
G01X1281693Y933209D02*
X1274000D01*
G01X1288878Y1036831D02*
X1282106D01*
G01X1288878Y1026831D02*
X1282106D01*
G01X1307500Y957250D02*
Y954000D01*
G01X1288878Y956831D02*
X1282106D01*
G01X1270492Y1008780D02*
X1277606D01*
G01X1270492Y999331D02*
X1277606D01*
G01X1270492Y989882D02*
X1277606D01*
G01X1288878Y986831D02*
X1282106D01*
G01X1288878Y971831D02*
X1282106D01*
G01X1266400Y1028250D02*
Y1024700D01*
G01X1304350Y986200D02*
X1301200D01*
X1300600Y986800D01*
G01X1304350Y982200D02*
X1301300D01*
X1300900Y981800D01*
G01X1326500Y969750D02*
Y966500D01*
G01X1312000Y957250D02*
Y954000D01*
G01X1262400Y1028250D02*
Y1024700D01*
G01X1281693Y1105453D02*
X1289106D01*
G01X1308500Y1056000D02*
X1314000D01*
G01X1313000Y1086300D02*
Y1091000D01*
G01X1298500Y1087000D02*
Y1091000D01*
G01X1302500Y1057500D02*
X1298500D01*
G01X1305000Y1086300D02*
Y1091000D01*
G01X1288878Y1066831D02*
X1282106D01*
G01X1288878Y1056831D02*
X1282106D01*
G01X1306625Y1429250D02*
Y1434000D01*
G01X1324000Y1416500D02*
X1327900D01*
G01X1324000Y1412600D02*
Y1408500D01*
X1323900Y1408400D01*
G01X1324000Y1412600D02*
Y1416500D01*
G01X1323900Y1408400D02*
X1322100D01*
X1321400Y1409100D01*
X1319500D01*
G01X1313500Y1401900D02*
X1317100D01*
X1319500Y1404300D01*
Y1409100D01*
G01X1300374Y1453750D02*
X1303874D01*
G01X1289124Y1452500D02*
X1292374D01*
G01X1289124Y1434000D02*
Y1430700D01*
G01X1300374Y1435250D02*
X1301534Y1434090D01*
Y1431345D01*
G01X1253374Y1463150D02*
Y1459300D01*
G01X1263424Y1484900D02*
X1265074D01*
X1266474Y1486300D01*
Y1487500D01*
G01X1274824Y1488600D02*
X1278474D01*
X1278574Y1488700D01*
G01X1287224Y1445500D02*
X1282374D01*
G01X1287224Y1464000D02*
X1282374D01*
G01X1296374Y1435250D02*
Y1430700D01*
G01Y1453750D02*
Y1451022D01*
X1297089Y1450307D01*
G01X1284624Y1480000D02*
Y1476400D01*
G01X1253374Y1466650D02*
Y1470000D01*
G01X1395741Y-145664D02*
Y-225664D01*
G01X1413091Y66319D02*
X1406319D01*
G01X1413091Y81319D02*
X1406319D01*
G01X1394705Y93819D02*
X1401819D01*
G01X1394705Y84370D02*
X1401819D01*
G01X1435750Y81000D02*
X1439500D01*
G01X1413091Y51319D02*
X1406319D01*
G01X1405906Y27697D02*
X1413319D01*
G01X1431500Y51750D02*
Y48500D01*
G01X1435750Y77000D02*
Y73750D01*
G01X1413091Y151319D02*
X1406319D01*
G01X1413091Y161319D02*
X1406319D01*
G01X1426500Y152000D02*
X1422500D01*
G01Y181500D02*
Y185500D01*
G01X1432500Y150500D02*
X1438000D01*
G01X1429000Y180800D02*
Y185500D01*
G01X1413091Y121319D02*
X1406319D01*
G01X1413091Y131319D02*
X1406319D01*
G01X1394705Y103268D02*
X1401819D01*
G01X1391200Y122850D02*
Y119500D01*
G01X1387200Y122850D02*
Y118349D01*
X1391849Y113700D01*
X1394200D01*
G01X1405906Y199941D02*
X1397947D01*
X1397937Y199951D01*
G01X1341324Y397026D02*
Y400607D01*
X1341343Y400626D01*
G01X1352557Y399595D02*
Y403203D01*
G01X1348307Y396494D02*
Y400842D01*
X1348305Y400844D01*
G01X1367500Y393500D02*
Y397086D01*
X1367514Y397100D01*
G01X1362500Y393500D02*
Y397086D01*
X1362514Y397100D01*
G01X1394705Y546575D02*
X1401819D01*
G01X1394705Y556024D02*
X1401819D01*
G01X1394705Y537126D02*
X1401819D01*
G01X1413091Y534075D02*
X1406319D01*
G01X1413091Y519075D02*
X1406319D01*
G01X1413091Y504075D02*
X1406319D01*
G01X1405906Y480453D02*
X1413319D01*
G01X1431500Y504750D02*
Y501500D01*
G01X1427850Y533900D02*
X1424700D01*
X1424400Y534200D01*
G01X1427850Y529900D02*
X1425300D01*
X1424500Y529100D01*
G01X1405906Y652697D02*
X1413319D01*
G01X1413091Y614075D02*
X1406319D01*
G01X1422500Y634500D02*
Y638500D01*
G01X1429000Y633800D02*
Y638500D01*
G01X1413091Y604075D02*
X1406319D01*
G01X1413091Y584075D02*
X1406319D01*
G01X1413091Y574075D02*
X1406319D01*
G01X1432500Y603500D02*
X1438000D01*
G01X1426500Y605000D02*
X1422500D01*
G01X1390400Y575550D02*
X1390420Y575530D01*
X1394110D01*
G01X1386400Y575550D02*
X1383952Y573102D01*
G01X1348307Y849250D02*
Y853598D01*
X1348305Y853600D01*
G01X1341324Y849782D02*
Y853363D01*
X1341343Y853382D01*
G01X1352557Y852351D02*
Y855959D01*
G01X1367500Y847000D02*
Y851922D01*
G01X1362500Y847000D02*
Y851922D01*
G01X1405906Y933209D02*
X1413319D01*
G01X1413091Y1036831D02*
X1406319D01*
G01X1413091Y1026831D02*
X1406319D01*
G01X1413091Y956831D02*
X1406319D01*
G01X1431500Y957250D02*
Y954000D01*
G01X1394705Y1008780D02*
X1401819D01*
G01X1394705Y999331D02*
X1401819D01*
G01X1394705Y989882D02*
X1401819D01*
G01X1413091Y986831D02*
X1406319D01*
G01X1413091Y971831D02*
X1406319D01*
G01X1391000Y1028350D02*
Y1024800D01*
G01X1427850Y986400D02*
X1424700D01*
X1424100Y987000D01*
G01X1427850Y982400D02*
X1424800D01*
X1424400Y982000D01*
G01X1387000Y1028350D02*
Y1024700D01*
X1386900Y1024600D01*
G01X1405906Y1105453D02*
X1413319D01*
G01X1426500Y1057500D02*
X1422500D01*
G01Y1087000D02*
Y1091000D01*
G01X1429000Y1086300D02*
Y1091000D01*
G01X1432500Y1056000D02*
X1438000D01*
G01X1413091Y1066831D02*
X1406319D01*
G01X1413091Y1056831D02*
X1406319D01*
G01X1348100Y1410700D02*
Y1415500D01*
X1347400Y1416200D01*
G01X1364566Y1460477D02*
Y1466929D01*
G01D02*
Y1473381D01*
G01X1358114Y1466929D02*
X1364566D01*
G01D02*
X1371018D01*
G01X1364566Y1438823D02*
Y1445275D01*
G01D02*
Y1451727D01*
G01X1358114Y1445275D02*
X1364566D01*
G01D02*
X1371018D01*
G01X1537303Y66319D02*
X1530531D01*
G01X1537303Y81319D02*
X1530531D01*
G01X1518917Y93819D02*
X1526031D01*
G01X1518917Y84370D02*
X1526031D01*
G01X1537303Y51319D02*
X1530531D01*
G01X1530118Y27697D02*
X1537531D01*
G01X1450500Y64250D02*
Y61000D01*
G01X1436000Y51750D02*
Y48500D01*
G01X1537303Y151319D02*
X1530531D01*
G01X1437000Y180800D02*
Y185500D01*
G01X1537303Y121319D02*
X1530531D01*
G01X1537303Y131319D02*
X1530531D01*
G01X1518917Y103268D02*
X1526031D01*
G01X1515400Y122850D02*
Y119400D01*
G01X1537303Y161319D02*
X1526834D01*
X1526823Y161308D01*
G01X1511400Y122850D02*
Y119500D01*
G01X1530118Y199941D02*
X1529341D01*
X1523100Y193700D01*
G01X1462036Y383426D02*
Y379176D01*
G01X1465536Y397026D02*
Y400607D01*
X1465555Y400626D01*
G01X1472519Y396494D02*
Y400842D01*
X1472517Y400844D01*
G01X1476769Y399595D02*
Y403203D01*
G01X1492000Y393500D02*
Y397086D01*
X1492014Y397100D01*
G01X1487000Y393500D02*
Y397086D01*
X1487014Y397100D01*
G01X1518917Y546575D02*
X1526031D01*
G01X1518917Y556024D02*
X1526031D01*
G01X1518917Y537126D02*
X1526031D01*
G01X1537303Y534075D02*
X1530531D01*
G01X1537303Y519075D02*
X1530531D01*
G01X1537303Y504075D02*
X1530531D01*
G01X1530118Y480453D02*
X1537531D01*
G01X1450500Y517250D02*
Y514000D01*
G01X1436000Y504750D02*
Y501500D01*
G01X1537500Y656000D02*
Y654500D01*
X1535697Y652697D01*
X1530118D01*
G01X1537303Y614075D02*
X1530531D01*
G01X1437000Y633800D02*
Y638500D01*
G01X1537303Y604075D02*
X1530531D01*
G01X1537303Y584075D02*
X1530531D01*
G01X1537303Y574075D02*
X1530531D01*
G01X1515200Y575550D02*
Y572200D01*
G01X1511200Y572300D02*
Y575550D01*
G01X1472519Y849250D02*
Y853598D01*
X1472517Y853600D01*
G01X1465536Y849782D02*
Y853363D01*
X1465555Y853382D01*
G01X1462036Y836182D02*
Y831932D01*
G01X1476769Y852351D02*
Y855959D01*
G01X1492000Y846500D02*
Y851600D01*
X1493500Y853100D01*
G01X1487000Y846500D02*
Y851600D01*
G01X1530118Y933209D02*
X1537531D01*
G01X1537303Y1036831D02*
X1530531D01*
G01X1537303Y1026831D02*
X1530531D01*
G01X1537303Y956831D02*
X1530531D01*
G01X1518917Y1008780D02*
X1526031D01*
G01X1518917Y999331D02*
X1526031D01*
G01X1518917Y989882D02*
X1526031D01*
G01X1537303Y986831D02*
X1530531D01*
G01X1537303Y971831D02*
X1530531D01*
G01X1515400Y1028350D02*
Y1025000D01*
G01X1450500Y969750D02*
Y966500D01*
G01X1511400Y1028350D02*
Y1024600D01*
G01X1436000Y957250D02*
Y954000D01*
G01X1530118Y1105453D02*
X1537531D01*
G01X1537303Y1066831D02*
X1530531D01*
G01X1537303Y1056831D02*
X1530531D01*
G01X1437000Y1086300D02*
Y1091000D01*
G01X1593241Y-145664D02*
Y-225664D01*
G01X1621241Y-129664D02*
G02I-12000J0D01*
G01X1616091D02*
G02I-6850J0D01*
G01X1609241Y-145664D02*
Y-113664D01*
G01X1625241Y-129664D02*
X1593241D01*
G01X1553000Y38250D02*
Y35000D01*
G01X1548500Y62900D02*
X1548900Y63300D01*
X1551950D01*
G01Y69300D02*
X1548270D01*
X1548279Y69309D01*
G01X1572000Y50750D02*
X1575400D01*
G01X1557500Y38250D02*
Y35000D01*
G01X1547000Y181500D02*
Y185500D01*
G01X1557000Y150500D02*
X1562500D01*
G01X1561500Y180800D02*
Y185500D01*
G01X1547000Y156222D02*
Y152000D01*
G01X1553500Y180800D02*
Y189500D01*
G01X1586249Y383426D02*
Y379176D01*
G01X1596732Y396494D02*
Y400842D01*
X1596730Y400844D01*
G01X1589749Y397026D02*
Y400607D01*
X1589768Y400626D01*
G01X1600982Y399595D02*
Y403203D01*
G01X1611000Y393500D02*
Y397086D01*
X1611014Y397100D01*
G01X1616000Y393500D02*
Y397086D01*
X1616014Y397100D01*
G01X1556000Y504750D02*
Y501500D01*
G01X1551950Y533800D02*
X1549700D01*
X1548600Y534900D01*
G01X1551950Y529800D02*
X1549400D01*
X1548400Y528800D01*
G01X1575000Y517250D02*
Y514000D01*
G01X1560500Y504750D02*
Y501500D01*
G01X1553500Y633800D02*
Y638500D01*
G01X1551000Y605000D02*
X1547000D01*
G01X1557000Y603500D02*
X1562500D01*
G01X1561500Y633800D02*
Y639860D01*
G01X1547000Y634500D02*
X1552800D01*
X1553500Y633800D01*
G01X1596732Y849250D02*
Y853598D01*
X1596730Y853600D01*
G01X1589749Y849782D02*
Y853363D01*
X1589768Y853382D01*
G01X1586249Y836182D02*
Y831932D01*
G01X1600982Y855959D02*
X1599441Y857500D01*
X1597000D01*
G01X1616000Y846500D02*
Y850100D01*
G01X1611000Y846500D02*
Y850100D01*
G01X1556000Y957250D02*
Y954000D01*
G01X1552250Y986600D02*
X1549900D01*
X1548900Y987600D01*
G01X1575000Y969750D02*
Y966500D01*
G01X1552250Y982600D02*
X1550000D01*
X1548900Y981500D01*
G01X1560500Y957250D02*
Y954000D01*
G01X1551000Y1057500D02*
X1547000D01*
G01Y1087000D02*
Y1091000D01*
G01X1557000Y1056000D02*
X1562500D01*
G01X1553500Y1086300D02*
Y1091000D01*
G01X1561500Y1086300D02*
Y1091000D01*
G01X1661516Y66319D02*
X1654744D01*
G01X1661516Y81319D02*
X1654744D01*
G01X1643130Y93819D02*
X1650244D01*
G01X1643130Y84370D02*
X1650244D01*
G01X1680000Y51750D02*
Y48500D01*
G01X1661516Y51319D02*
X1654744D01*
G01X1654331Y27697D02*
X1661744D01*
G01X1683150Y81000D02*
X1686721D01*
X1686730Y80991D01*
G01X1699000Y64250D02*
Y61000D01*
G01X1676150Y77000D02*
X1673500D01*
X1672900Y76400D01*
G01X1684500Y51750D02*
Y48500D01*
G01X1677500Y180800D02*
Y185500D01*
G01X1681000Y150500D02*
X1686500D01*
G01X1675000Y152000D02*
X1671000D01*
G01X1661516Y151319D02*
X1654744D01*
G01X1661516Y161319D02*
X1654744D01*
G01X1685500Y180800D02*
Y185500D01*
G01X1661516Y121319D02*
X1654744D01*
G01X1643130Y103268D02*
X1650244D01*
G01X1639300Y122850D02*
Y119500D01*
G01X1661516Y131319D02*
X1656446D01*
X1653206Y134559D01*
G01X1671000Y181500D02*
Y190632D01*
X1671003Y190635D01*
G01X1635300Y119600D02*
Y122850D01*
G01X1654331Y199941D02*
X1661744D01*
G01X1643130Y546575D02*
X1650244D01*
G01X1643130Y556024D02*
X1650244D01*
G01X1643130Y537126D02*
X1650244D01*
G01X1661516Y534075D02*
X1654744D01*
G01X1661516Y519075D02*
X1654744D01*
G01X1661516Y504075D02*
X1654744D01*
G01X1654331Y480453D02*
X1661744D01*
G01X1680000Y504750D02*
Y501500D01*
G01X1676550Y534100D02*
X1674200D01*
X1673200Y535100D01*
G01X1676550Y530100D02*
X1674300D01*
X1673200Y529000D01*
G01X1699000Y517250D02*
Y514000D01*
G01X1684500Y504750D02*
Y501500D01*
G01X1654331Y652697D02*
X1661744D01*
G01X1661516Y614075D02*
X1654744D01*
G01X1671000Y634500D02*
Y638500D01*
G01X1685500Y633800D02*
Y638500D01*
G01X1677500Y633800D02*
Y638500D01*
G01X1661516Y604075D02*
X1654744D01*
G01X1661516Y584075D02*
X1654744D01*
G01X1681000Y603500D02*
X1686500D01*
G01X1675000Y605000D02*
X1671000D01*
G01X1638200Y575550D02*
Y572200D01*
G01X1661516Y574075D02*
X1652843D01*
X1652808Y574040D01*
G01X1634200Y572200D02*
Y575550D01*
G01X1720944Y849250D02*
Y853598D01*
X1720942Y853600D01*
G01X1713961Y849782D02*
Y853363D01*
X1713980Y853382D01*
G01X1710461Y836182D02*
Y831932D01*
G01X1661800Y933400D02*
X1661609Y933209D01*
X1654331D01*
G01X1661516Y1036831D02*
X1654744D01*
G01X1661516Y1026831D02*
X1654744D01*
G01X1661516Y956831D02*
X1654744D01*
G01X1680000Y957250D02*
Y954000D01*
G01X1643130Y1008780D02*
X1650244D01*
G01X1643130Y999331D02*
X1650244D01*
G01X1643130Y989882D02*
X1650244D01*
G01X1661516Y986831D02*
X1654744D01*
G01X1661516Y971831D02*
X1654744D01*
G01X1639100Y1028350D02*
Y1024900D01*
G01X1676150Y986300D02*
X1673800D01*
X1672800Y987300D01*
G01X1699000Y969750D02*
Y966500D01*
G01X1676150Y982300D02*
X1673900D01*
X1672800Y981200D01*
G01X1684500Y957250D02*
Y954000D01*
G01X1635100Y1028350D02*
Y1024700D01*
G01X1654331Y1105453D02*
X1661744D01*
G01X1677500Y1086300D02*
Y1091000D01*
G01X1681000Y1056000D02*
X1686500D01*
G01X1671000Y1087000D02*
Y1091000D01*
G01X1675000Y1057500D02*
X1671000D01*
G01X1685500Y1086300D02*
Y1091000D01*
G01X1661516Y1066831D02*
X1654744D01*
G01X1661516Y1056831D02*
X1654744D01*
G01X1694751Y1429250D02*
Y1434000D01*
G01X1669376D02*
Y1429200D01*
G01X1712126Y1416500D02*
Y1412600D01*
G01D02*
Y1408700D01*
G01D02*
X1709871D01*
X1709471Y1409100D01*
X1707626D01*
G01X1701626Y1401900D02*
X1705226D01*
X1707626Y1404300D01*
Y1409100D01*
G01X1712126Y1416500D02*
X1716026D01*
G01X1669376Y1452500D02*
X1672626D01*
G01X1680626Y1435250D02*
X1684976D01*
X1686226Y1434000D01*
Y1432500D01*
G01X1680626Y1453750D02*
X1683926D01*
G01X1667476Y1464000D02*
X1662626D01*
G01X1667476Y1445500D02*
X1662626D01*
G01X1676626Y1453750D02*
Y1449100D01*
X1674926Y1447400D01*
G01X1676626Y1435250D02*
Y1432000D01*
G01X1652750Y1465000D02*
Y1471124D01*
X1661626Y1480000D01*
G01X1785728Y66319D02*
X1778956D01*
G01X1785728Y81319D02*
X1778956D01*
G01X1767342Y93819D02*
X1774456D01*
G01X1767342Y84370D02*
X1774456D01*
G01X1778543Y27697D02*
X1785956D01*
G01X1785728Y51319D02*
X1778956D01*
G01X1814850Y24800D02*
Y21500D01*
G01X1817500Y28900D02*
Y32700D01*
G01X1803100Y78550D02*
Y81800D01*
X1803500Y82200D01*
G01X1808500Y60950D02*
X1810700D01*
X1811700Y59950D01*
Y59550D01*
G01X1799100Y78550D02*
Y82027D01*
X1799094Y82033D01*
G01X1797650Y63200D02*
X1794500D01*
X1794300Y63400D01*
G01X1809500Y180800D02*
Y185500D01*
G01X1801500Y180800D02*
Y185500D01*
G01X1799000Y152000D02*
X1795000D01*
G01Y181500D02*
Y185500D01*
G01X1785728Y151319D02*
X1778956D01*
G01X1785728Y161319D02*
X1778956D01*
G01X1785728Y121319D02*
X1778956D01*
G01X1785728Y131319D02*
X1778956D01*
G01X1767342Y103268D02*
X1774456D01*
G01X1763600Y122850D02*
Y119400D01*
G01X1805000Y150500D02*
X1808799D01*
X1811305Y147994D01*
G01X1759600Y122850D02*
Y119500D01*
G01X1778543Y199941D02*
X1785956D01*
G01X1801642Y383782D02*
Y379532D01*
G01X1816375Y399951D02*
Y403559D01*
G01X1812125Y396850D02*
Y401198D01*
X1812123Y401200D01*
G01X1805142Y400982D02*
Y397382D01*
G01X1731710Y475473D02*
X1733343D01*
X1735109Y473707D01*
G01X1734201Y464705D02*
Y468549D01*
X1734859Y469207D01*
G01D02*
X1735109Y469457D01*
Y473707D01*
G01X1749942Y402630D02*
Y405820D01*
X1749952Y405830D01*
G01X1745759Y396293D02*
Y400621D01*
X1745737Y400643D01*
G01X1764151Y402301D02*
X1764168Y402318D01*
Y405501D01*
G01X1759916Y396297D02*
X1759904Y396309D01*
Y400647D01*
G01X1763359Y453707D02*
X1765266Y451800D01*
X1799600D01*
G01X1750368Y469232D02*
Y466698D01*
X1763359Y453707D01*
G01X1735000Y393500D02*
Y397086D01*
X1735014Y397100D01*
G01X1740000Y393500D02*
Y397086D01*
X1740014Y397100D01*
G01X1751774Y430510D02*
Y434652D01*
G01D02*
Y438717D01*
G01X1743359Y438057D02*
X1735390D01*
G01X1748274Y438717D02*
X1747614Y438057D01*
X1743359D01*
G01X1735859Y451807D02*
X1739934Y455882D01*
X1742581D01*
X1742758Y456059D01*
G01X1735859Y445807D02*
X1743959D01*
G01X1748302Y443744D02*
X1746239Y445807D01*
X1743959D01*
G01X1767342Y556024D02*
X1774456D01*
G01X1767342Y546575D02*
X1774456D01*
G01X1778543Y480453D02*
X1785956D01*
G01X1804000Y504750D02*
Y501500D01*
G01X1785728Y519075D02*
X1778956D01*
G01X1785728Y504075D02*
X1778956D01*
G01X1767342Y537126D02*
Y533721D01*
G01X1785728Y534075D02*
Y538736D01*
G01X1800550Y534100D02*
X1798100Y536550D01*
Y537973D01*
G01X1800550Y530100D02*
X1798700D01*
X1797400Y528800D01*
G01X1742859Y484707D02*
Y481457D01*
G01X1808500Y504750D02*
Y501500D01*
G01X1778543Y652697D02*
X1785956D01*
G01X1795000Y634500D02*
Y638500D01*
G01X1801500Y633800D02*
Y638500D01*
G01X1809500Y633800D02*
Y638500D01*
G01X1785728Y614075D02*
X1778956D01*
G01X1805000Y603500D02*
X1810500D01*
G01X1799000Y605000D02*
X1795000D01*
G01X1785728Y604075D02*
X1778956D01*
G01X1785728Y584075D02*
X1778956D01*
G01X1785728Y574075D02*
X1778956D01*
G01X1759750Y579500D02*
Y576000D01*
G01Y583500D02*
Y587000D01*
G01X1725194Y852351D02*
Y855959D01*
G01X1740000Y846500D02*
Y850100D01*
G01X1735000Y846500D02*
Y850100D01*
G01X1778543Y933209D02*
X1785956D01*
G01X1809513Y908025D02*
Y903775D01*
X1809263Y903525D01*
G01X1809513Y908025D02*
X1807747Y909791D01*
X1806114D01*
G01X1809263Y903525D02*
X1808605Y902867D01*
Y899023D01*
G01X1817263Y919025D02*
Y915775D01*
G01X1816263Y872375D02*
X1809794D01*
G01X1822678Y873035D02*
X1822018Y872375D01*
X1816263D01*
G01X1810263Y886125D02*
X1813896Y889758D01*
X1817739D01*
G01X1817863Y880125D02*
X1810263D01*
G01X1785728Y1036831D02*
X1778956D01*
G01X1785728Y1026831D02*
X1778956D01*
G01X1804000Y957250D02*
Y954000D01*
G01X1785728Y956831D02*
X1778956D01*
G01X1767342Y1008780D02*
X1774456D01*
G01X1767342Y999331D02*
X1774456D01*
G01X1767342Y989882D02*
X1774456D01*
G01X1785728Y986831D02*
X1778956D01*
G01X1785728Y971831D02*
X1778956D01*
G01X1763300Y1028350D02*
Y1024800D01*
G01X1800250Y986200D02*
X1797900D01*
X1796900Y987200D01*
G01X1800250Y982200D02*
X1798000D01*
X1796900Y981100D01*
G01X1808500Y957250D02*
Y954000D01*
G01X1759300Y1028350D02*
Y1024900D01*
G01X1778543Y1105453D02*
X1785956D01*
G01X1809500Y1086300D02*
Y1091000D01*
G01X1801500Y1086300D02*
Y1091000D01*
G01X1805000Y1056000D02*
X1810500D01*
G01X1795000Y1087000D02*
Y1091000D01*
G01X1799000Y1057500D02*
X1795000D01*
G01X1785728Y1066831D02*
X1778956D01*
G01X1785728Y1056831D02*
X1778956D01*
G01X1736326Y1410600D02*
Y1415100D01*
X1735126Y1416300D01*
G01X1790226Y1462350D02*
Y1458600D01*
G01X1744881Y1460477D02*
Y1466929D01*
G01D02*
Y1473381D01*
G01X1738429Y1466929D02*
X1744881D01*
G01D02*
X1751333D01*
G01X1744881Y1438823D02*
Y1445275D01*
G01D02*
Y1451727D01*
G01X1738429Y1445275D02*
X1744881D01*
G01D02*
X1751333D01*
G01X1807676Y1478310D02*
X1809786Y1476200D01*
X1810426D01*
G01X1790226Y1465850D02*
Y1469300D01*
G01X1891555Y93819D02*
X1898669D01*
G01X1891555Y84370D02*
X1898669D01*
G01X1909941Y66319D02*
X1903169D01*
G01X1909941Y81319D02*
X1903169D01*
G01X1909941Y51319D02*
X1903169D01*
G01X1902756Y27697D02*
X1910169D01*
G01X1884600Y45750D02*
Y49000D01*
G01X1866250Y82000D02*
X1871400D01*
G01X1821850Y32000D02*
Y35400D01*
G01X1827450Y25100D02*
X1825900D01*
X1824200Y23400D01*
G01X1825550Y19000D02*
X1827450Y20900D01*
G01X1824200Y19000D02*
X1825550D01*
G01X1881750Y81500D02*
X1884700D01*
X1885200Y81000D01*
G01X1870607Y75897D02*
X1868353D01*
X1866250Y78000D01*
G01X1822428Y85039D02*
Y87728D01*
X1823300Y88600D01*
G01X1863950Y38100D02*
X1860500D01*
G01X1863950Y42100D02*
Y45400D01*
G01X1859050Y22300D02*
Y19000D01*
G01X1881750Y77500D02*
X1885421D01*
X1885508Y77413D01*
G01X1842350Y25200D02*
Y21100D01*
G01X1838450Y29300D02*
X1838650Y29500D01*
X1842400D01*
G01D02*
Y25250D01*
X1842350Y25200D01*
G01X1880500Y45750D02*
Y48900D01*
G01X1909941Y151319D02*
X1903169D01*
G01X1909941Y161319D02*
X1903169D01*
G01X1886000Y162200D02*
X1881000D01*
G01X1845700Y140000D02*
X1841000D01*
G01X1909941Y121319D02*
X1903169D01*
G01X1909941Y131319D02*
X1903169D01*
G01X1891555Y103268D02*
X1898669D01*
G01X1868400Y132500D02*
X1864800D01*
G01X1887000Y181500D02*
X1883000D01*
G01X1865000Y125500D02*
Y124324D01*
X1860817Y120141D01*
G01X1902756Y199941D02*
X1910169D01*
G01X1827100Y394300D02*
Y397886D01*
X1827114Y397900D01*
G01X1832100Y394300D02*
Y397886D01*
X1832114Y397900D01*
G01X1891555Y546575D02*
X1898669D01*
G01X1891555Y556024D02*
X1898669D01*
G01X1891555Y537126D02*
X1898669D01*
G01X1855750Y547500D02*
Y551000D01*
G01X1909941Y534075D02*
X1903169D01*
G01X1909941Y519075D02*
X1903169D01*
G01X1909941Y504075D02*
X1903169D01*
G01X1902756Y480453D02*
X1910169D01*
G01X1863000Y507250D02*
X1866500D01*
G01X1879650Y534600D02*
X1883200D01*
G01X1855750Y543500D02*
Y540000D01*
G01X1839750Y533500D02*
Y530250D01*
G01X1848250Y549000D02*
Y553000D01*
G01X1823000Y517250D02*
Y514000D01*
G01X1853000Y507250D02*
Y504000D01*
G01X1879650Y530600D02*
X1882700D01*
X1883300Y530000D01*
G01X1902756Y652697D02*
X1910169D01*
G01X1909941Y614075D02*
X1903169D01*
G01X1885800Y615200D02*
X1880500D01*
G01X1887000Y634500D02*
Y638500D01*
G01X1909941Y604075D02*
X1903169D01*
G01X1909941Y584075D02*
X1903169D01*
G01X1909941Y574075D02*
X1903169D01*
G01X1865000Y573000D02*
Y578500D01*
G01X1845700Y593000D02*
X1841000D01*
G01X1868500Y585500D02*
X1864700D01*
G01X1845157Y849250D02*
Y853598D01*
X1845155Y853600D01*
G01X1838174Y849782D02*
Y853363D01*
X1838193Y853382D01*
G01X1834674Y836182D02*
Y831932D01*
G01X1849407Y852351D02*
Y855959D01*
G01X1859500Y846500D02*
Y850100D01*
G01X1864500Y846500D02*
Y850100D01*
G01X1902756Y933209D02*
X1910169D01*
G01X1873800Y886300D02*
X1873500Y886600D01*
X1839188D01*
X1837763Y888025D01*
G01X1824772Y903550D02*
Y901016D01*
X1837763Y888025D01*
G01X1826206Y878062D02*
Y882768D01*
X1828363Y884925D01*
G01X1827763Y869025D02*
Y866025D01*
X1828763Y865025D01*
G01X1826178Y873035D02*
X1827763Y871450D01*
Y869025D01*
G01X1822706Y878062D02*
X1820643Y880125D01*
X1817863D01*
G01X1865000Y1026000D02*
Y1031500D01*
G01X1909941Y1036831D02*
X1903169D01*
G01X1909941Y1026831D02*
X1903169D01*
G01X1845700Y1046000D02*
X1841000D01*
G01X1909941Y956831D02*
X1903169D01*
G01X1891555Y1008780D02*
X1898669D01*
G01X1891555Y999331D02*
X1898669D01*
G01X1891555Y989882D02*
X1898669D01*
G01X1909941Y986831D02*
X1903169D01*
G01X1909941Y971831D02*
X1903169D01*
G01X1855750Y1000500D02*
Y1004000D01*
G01X1868200Y1038500D02*
X1864500D01*
G01X1879800Y984750D02*
X1883100D01*
G01X1863000Y960250D02*
X1859600D01*
G01X1848250Y1002000D02*
Y1006000D01*
G01X1855750Y996500D02*
Y993000D01*
G01X1823000Y969750D02*
Y966500D01*
G01X1839750Y986500D02*
Y983000D01*
G01X1853000Y960250D02*
Y957000D01*
G01X1875800Y984750D02*
Y981000D01*
G01X1902756Y1105453D02*
X1910169D01*
G01X1887000Y1087500D02*
Y1091500D01*
G01X1909941Y1066831D02*
X1903169D01*
G01X1909941Y1056831D02*
X1903169D01*
G01X1885963Y1068286D02*
X1880586D01*
X1880500Y1068200D01*
G01X1824826Y1470900D02*
Y1471100D01*
X1824626Y1470900D01*
X1821276D01*
X127988Y67319D03*
Y71319D03*
Y76319D03*
Y80319D03*
X134983Y65269D03*
Y61269D03*
Y56769D03*
Y52769D03*
X127988Y520075D03*
Y524075D03*
Y529075D03*
Y533075D03*
X134983Y518025D03*
Y514025D03*
Y509525D03*
Y505525D03*
X127988Y972831D03*
Y976831D03*
Y981831D03*
Y985831D03*
X134983Y970781D03*
Y966781D03*
Y962281D03*
Y958281D03*
X252200Y67319D03*
Y71319D03*
Y76319D03*
Y80319D03*
X259195Y65269D03*
Y61269D03*
Y56769D03*
Y52769D03*
X252200Y520075D03*
Y524075D03*
Y529075D03*
Y533075D03*
X259195Y518025D03*
Y514025D03*
Y509525D03*
Y505525D03*
X252200Y972831D03*
Y976831D03*
Y981831D03*
Y985831D03*
X259195Y970781D03*
Y966781D03*
Y962281D03*
Y958281D03*
X376413Y67319D03*
Y71319D03*
Y76319D03*
Y80319D03*
X383408Y65269D03*
Y61269D03*
Y56769D03*
Y52769D03*
X376413Y520075D03*
Y524075D03*
Y529075D03*
Y533075D03*
X383408Y518025D03*
Y514025D03*
Y509525D03*
Y505525D03*
X376413Y972831D03*
Y976831D03*
Y981831D03*
Y985831D03*
X383408Y970781D03*
Y966781D03*
Y962281D03*
Y958281D03*
X500625Y67319D03*
Y71319D03*
Y76319D03*
Y80319D03*
X507620Y65269D03*
Y61269D03*
Y56769D03*
Y52769D03*
X500625Y520075D03*
Y524075D03*
Y529075D03*
Y533075D03*
X507620Y518025D03*
Y514025D03*
Y509525D03*
Y505525D03*
X500625Y972831D03*
Y976831D03*
Y981831D03*
Y985831D03*
X507620Y970781D03*
Y966781D03*
Y962281D03*
Y958281D03*
X500000Y1472000D03*
X624838Y67319D03*
Y71319D03*
Y76319D03*
Y80319D03*
X631833Y65269D03*
Y61269D03*
Y56769D03*
Y52769D03*
X624838Y520075D03*
Y524075D03*
Y529075D03*
Y533075D03*
X631833Y518025D03*
Y514025D03*
Y509525D03*
Y505525D03*
X624838Y972831D03*
Y976831D03*
Y981831D03*
Y985831D03*
X631833Y970781D03*
Y966781D03*
Y962281D03*
Y958281D03*
X749051Y67319D03*
Y71319D03*
Y76319D03*
Y80319D03*
X756046Y65269D03*
Y61269D03*
Y56769D03*
Y52769D03*
X749051Y520075D03*
Y524075D03*
Y529075D03*
Y533075D03*
X756046Y518025D03*
Y514025D03*
Y509525D03*
Y505525D03*
X749051Y972831D03*
Y976831D03*
Y981831D03*
Y985831D03*
X756046Y970781D03*
Y966781D03*
Y962281D03*
Y958281D03*
X918400Y760750D03*
X1279400Y68650D03*
X1275400D03*
X1270400D03*
X1266400D03*
X1252750Y53650D03*
X1256750D03*
X1261250D03*
X1265250D03*
X1279400Y521406D03*
X1275400D03*
X1270400D03*
X1266400D03*
X1252750Y506406D03*
X1256750D03*
X1261250D03*
X1265250D03*
X1273975Y972831D03*
Y976831D03*
Y981831D03*
Y985831D03*
X1257490Y970361D03*
Y966361D03*
Y961861D03*
Y957861D03*
X1403613Y68650D03*
X1399613D03*
X1394613D03*
X1390613D03*
X1376963Y53650D03*
X1380963D03*
X1385463D03*
X1389463D03*
X1403613Y521406D03*
X1399613D03*
X1394613D03*
X1390613D03*
X1376963Y506406D03*
X1380963D03*
X1385463D03*
X1389463D03*
X1398188Y972831D03*
Y976831D03*
Y981831D03*
Y985831D03*
X1381663Y970381D03*
Y966381D03*
Y961881D03*
Y957881D03*
X1527825Y68650D03*
X1523825D03*
X1518825D03*
X1514825D03*
X1501175Y53650D03*
X1505175D03*
X1509675D03*
X1513675D03*
X1527825Y521406D03*
X1523825D03*
X1518825D03*
X1514825D03*
X1501175Y506406D03*
X1505175D03*
X1509675D03*
X1513675D03*
X1522400Y972831D03*
Y976831D03*
Y981831D03*
Y985831D03*
X1505875Y970321D03*
Y966321D03*
Y961821D03*
Y957821D03*
X1625388Y53650D03*
Y506406D03*
X1652038Y68650D03*
X1648038D03*
X1643038D03*
X1639038D03*
X1629388Y53650D03*
X1633888D03*
X1637888D03*
X1652038Y521406D03*
X1648038D03*
X1643038D03*
X1639038D03*
X1629388Y506406D03*
X1633888D03*
X1637888D03*
X1646613Y972831D03*
Y976831D03*
Y981831D03*
Y985831D03*
X1630088Y970881D03*
Y966881D03*
Y962381D03*
Y958381D03*
X1776250Y68650D03*
X1772250D03*
X1767250D03*
X1763250D03*
X1749600Y53650D03*
X1753600D03*
X1758100D03*
X1762100D03*
X1776250Y521406D03*
X1772250D03*
X1767250D03*
X1763250D03*
X1749600Y506406D03*
X1753600D03*
X1758100D03*
X1762100D03*
X1770825Y972831D03*
Y976831D03*
Y981831D03*
Y985831D03*
X1754340Y970361D03*
Y966361D03*
Y961861D03*
Y957861D03*
X1900463Y68650D03*
X1896463D03*
X1891463D03*
X1887463D03*
X1873813Y53650D03*
X1877813D03*
X1882313D03*
X1886313D03*
X1900463Y521406D03*
X1896463D03*
X1891463D03*
X1887463D03*
X1873813Y506406D03*
X1877813D03*
X1882313D03*
X1886313D03*
X1895038Y972831D03*
Y976831D03*
Y981831D03*
Y985831D03*
X1878553Y970361D03*
Y966361D03*
Y961861D03*
Y957861D03*
G54D19*
X72500Y67200D03*
Y519700D03*
Y972700D03*
X102263Y915725D03*
X180374Y1420200D03*
X162274Y1422800D03*
X180374Y1412550D03*
X139374Y1481700D03*
X162374Y1431400D03*
X105474Y1476685D03*
X215500Y77200D03*
X220000D03*
X202800Y40900D03*
X196500Y519700D03*
X200090Y477989D03*
X197000Y972700D03*
X321000Y67200D03*
Y519700D03*
Y972700D03*
X464000Y77200D03*
X468500D03*
X444400Y39200D03*
X435100Y122300D03*
X445000Y519700D03*
Y972700D03*
X569500Y67200D03*
Y519700D03*
Y972700D03*
X500000Y1468700D03*
X672000Y1425700D03*
X655795Y1440119D03*
X653000Y1484700D03*
X712500Y77200D03*
X717000D03*
X699600Y40800D03*
X693500Y519700D03*
Y972700D03*
X689000Y1425700D03*
X681000D03*
X680500Y1479700D03*
X703500Y1432700D03*
X730232Y1464719D03*
X752832Y1461719D03*
X860298Y413792D03*
X862766Y424592D03*
X850947Y413792D03*
X830470Y927630D03*
X826470D03*
X818470D03*
X826470Y977630D03*
X839970D03*
X834470D03*
X872137Y424592D03*
X950639Y550441D03*
X947587Y524082D03*
X871240Y639140D03*
X868500Y803000D03*
X957500Y849200D03*
X944000D03*
X935000D03*
X939500D03*
X927260Y919070D03*
X915580Y864070D03*
X922760Y919070D03*
X909760D03*
X924670Y864040D03*
X920170D03*
X955500Y1229700D03*
X947500D03*
X943500D03*
X869937Y1390329D03*
X944016Y1448972D03*
X991129Y551101D03*
X987333Y526468D03*
X962000Y849200D03*
X977570Y835128D03*
X973070D03*
X983070Y833190D03*
X1005450Y845460D03*
X1000950D03*
X1029600Y857000D03*
X985542Y879500D03*
X989742D03*
X972042Y881200D03*
X1030515Y886681D03*
X1033315Y894281D03*
X1039500Y886700D03*
X1048000Y893700D03*
X967500Y1229700D03*
X963500D03*
X1010943Y1420599D03*
X979443Y1414599D03*
X988443Y1413599D03*
X996443D03*
X963238Y1428018D03*
X1017618Y1467565D03*
X994271Y1467617D03*
X1021618Y1467565D03*
X1038303Y1448349D03*
X1040663Y1467841D03*
X1115825Y621943D03*
X1055500Y893700D03*
X1060118Y1384789D03*
X1126112Y1369973D03*
X1130112D03*
X1223730Y1292483D03*
X1235600D03*
X1230600D03*
X1190524D03*
X1197394D03*
X1202394D03*
X1241600Y1343483D03*
X1227100D03*
X1208394D03*
X1193894D03*
X1303500Y41700D03*
X1307500Y508200D03*
Y960700D03*
X1319500Y1420200D03*
Y1412550D03*
X1251874Y1484385D03*
X1431500Y55200D03*
Y508200D03*
Y960700D03*
X1553000Y41700D03*
X1556000Y508200D03*
Y960700D03*
X1680000Y55200D03*
Y508200D03*
Y960700D03*
X1707626Y1420200D03*
Y1412550D03*
X1652510Y1456700D03*
X1799100Y78500D03*
X1808500Y64400D03*
X1803400Y53800D03*
X1808300Y53900D03*
X1804000Y508200D03*
X1742859Y481407D03*
X1817263Y915725D03*
X1804000Y960700D03*
X1807676Y1481760D03*
X1880500Y45700D03*
X1872900D03*
X1874900Y25200D03*
X1863000Y510700D03*
Y963700D03*
G54D28*
X64200Y95000D03*
Y547500D03*
Y1000500D03*
X144500Y25200D03*
X188200Y547500D03*
X107628Y873035D03*
X188700Y1000500D03*
X205455Y435299D03*
X312700Y95000D03*
Y547500D03*
Y1000500D03*
X436700Y547500D03*
Y1000500D03*
X402200Y1408000D03*
X561200Y95000D03*
Y547500D03*
Y1000500D03*
X507200Y1474500D03*
X524900Y1448100D03*
X685200Y547500D03*
Y1000500D03*
X940200Y890000D03*
X1009700Y846500D03*
X1000507Y895075D03*
X990124Y891165D03*
X1113812Y1402773D03*
X1301500Y63900D03*
X1303300Y534000D03*
X1304300Y986200D03*
X1427800Y533900D03*
Y986400D03*
X1551900Y63300D03*
Y533800D03*
X1552200Y986600D03*
X1676500Y534100D03*
X1676100Y986300D03*
X1811300Y24800D03*
X1748224Y438717D03*
X1800500Y534100D03*
X1759700Y579500D03*
X1800200Y986200D03*
X1855700Y547500D03*
X1822628Y873035D03*
X1855700Y1000500D03*
G54D73*
X627499Y1290524D03*
X659901D03*
Y1415176D03*
X627499D03*
X948099Y1356976D03*
X980501D03*
G54D91*
X957000Y1207500D03*
X1124612Y1388773D03*
G54D37*
X61800Y140500D03*
X54200D03*
X61800Y593000D03*
X54200D03*
X72490Y881867D03*
X80090D03*
X72490Y874206D03*
X80090D03*
X87194Y872375D03*
X94794D03*
X61800Y1046000D03*
X54200D03*
X86624Y1465850D03*
X94224D03*
X94324Y1473650D03*
X86724D03*
X185800Y140500D03*
X178200D03*
X170317Y444131D03*
X177917D03*
X170317Y436470D03*
X177917D03*
X185021Y434639D03*
X192621D03*
X185800Y593000D03*
X178200D03*
X186300Y1046000D03*
X178700D03*
X310300Y140500D03*
X302700D03*
X310300Y593000D03*
X302700D03*
X310300Y1046000D03*
X302700D03*
X434300Y140500D03*
X426700D03*
X434300Y593000D03*
X426700D03*
X434300Y1046000D03*
X426700D03*
X558800Y140500D03*
X551200D03*
X558800Y593000D03*
X551200D03*
X558800Y1046000D03*
X551200D03*
X682800Y140500D03*
X675200D03*
X682800Y593000D03*
X675200D03*
X682800Y1046000D03*
X675200D03*
X731350Y1486450D03*
X738950D03*
Y1494250D03*
X731350D03*
X817800Y1333000D03*
X810200D03*
X847295Y1392884D03*
X839695D03*
X839656Y1400536D03*
X847256D03*
X830342Y1402656D03*
X822742D03*
X817800Y1371500D03*
X810200D03*
X1049568Y1327989D03*
X1041968D03*
X1041818Y1391589D03*
X1049418D03*
Y1399389D03*
X1041818D03*
X1049568Y1355789D03*
X1041968D03*
X1049568Y1383589D03*
X1041968D03*
X1125673Y1493448D03*
X1118073D03*
X1234874Y1465500D03*
X1242474D03*
Y1473200D03*
X1234874D03*
X1713086Y447549D03*
X1720686D03*
X1713086Y439888D03*
X1720686D03*
X1727790Y438057D03*
X1735390D03*
X1787490Y881867D03*
X1795090D03*
X1787490Y874206D03*
X1795090D03*
X1802194Y872375D03*
X1809794D03*
X1853300Y140000D03*
X1845700D03*
X1853300Y593000D03*
X1845700D03*
X1853300Y1046000D03*
X1845700D03*
X1842026Y1473350D03*
X1834426D03*
X1834526Y1465600D03*
X1842126D03*
G54D46*
X118209Y81319D03*
Y76319D03*
Y71319D03*
Y66319D03*
Y61319D03*
Y56319D03*
Y51319D03*
Y176319D03*
Y171319D03*
Y166319D03*
Y161319D03*
Y156319D03*
Y151319D03*
Y146319D03*
Y141319D03*
Y136319D03*
Y131319D03*
Y126319D03*
Y121319D03*
Y116319D03*
Y111319D03*
Y106319D03*
Y569075D03*
Y564075D03*
Y559075D03*
Y534075D03*
Y529075D03*
Y524075D03*
Y519075D03*
Y514075D03*
Y509075D03*
Y504075D03*
Y629075D03*
Y624075D03*
Y619075D03*
Y614075D03*
Y609075D03*
Y604075D03*
Y599075D03*
Y594075D03*
Y589075D03*
Y584075D03*
Y579075D03*
Y574075D03*
Y1046831D03*
Y1041831D03*
Y1036831D03*
Y1031831D03*
Y1026831D03*
Y1021831D03*
Y1016831D03*
Y1011831D03*
Y986831D03*
Y981831D03*
Y976831D03*
Y971831D03*
Y966831D03*
Y961831D03*
Y956831D03*
Y1081831D03*
Y1076831D03*
Y1071831D03*
Y1066831D03*
Y1061831D03*
Y1056831D03*
Y1051831D03*
X242421Y81319D03*
Y76319D03*
Y71319D03*
Y66319D03*
Y61319D03*
Y56319D03*
Y51319D03*
Y176319D03*
Y171319D03*
Y166319D03*
Y161319D03*
Y156319D03*
Y151319D03*
Y146319D03*
Y141319D03*
Y136319D03*
Y131319D03*
Y126319D03*
Y121319D03*
Y116319D03*
Y111319D03*
Y106319D03*
Y569075D03*
Y564075D03*
Y559075D03*
Y534075D03*
Y529075D03*
Y524075D03*
Y519075D03*
Y514075D03*
Y509075D03*
Y504075D03*
Y629075D03*
Y624075D03*
Y619075D03*
Y614075D03*
Y609075D03*
Y604075D03*
Y599075D03*
Y594075D03*
Y589075D03*
Y584075D03*
Y579075D03*
Y574075D03*
Y1046831D03*
Y1041831D03*
Y1036831D03*
Y1031831D03*
Y1026831D03*
Y1021831D03*
Y1016831D03*
Y1011831D03*
Y986831D03*
Y981831D03*
Y976831D03*
Y971831D03*
Y966831D03*
Y961831D03*
Y956831D03*
Y1081831D03*
Y1076831D03*
Y1071831D03*
Y1066831D03*
Y1061831D03*
Y1056831D03*
Y1051831D03*
X366634Y81319D03*
Y76319D03*
Y71319D03*
Y66319D03*
Y61319D03*
Y56319D03*
Y51319D03*
Y176319D03*
Y171319D03*
Y166319D03*
Y161319D03*
Y156319D03*
Y151319D03*
Y146319D03*
Y141319D03*
Y136319D03*
Y131319D03*
Y126319D03*
Y121319D03*
Y116319D03*
Y111319D03*
Y106319D03*
Y569075D03*
Y564075D03*
Y559075D03*
Y534075D03*
Y529075D03*
Y524075D03*
Y519075D03*
Y514075D03*
Y509075D03*
Y504075D03*
Y629075D03*
Y624075D03*
Y619075D03*
Y614075D03*
Y609075D03*
Y604075D03*
Y599075D03*
Y594075D03*
Y589075D03*
Y584075D03*
Y579075D03*
Y574075D03*
Y1046831D03*
Y1041831D03*
Y1036831D03*
Y1031831D03*
Y1026831D03*
Y1021831D03*
Y1016831D03*
Y1011831D03*
Y986831D03*
Y981831D03*
Y976831D03*
Y971831D03*
Y966831D03*
Y961831D03*
Y956831D03*
Y1081831D03*
Y1076831D03*
Y1071831D03*
Y1066831D03*
Y1061831D03*
Y1056831D03*
Y1051831D03*
X490846Y81319D03*
Y76319D03*
Y71319D03*
Y66319D03*
Y61319D03*
Y56319D03*
Y51319D03*
Y176319D03*
Y171319D03*
Y166319D03*
Y161319D03*
Y156319D03*
Y151319D03*
Y146319D03*
Y141319D03*
Y136319D03*
Y131319D03*
Y126319D03*
Y121319D03*
Y116319D03*
Y111319D03*
Y106319D03*
Y569075D03*
Y564075D03*
Y559075D03*
Y534075D03*
Y529075D03*
Y524075D03*
Y519075D03*
Y514075D03*
Y509075D03*
Y504075D03*
Y629075D03*
Y624075D03*
Y619075D03*
Y614075D03*
Y609075D03*
Y604075D03*
Y599075D03*
Y594075D03*
Y589075D03*
Y584075D03*
Y579075D03*
Y574075D03*
Y1046831D03*
Y1041831D03*
Y1036831D03*
Y1031831D03*
Y1026831D03*
Y1021831D03*
Y1016831D03*
Y1011831D03*
Y986831D03*
Y981831D03*
Y976831D03*
Y971831D03*
Y966831D03*
Y961831D03*
Y956831D03*
Y1081831D03*
Y1076831D03*
Y1071831D03*
Y1066831D03*
Y1061831D03*
Y1056831D03*
Y1051831D03*
X615059Y81319D03*
Y76319D03*
Y71319D03*
Y66319D03*
Y61319D03*
Y56319D03*
Y51319D03*
Y176319D03*
Y171319D03*
Y166319D03*
Y161319D03*
Y156319D03*
Y151319D03*
Y146319D03*
Y141319D03*
Y136319D03*
Y131319D03*
Y126319D03*
Y121319D03*
Y116319D03*
Y111319D03*
Y106319D03*
Y569075D03*
Y564075D03*
Y559075D03*
Y534075D03*
Y529075D03*
Y524075D03*
Y519075D03*
Y514075D03*
Y509075D03*
Y504075D03*
Y629075D03*
Y624075D03*
Y619075D03*
Y614075D03*
Y609075D03*
Y604075D03*
Y599075D03*
Y594075D03*
Y589075D03*
Y584075D03*
Y579075D03*
Y574075D03*
Y1046831D03*
Y1041831D03*
Y1036831D03*
Y1031831D03*
Y1026831D03*
Y1021831D03*
Y1016831D03*
Y1011831D03*
Y986831D03*
Y981831D03*
Y976831D03*
Y971831D03*
Y966831D03*
Y961831D03*
Y956831D03*
Y1081831D03*
Y1076831D03*
Y1071831D03*
Y1066831D03*
Y1061831D03*
Y1056831D03*
Y1051831D03*
X739272Y81319D03*
Y76319D03*
Y71319D03*
Y66319D03*
Y61319D03*
Y56319D03*
Y51319D03*
Y176319D03*
Y171319D03*
Y166319D03*
Y161319D03*
Y156319D03*
Y151319D03*
Y146319D03*
Y141319D03*
Y136319D03*
Y131319D03*
Y126319D03*
Y121319D03*
Y116319D03*
Y111319D03*
Y106319D03*
Y569075D03*
Y564075D03*
Y559075D03*
Y534075D03*
Y529075D03*
Y524075D03*
Y519075D03*
Y514075D03*
Y509075D03*
Y504075D03*
Y629075D03*
Y624075D03*
Y619075D03*
Y614075D03*
Y609075D03*
Y604075D03*
Y599075D03*
Y594075D03*
Y589075D03*
Y584075D03*
Y579075D03*
Y574075D03*
Y1046831D03*
Y1041831D03*
Y1036831D03*
Y1031831D03*
Y1026831D03*
Y1021831D03*
Y1016831D03*
Y1011831D03*
Y986831D03*
Y981831D03*
Y976831D03*
Y971831D03*
Y966831D03*
Y961831D03*
Y956831D03*
Y1081831D03*
Y1076831D03*
Y1071831D03*
Y1066831D03*
Y1061831D03*
Y1056831D03*
Y1051831D03*
X1288878Y81319D03*
Y76319D03*
Y71319D03*
Y66319D03*
Y61319D03*
Y56319D03*
Y51319D03*
Y176319D03*
Y171319D03*
Y166319D03*
Y161319D03*
Y156319D03*
Y151319D03*
Y146319D03*
Y141319D03*
Y136319D03*
Y131319D03*
Y126319D03*
Y121319D03*
Y116319D03*
Y111319D03*
Y106319D03*
Y569075D03*
Y564075D03*
Y559075D03*
Y534075D03*
Y529075D03*
Y524075D03*
Y519075D03*
Y514075D03*
Y509075D03*
Y504075D03*
Y629075D03*
Y624075D03*
Y619075D03*
Y614075D03*
Y609075D03*
Y604075D03*
Y599075D03*
Y594075D03*
Y589075D03*
Y584075D03*
Y579075D03*
Y574075D03*
Y1046831D03*
Y1041831D03*
Y1036831D03*
Y1031831D03*
Y1026831D03*
Y1021831D03*
Y1016831D03*
Y1011831D03*
Y986831D03*
Y981831D03*
Y976831D03*
Y971831D03*
Y966831D03*
Y961831D03*
Y956831D03*
Y1081831D03*
Y1076831D03*
Y1071831D03*
Y1066831D03*
Y1061831D03*
Y1056831D03*
Y1051831D03*
X1413091Y81319D03*
Y76319D03*
Y71319D03*
Y66319D03*
Y61319D03*
Y56319D03*
Y51319D03*
Y176319D03*
Y171319D03*
Y166319D03*
Y161319D03*
Y156319D03*
Y151319D03*
Y146319D03*
Y141319D03*
Y136319D03*
Y131319D03*
Y126319D03*
Y121319D03*
Y116319D03*
Y111319D03*
Y106319D03*
Y569075D03*
Y564075D03*
Y559075D03*
Y534075D03*
Y529075D03*
Y524075D03*
Y519075D03*
Y514075D03*
Y509075D03*
Y504075D03*
Y629075D03*
Y624075D03*
Y619075D03*
Y614075D03*
Y609075D03*
Y604075D03*
Y599075D03*
Y594075D03*
Y589075D03*
Y584075D03*
Y579075D03*
Y574075D03*
Y1046831D03*
Y1041831D03*
Y1036831D03*
Y1031831D03*
Y1026831D03*
Y1021831D03*
Y1016831D03*
Y1011831D03*
Y986831D03*
Y981831D03*
Y976831D03*
Y971831D03*
Y966831D03*
Y961831D03*
Y956831D03*
Y1081831D03*
Y1076831D03*
Y1071831D03*
Y1066831D03*
Y1061831D03*
Y1056831D03*
Y1051831D03*
X1537303Y81319D03*
Y76319D03*
Y71319D03*
Y66319D03*
Y61319D03*
Y56319D03*
Y51319D03*
Y176319D03*
Y171319D03*
Y166319D03*
Y161319D03*
Y156319D03*
Y151319D03*
Y146319D03*
Y141319D03*
Y136319D03*
Y131319D03*
Y126319D03*
Y121319D03*
Y116319D03*
Y111319D03*
Y106319D03*
Y569075D03*
Y564075D03*
Y559075D03*
Y534075D03*
Y529075D03*
Y524075D03*
Y519075D03*
Y514075D03*
Y509075D03*
Y504075D03*
Y629075D03*
Y624075D03*
Y619075D03*
Y614075D03*
Y609075D03*
Y604075D03*
Y599075D03*
Y594075D03*
Y589075D03*
Y584075D03*
Y579075D03*
Y574075D03*
Y1046831D03*
Y1041831D03*
Y1036831D03*
Y1031831D03*
Y1026831D03*
Y1021831D03*
Y1016831D03*
Y1011831D03*
Y986831D03*
Y981831D03*
Y976831D03*
Y971831D03*
Y966831D03*
Y961831D03*
Y956831D03*
Y1081831D03*
Y1076831D03*
Y1071831D03*
Y1066831D03*
Y1061831D03*
Y1056831D03*
Y1051831D03*
X1661516Y81319D03*
Y76319D03*
Y71319D03*
Y66319D03*
Y61319D03*
Y56319D03*
Y51319D03*
Y176319D03*
Y171319D03*
Y166319D03*
Y161319D03*
Y156319D03*
Y151319D03*
Y146319D03*
Y141319D03*
Y136319D03*
Y131319D03*
Y126319D03*
Y121319D03*
Y116319D03*
Y111319D03*
Y106319D03*
Y569075D03*
Y564075D03*
Y559075D03*
Y534075D03*
Y529075D03*
Y524075D03*
Y519075D03*
Y514075D03*
Y509075D03*
Y504075D03*
Y629075D03*
Y624075D03*
Y619075D03*
Y614075D03*
Y609075D03*
Y604075D03*
Y599075D03*
Y594075D03*
Y589075D03*
Y584075D03*
Y579075D03*
Y574075D03*
Y1046831D03*
Y1041831D03*
Y1036831D03*
Y1031831D03*
Y1026831D03*
Y1021831D03*
Y1016831D03*
Y1011831D03*
Y986831D03*
Y981831D03*
Y976831D03*
Y971831D03*
Y966831D03*
Y961831D03*
Y956831D03*
Y1081831D03*
Y1076831D03*
Y1071831D03*
Y1066831D03*
Y1061831D03*
Y1056831D03*
Y1051831D03*
X1785728Y81319D03*
Y76319D03*
Y71319D03*
Y66319D03*
Y61319D03*
Y56319D03*
Y51319D03*
Y176319D03*
Y171319D03*
Y166319D03*
Y161319D03*
Y156319D03*
Y151319D03*
Y146319D03*
Y141319D03*
Y136319D03*
Y131319D03*
Y126319D03*
Y121319D03*
Y116319D03*
Y111319D03*
Y106319D03*
Y569075D03*
Y564075D03*
Y559075D03*
Y534075D03*
Y529075D03*
Y524075D03*
Y519075D03*
Y514075D03*
Y509075D03*
Y504075D03*
Y629075D03*
Y624075D03*
Y619075D03*
Y614075D03*
Y609075D03*
Y604075D03*
Y599075D03*
Y594075D03*
Y589075D03*
Y584075D03*
Y579075D03*
Y574075D03*
Y1046831D03*
Y1041831D03*
Y1036831D03*
Y1031831D03*
Y1026831D03*
Y1021831D03*
Y1016831D03*
Y1011831D03*
Y986831D03*
Y981831D03*
Y976831D03*
Y971831D03*
Y966831D03*
Y961831D03*
Y956831D03*
Y1081831D03*
Y1076831D03*
Y1071831D03*
Y1066831D03*
Y1061831D03*
Y1056831D03*
Y1051831D03*
X1909941Y81319D03*
Y76319D03*
Y71319D03*
Y66319D03*
Y61319D03*
Y56319D03*
Y51319D03*
Y176319D03*
Y171319D03*
Y166319D03*
Y161319D03*
Y156319D03*
Y151319D03*
Y146319D03*
Y141319D03*
Y136319D03*
Y131319D03*
Y126319D03*
Y121319D03*
Y116319D03*
Y111319D03*
Y106319D03*
Y569075D03*
Y564075D03*
Y559075D03*
Y534075D03*
Y529075D03*
Y524075D03*
Y519075D03*
Y514075D03*
Y509075D03*
Y504075D03*
Y629075D03*
Y624075D03*
Y619075D03*
Y614075D03*
Y609075D03*
Y604075D03*
Y599075D03*
Y594075D03*
Y589075D03*
Y584075D03*
Y579075D03*
Y574075D03*
Y1046831D03*
Y1041831D03*
Y1036831D03*
Y1031831D03*
Y1026831D03*
Y1021831D03*
Y1016831D03*
Y1011831D03*
Y986831D03*
Y981831D03*
Y976831D03*
Y971831D03*
Y966831D03*
Y961831D03*
Y956831D03*
Y1081831D03*
Y1076831D03*
Y1071831D03*
Y1066831D03*
Y1061831D03*
Y1056831D03*
Y1051831D03*
G54D64*
X110639Y1486040D03*
Y1488600D03*
Y1491160D03*
X118709D03*
Y1488600D03*
Y1486040D03*
X736597Y1471974D03*
Y1474534D03*
Y1477094D03*
X744667D03*
Y1474534D03*
Y1471974D03*
X1256939Y1490840D03*
Y1493400D03*
Y1495960D03*
X1265009D03*
Y1493400D03*
Y1490840D03*
G54D55*
X127600Y122600D03*
X158474Y1419300D03*
X153374Y1453700D03*
Y1435200D03*
X250900Y122800D03*
X375500D03*
X440849Y115300D03*
X499900Y122700D03*
X624000D03*
X668000Y1422200D03*
X672500Y1476200D03*
X748200Y575500D03*
X698500Y1422200D03*
X685000D03*
X693000D03*
X735232Y1443534D03*
X990100Y829700D03*
X1026515Y883181D03*
X1000443Y1410099D03*
X992443D03*
X975443Y1411099D03*
X1005943Y1410099D03*
X1035943Y1428099D03*
X971438Y1450108D03*
X1207440Y1421054D03*
X1266600Y122800D03*
Y575500D03*
X1266400Y1028200D03*
X1300374Y1453700D03*
Y1435200D03*
X1253374Y1463100D03*
X1391200Y122800D03*
X1390400Y575500D03*
X1391000Y1028300D03*
X1515400Y122800D03*
X1515200Y575500D03*
X1515400Y1028300D03*
X1639300Y122800D03*
X1638200Y575500D03*
X1639100Y1028300D03*
X1680626Y1453700D03*
Y1435200D03*
X1763600Y122800D03*
X1763300Y1028300D03*
X1790226Y1462300D03*
X1879800Y984700D03*
G54D82*
X862205Y277953D03*
X848032D03*
X833859D03*
X862205Y272441D03*
X848032D03*
X833859D03*
X862205Y263779D03*
X848032D03*
X833859D03*
X862205Y258268D03*
X848032D03*
X833859D03*
X862205Y282283D03*
X848032D03*
X833859D03*
X862205Y268110D03*
X848032D03*
X833859D03*
X862205Y253937D03*
X848032D03*
X833859D03*
X855118Y282677D03*
X840945D03*
X826772D03*
X855118Y277165D03*
X840945D03*
X826772D03*
X855118Y272835D03*
X840945D03*
X826772D03*
X855118Y268504D03*
X840945D03*
X826772D03*
X855118Y262992D03*
X840945D03*
X826772D03*
X862205Y306299D03*
X848032D03*
X833859D03*
X862205Y300787D03*
X848032D03*
X833859D03*
X862205Y292126D03*
X848032D03*
X833859D03*
X862205Y286614D03*
X848032D03*
X833859D03*
X862205Y310630D03*
X848032D03*
X833859D03*
X862205Y296457D03*
X848032D03*
X833859D03*
X855118Y311023D03*
X840945D03*
X826772D03*
X855118Y305512D03*
X840945D03*
X826772D03*
X855118Y296850D03*
X840945D03*
X826772D03*
X855118Y291338D03*
X840945D03*
X826772D03*
X855118Y315354D03*
X840945D03*
X826772D03*
X855118Y301181D03*
X840945D03*
X826772D03*
X855118Y287008D03*
X840945D03*
X826772D03*
X904725Y272835D03*
Y277165D03*
Y282677D03*
X911811Y272441D03*
Y277953D03*
Y282283D03*
X904725Y262992D03*
Y268504D03*
X911811Y253937D03*
Y258268D03*
Y263779D03*
Y268110D03*
X897638Y282283D03*
Y272441D03*
Y277953D03*
Y253937D03*
Y268110D03*
Y258268D03*
Y263779D03*
X890552Y272835D03*
Y277165D03*
Y282677D03*
Y262992D03*
Y268504D03*
X876378Y277953D03*
Y272441D03*
Y263779D03*
Y258268D03*
Y282283D03*
Y268110D03*
Y253937D03*
X869292Y282677D03*
Y277165D03*
Y272835D03*
Y268504D03*
Y262992D03*
X904725Y305512D03*
Y311023D03*
Y315354D03*
X911811Y306299D03*
Y310630D03*
X904725Y301181D03*
X911811Y300787D03*
X904725Y287008D03*
Y291338D03*
Y296850D03*
X911811Y286614D03*
Y292126D03*
Y296457D03*
X897638Y310630D03*
Y306299D03*
Y296457D03*
Y286614D03*
Y292126D03*
Y300787D03*
X890552Y315354D03*
Y305512D03*
Y311023D03*
Y287008D03*
Y301181D03*
Y291338D03*
Y296850D03*
X876378Y306299D03*
Y300787D03*
Y292126D03*
Y286614D03*
Y310630D03*
Y296457D03*
X869292Y311023D03*
Y305512D03*
Y296850D03*
Y291338D03*
Y315354D03*
Y301181D03*
Y287008D03*
X1091089Y520057D03*
X1095420D03*
X1100932D03*
X1105262D03*
X1109593D03*
X1115105D03*
X1119435D03*
X1123766D03*
X1129278D03*
X1133609D03*
X1095026Y527143D03*
X1099357D03*
X1104869D03*
X1109199D03*
X1113530D03*
X1119042D03*
X1123372D03*
X1127703D03*
X1133215D03*
X1091089Y534230D03*
X1095420D03*
X1100932D03*
X1105262D03*
X1109593D03*
X1115105D03*
X1119435D03*
X1123766D03*
X1129278D03*
X1133609D03*
X1095026Y541317D03*
X1099357D03*
X1104869D03*
X1109199D03*
X1113530D03*
X1119042D03*
X1123372D03*
X1127703D03*
X1133215D03*
X1091089Y548403D03*
X1095420D03*
X1100932D03*
X1105262D03*
X1109593D03*
X1115105D03*
X1119435D03*
X1123766D03*
X1129278D03*
X1133609D03*
X1095026Y555490D03*
X1099357D03*
X1104869D03*
X1109199D03*
X1113530D03*
X1119042D03*
X1123372D03*
X1127703D03*
X1133215D03*
X1091089Y562576D03*
X1095420D03*
X1100932D03*
X1105262D03*
X1109593D03*
X1115105D03*
X1119435D03*
X1123766D03*
X1129278D03*
X1133609D03*
X1095026Y569663D03*
X1099357D03*
X1104869D03*
X1109199D03*
X1113530D03*
X1119042D03*
X1123372D03*
X1127703D03*
X1133215D03*
X1091089Y691711D03*
Y705884D03*
Y720057D03*
Y734230D03*
Y748403D03*
Y762577D03*
X1095420Y691711D03*
Y705884D03*
Y720057D03*
Y734230D03*
Y748403D03*
Y762577D03*
X1100932Y691711D03*
Y705884D03*
Y720057D03*
Y734230D03*
Y748403D03*
Y762577D03*
X1105262Y691711D03*
Y705884D03*
Y720057D03*
Y734230D03*
Y748403D03*
Y762577D03*
X1109593Y691711D03*
Y705884D03*
Y720057D03*
Y734230D03*
Y748403D03*
Y762577D03*
X1115105Y691711D03*
Y705884D03*
Y720057D03*
Y734230D03*
Y748403D03*
Y762577D03*
X1119435Y691711D03*
Y705884D03*
Y720057D03*
Y734230D03*
Y748403D03*
Y762577D03*
X1123766Y691711D03*
Y705884D03*
Y720057D03*
Y734230D03*
Y748403D03*
Y762577D03*
X1129278Y691711D03*
Y705884D03*
Y720057D03*
Y734230D03*
Y748403D03*
Y762577D03*
X1133609Y691711D03*
Y705884D03*
Y720057D03*
Y734230D03*
Y748403D03*
Y762577D03*
X1095026Y698797D03*
Y712970D03*
Y727144D03*
Y741317D03*
Y755490D03*
X1099357Y698797D03*
Y712970D03*
Y727144D03*
Y741317D03*
Y755490D03*
X1104869Y698797D03*
Y712970D03*
Y727144D03*
Y741317D03*
Y755490D03*
X1109199Y698797D03*
Y712970D03*
Y727144D03*
Y741317D03*
Y755490D03*
X1113530Y698797D03*
Y712970D03*
Y727144D03*
Y741317D03*
Y755490D03*
X1119042Y698797D03*
Y712970D03*
Y727144D03*
Y741317D03*
Y755490D03*
X1123372Y698797D03*
Y712970D03*
Y727144D03*
Y741317D03*
Y755490D03*
X1127703Y698797D03*
Y712970D03*
Y727144D03*
Y741317D03*
Y755490D03*
X1133215Y698797D03*
Y712970D03*
Y727144D03*
Y741317D03*
Y755490D03*
X1091089Y776750D03*
Y790923D03*
Y805096D03*
Y819270D03*
Y833443D03*
Y847616D03*
X1095420Y776750D03*
Y790923D03*
Y805096D03*
Y819270D03*
Y833443D03*
Y847616D03*
X1100932Y776750D03*
Y790923D03*
Y805096D03*
Y819270D03*
Y833443D03*
Y847616D03*
X1105262Y776750D03*
Y790923D03*
Y805096D03*
Y819270D03*
Y833443D03*
Y847616D03*
X1109593Y776750D03*
Y790923D03*
Y805096D03*
Y819270D03*
Y833443D03*
Y847616D03*
X1115105Y776750D03*
Y790923D03*
Y805096D03*
Y819270D03*
Y833443D03*
Y847616D03*
X1119435Y776750D03*
Y790923D03*
Y805096D03*
Y819270D03*
Y833443D03*
Y847616D03*
X1123766Y776750D03*
Y790923D03*
Y805096D03*
Y819270D03*
Y833443D03*
Y847616D03*
X1129278Y776750D03*
Y790923D03*
Y805096D03*
Y819270D03*
Y833443D03*
Y847616D03*
X1133609Y776750D03*
Y790923D03*
Y805096D03*
Y819270D03*
Y833443D03*
Y847616D03*
X1095026Y769663D03*
Y783836D03*
Y798010D03*
Y812183D03*
Y826356D03*
Y840529D03*
Y854703D03*
X1099357Y769663D03*
Y783836D03*
Y798010D03*
Y812183D03*
Y826356D03*
Y840529D03*
Y854703D03*
X1104869Y769663D03*
Y783836D03*
Y798010D03*
Y812183D03*
Y826356D03*
Y840529D03*
Y854703D03*
X1109199Y769663D03*
Y783836D03*
Y798010D03*
Y812183D03*
Y826356D03*
Y840529D03*
Y854703D03*
X1113530Y769663D03*
Y783836D03*
Y798010D03*
Y812183D03*
Y826356D03*
Y840529D03*
Y854703D03*
X1119042Y769663D03*
Y783836D03*
Y798010D03*
Y812183D03*
Y826356D03*
Y840529D03*
Y854703D03*
X1123372Y769663D03*
Y783836D03*
Y798010D03*
Y812183D03*
Y826356D03*
Y840529D03*
Y854703D03*
X1127703Y769663D03*
Y783836D03*
Y798010D03*
Y812183D03*
Y826356D03*
Y840529D03*
Y854703D03*
X1133215Y769663D03*
Y783836D03*
Y798010D03*
Y812183D03*
Y826356D03*
Y840529D03*
Y854703D03*
X1091089Y861789D03*
Y875962D03*
Y890136D03*
Y904309D03*
Y918482D03*
Y932655D03*
X1095420Y861789D03*
Y875962D03*
Y890136D03*
Y904309D03*
Y918482D03*
Y932655D03*
X1100932Y861789D03*
Y875962D03*
Y890136D03*
Y904309D03*
Y918482D03*
Y932655D03*
X1105262Y861789D03*
Y875962D03*
Y890136D03*
Y904309D03*
Y918482D03*
Y932655D03*
X1109593Y861789D03*
Y875962D03*
Y890136D03*
Y904309D03*
Y918482D03*
Y932655D03*
X1115105Y861789D03*
Y875962D03*
Y890136D03*
Y904309D03*
Y918482D03*
Y932655D03*
X1119435Y861789D03*
Y875962D03*
Y890136D03*
Y904309D03*
Y918482D03*
Y932655D03*
X1123766Y861789D03*
Y875962D03*
Y890136D03*
Y904309D03*
Y918482D03*
Y932655D03*
X1129278Y861789D03*
Y875962D03*
Y890136D03*
Y904309D03*
Y918482D03*
Y932655D03*
X1133609Y861789D03*
Y875962D03*
Y890136D03*
Y904309D03*
Y918482D03*
Y932655D03*
X1095026Y868876D03*
Y883049D03*
Y897222D03*
Y911396D03*
Y925569D03*
Y939742D03*
X1099357Y868876D03*
Y883049D03*
Y897222D03*
Y911396D03*
Y925569D03*
Y939742D03*
X1104869Y868876D03*
Y883049D03*
Y897222D03*
Y911396D03*
Y925569D03*
Y939742D03*
X1109199Y868876D03*
Y883049D03*
Y897222D03*
Y911396D03*
Y925569D03*
Y939742D03*
X1113530Y868876D03*
Y883049D03*
Y897222D03*
Y911396D03*
Y925569D03*
Y939742D03*
X1119042Y868876D03*
Y883049D03*
Y897222D03*
Y911396D03*
Y925569D03*
Y939742D03*
X1123372Y868876D03*
Y883049D03*
Y897222D03*
Y911396D03*
Y925569D03*
Y939742D03*
X1127703Y868876D03*
Y883049D03*
Y897222D03*
Y911396D03*
Y925569D03*
Y939742D03*
X1133215Y868876D03*
Y883049D03*
Y897222D03*
Y911396D03*
Y925569D03*
Y939742D03*
G54D56*
X131200Y262981D03*
Y715737D03*
Y1168492D03*
X379232Y262981D03*
Y715737D03*
Y1168492D03*
X627263Y262981D03*
Y715737D03*
Y1168492D03*
X747244Y381878D03*
Y814949D03*
X961417Y703925D03*
Y972429D03*
X1181889Y381878D03*
Y972429D03*
X1301870Y262980D03*
Y715737D03*
Y1168492D03*
X1549901Y262981D03*
Y715737D03*
Y1168492D03*
X1797933Y262980D03*
Y715737D03*
Y1168492D03*
G54D74*
X666250Y1485000D03*
X658750Y1481125D03*
Y1488875D03*
X954750Y908000D03*
X947250Y911875D03*
Y904125D03*
X957266Y1449272D03*
X949766Y1445397D03*
Y1453147D03*
X1024507Y929750D03*
X1017007Y933625D03*
Y925875D03*
G54D38*
X94000Y170300D03*
Y162700D03*
Y622800D03*
Y615200D03*
Y1075800D03*
Y1068200D03*
X218500Y170300D03*
Y162700D03*
Y622800D03*
Y615200D03*
Y1075800D03*
Y1068200D03*
X342500Y170300D03*
Y162700D03*
Y622800D03*
Y615200D03*
Y1075800D03*
Y1068200D03*
X467000Y170300D03*
Y162700D03*
Y622800D03*
Y615200D03*
Y1075800D03*
Y1068200D03*
X591000Y170300D03*
Y162700D03*
Y622800D03*
Y615200D03*
Y1075800D03*
Y1068200D03*
X715300Y170300D03*
Y162700D03*
Y622800D03*
Y615200D03*
Y1075800D03*
Y1068200D03*
X1007618Y1465065D03*
Y1472665D03*
X1305000Y173200D03*
Y180800D03*
X1313000Y173200D03*
Y180800D03*
X1305000Y626200D03*
Y633800D03*
X1313000Y626200D03*
Y633800D03*
X1305000Y1078700D03*
Y1086300D03*
X1313000Y1078700D03*
Y1086300D03*
X1429000Y173200D03*
Y180800D03*
X1437000Y173200D03*
Y180800D03*
X1429000Y626200D03*
Y633800D03*
X1437000Y626200D03*
Y633800D03*
X1429000Y1078700D03*
Y1086300D03*
X1437000Y1078700D03*
Y1086300D03*
X1553500Y173200D03*
Y180800D03*
X1561500Y173200D03*
Y180800D03*
X1553500Y626200D03*
Y633800D03*
X1561500Y626200D03*
Y633800D03*
X1553500Y1078700D03*
Y1086300D03*
X1561500Y1078700D03*
Y1086300D03*
X1677500Y173200D03*
Y180800D03*
X1685500Y173200D03*
Y180800D03*
X1677500Y626200D03*
Y633800D03*
X1685500Y626200D03*
Y633800D03*
X1677500Y1078700D03*
Y1086300D03*
X1685500Y1078700D03*
Y1086300D03*
X1801500Y173200D03*
Y180800D03*
X1809500Y173200D03*
Y180800D03*
X1801500Y626200D03*
Y633800D03*
X1809500Y626200D03*
Y633800D03*
X1801500Y1078700D03*
Y1086300D03*
X1809500Y1078700D03*
Y1086300D03*
X1886000Y169800D03*
Y162200D03*
X1885800Y622800D03*
Y615200D03*
X1885963Y1075886D03*
Y1068286D03*
G54D47*
X111024Y27697D03*
Y199941D03*
Y480453D03*
Y652697D03*
Y933209D03*
Y1105453D03*
X235236Y27697D03*
Y199941D03*
Y480453D03*
Y652697D03*
Y933209D03*
Y1105453D03*
X359449Y27697D03*
Y199941D03*
Y480453D03*
Y652697D03*
Y933209D03*
Y1105453D03*
X483661Y27697D03*
Y199941D03*
Y480453D03*
Y652697D03*
Y933209D03*
Y1105453D03*
X607874Y27697D03*
Y199941D03*
Y480453D03*
Y652697D03*
Y933209D03*
Y1105453D03*
X732087Y27697D03*
Y199941D03*
Y480453D03*
Y652697D03*
Y933209D03*
Y1105453D03*
X1281693Y27697D03*
Y199941D03*
Y480453D03*
Y652697D03*
Y933209D03*
Y1105453D03*
X1405906Y27697D03*
Y199941D03*
Y480453D03*
Y652697D03*
Y933209D03*
Y1105453D03*
X1530118Y27697D03*
Y199941D03*
Y480453D03*
Y652697D03*
Y933209D03*
Y1105453D03*
X1654331Y27697D03*
Y199941D03*
Y480453D03*
Y652697D03*
Y933209D03*
Y1105453D03*
X1778543Y27697D03*
Y199941D03*
Y480453D03*
Y652697D03*
Y933209D03*
Y1105453D03*
X1902756Y27697D03*
Y199941D03*
Y480453D03*
Y652697D03*
Y933209D03*
Y1105453D03*
G54D65*
X217500Y51200D03*
X208500D03*
X466000Y51500D03*
X457000D03*
X714500Y51300D03*
X705500D03*
X1040500Y1410500D03*
X1049500D03*
X1323500Y527000D03*
X1332500D03*
X1323500Y979500D03*
X1332500D03*
X1447500Y74000D03*
X1456500D03*
X1447500Y527000D03*
X1456500D03*
X1447500Y979500D03*
X1456500D03*
X1572000Y527000D03*
X1581000D03*
X1572000Y979500D03*
X1581000D03*
X1696000Y74000D03*
X1705000D03*
X1696000Y527000D03*
X1705000D03*
X1696000Y979500D03*
X1705000D03*
X1818900Y94400D03*
X1827900D03*
X1820000Y527000D03*
X1829000D03*
X1820000Y979500D03*
X1829000D03*
G54D29*
X56700Y100500D03*
Y553000D03*
Y1006000D03*
X195200Y82500D03*
X180700Y553000D03*
X137200Y579000D03*
X107656Y878062D03*
X137200Y1032000D03*
X181200Y1006000D03*
X205483Y440326D03*
X261200Y579000D03*
X260900Y1032000D03*
X223355Y1434029D03*
X305200Y100500D03*
Y553000D03*
X385700Y579000D03*
X305200Y1006000D03*
X385700Y1032000D03*
X429200Y553000D03*
Y1006000D03*
X553700Y100500D03*
Y553000D03*
X509700Y579000D03*
Y1032000D03*
X553700Y1006000D03*
X634200Y579000D03*
Y1032000D03*
X692200Y82500D03*
X748200Y126500D03*
X677700Y553000D03*
Y1006000D03*
X749500Y1032000D03*
X692200Y1476000D03*
X710700Y1449700D03*
X837190Y645690D03*
X834900Y804500D03*
X867000Y774500D03*
X927700Y763820D03*
X867700Y887500D03*
X873400Y1188400D03*
X896500Y1191700D03*
X978081Y559671D03*
X976647Y533383D03*
X1008041Y895045D03*
X1018333Y892965D03*
X964500Y1193500D03*
X1330700Y113500D03*
X1331700Y566500D03*
Y1019000D03*
X1432200Y81000D03*
X1370429Y1434045D03*
X1455700Y113500D03*
Y566500D03*
Y1019000D03*
X1601100Y133000D03*
X1580200Y566500D03*
Y1019000D03*
X1679600Y81000D03*
X1704200Y113500D03*
Y566500D03*
Y1019000D03*
X1748252Y443744D03*
X1750574Y1434109D03*
X1878200Y81500D03*
X1862700Y82000D03*
X1863900Y42100D03*
X1827200Y113500D03*
X1828200Y566500D03*
X1876100Y534600D03*
X1848200Y553000D03*
X1822656Y878062D03*
X1828200Y1019000D03*
X1848200Y1006000D03*
G54D92*
X949000Y1202776D03*
Y1204350D03*
Y1205925D03*
Y1207500D03*
Y1209075D03*
Y1210650D03*
Y1212224D03*
X965000D03*
Y1210650D03*
Y1209075D03*
Y1207500D03*
Y1205925D03*
Y1204350D03*
Y1202776D03*
X1116612Y1384049D03*
Y1385623D03*
Y1387198D03*
Y1388773D03*
Y1390348D03*
Y1391923D03*
Y1393497D03*
X1132612D03*
Y1391923D03*
Y1390348D03*
Y1388773D03*
Y1387198D03*
Y1385623D03*
Y1384049D03*
G54D83*
X814843Y403862D03*
Y424130D03*
X810400Y561866D03*
Y582134D03*
X801300Y1201766D03*
Y1222034D03*
X1028394Y771349D03*
Y791617D03*
X1112677Y402838D03*
Y423106D03*
X1121600Y1201266D03*
Y1221534D03*
G54D57*
X184874Y1416450D03*
X107474Y1458600D03*
X198800Y37400D03*
X440400Y35700D03*
X524211Y1429134D03*
X669761Y1453700D03*
X695600Y37300D03*
X834470Y937130D03*
X924000Y881700D03*
X951569Y1399632D03*
X950339Y1387003D03*
X1002118Y1464065D03*
X978443Y1441599D03*
X1125615Y1311270D03*
X1175800Y1309100D03*
X1208933Y1309144D03*
X1200962Y1405802D03*
X1324000Y1416450D03*
X1712126D03*
X1803100Y75000D03*
G54D39*
X72049Y260355D03*
X68109D03*
X72049Y254605D03*
X68109D03*
X72049Y713111D03*
X68109D03*
X72049Y707361D03*
X68109D03*
X192321Y260355D03*
Y254605D03*
Y713111D03*
Y707361D03*
X196261Y260355D03*
Y254605D03*
Y713111D03*
Y707361D03*
X320474Y260355D03*
X316534D03*
X320474Y254605D03*
X316534D03*
X320474Y713111D03*
X316534D03*
X320474Y707361D03*
X316534D03*
X444687Y260355D03*
X440747D03*
X444687Y254605D03*
X440747D03*
X444687Y713111D03*
X440747D03*
X444687Y707361D03*
X440747D03*
X568899Y260355D03*
X564959D03*
X568899Y254605D03*
X564959D03*
X568899Y713111D03*
X564959D03*
X568899Y707361D03*
X564959D03*
X693112Y260355D03*
X689172D03*
X693112Y254605D03*
X689172D03*
X693112Y713111D03*
X689172D03*
X693112Y707361D03*
X689172D03*
X1242718Y260355D03*
X1238778D03*
X1242718Y254605D03*
X1238778D03*
X1242718Y713111D03*
X1238778D03*
X1242718Y707361D03*
X1238778D03*
X1366931Y260355D03*
X1362991D03*
X1366931Y254605D03*
X1362991D03*
X1366931Y713111D03*
X1362991D03*
X1366931Y707361D03*
X1362991D03*
X1491143Y260355D03*
X1487203D03*
X1491143Y254605D03*
X1487203D03*
X1491143Y713111D03*
X1487203D03*
X1491143Y707361D03*
X1487203D03*
X1615356Y260355D03*
X1611416D03*
X1615356Y254605D03*
X1611416D03*
X1615356Y713111D03*
X1611416D03*
X1615356Y707361D03*
X1611416D03*
X1739568Y260355D03*
X1735628D03*
X1739568Y254605D03*
X1735628D03*
X1739568Y713111D03*
X1735628D03*
X1739568Y707361D03*
X1735628D03*
X1863781Y260355D03*
X1859841D03*
X1863781Y254605D03*
X1859841D03*
X1863781Y713111D03*
X1859841D03*
X1863781Y707361D03*
X1859841D03*
G54D84*
X859590Y650110D03*
Y652670D03*
Y655230D03*
Y657790D03*
Y660350D03*
Y662910D03*
Y665470D03*
X837390D03*
Y662910D03*
Y660350D03*
Y657790D03*
Y655230D03*
Y652670D03*
Y650110D03*
X833200Y760280D03*
Y757720D03*
Y755160D03*
Y752600D03*
Y750040D03*
Y747480D03*
Y744920D03*
X855400D03*
Y747480D03*
Y750040D03*
Y752600D03*
Y755160D03*
Y757720D03*
Y760280D03*
X859590Y668030D03*
Y670590D03*
Y673150D03*
Y675710D03*
Y678270D03*
X837390D03*
Y675710D03*
Y673150D03*
Y670590D03*
Y668030D03*
X838400Y856920D03*
X860600D03*
X833200Y773080D03*
Y770520D03*
Y767960D03*
Y765400D03*
Y762840D03*
X855400D03*
Y765400D03*
Y767960D03*
Y770520D03*
Y773080D03*
X861100Y809920D03*
Y812480D03*
Y815040D03*
Y817600D03*
Y820160D03*
Y822720D03*
Y825280D03*
Y827840D03*
Y830400D03*
Y832960D03*
Y835520D03*
Y838080D03*
X838900D03*
Y835520D03*
Y832960D03*
Y830400D03*
Y827840D03*
Y825280D03*
Y822720D03*
Y820160D03*
Y817600D03*
Y815040D03*
Y812480D03*
Y809920D03*
X838400Y885080D03*
Y882520D03*
Y879960D03*
Y877400D03*
Y874840D03*
Y872280D03*
Y869720D03*
Y867160D03*
Y864600D03*
Y862040D03*
Y859480D03*
X860600D03*
Y862040D03*
Y864600D03*
Y867160D03*
Y869720D03*
Y872280D03*
Y874840D03*
Y877400D03*
Y879960D03*
Y882520D03*
Y885080D03*
X947600Y769720D03*
Y772280D03*
Y774840D03*
Y777400D03*
Y779960D03*
Y782520D03*
Y785080D03*
Y787640D03*
Y790200D03*
Y792760D03*
Y795320D03*
Y797880D03*
X925400D03*
Y795320D03*
Y792760D03*
Y790200D03*
Y787640D03*
Y785080D03*
Y782520D03*
Y779960D03*
Y777400D03*
Y774840D03*
Y772280D03*
Y769720D03*
X898400Y1195980D03*
Y1198540D03*
Y1201100D03*
Y1203660D03*
Y1206220D03*
Y1208780D03*
Y1211340D03*
Y1213900D03*
Y1216460D03*
Y1219020D03*
X920600D03*
Y1216460D03*
Y1213900D03*
Y1211340D03*
Y1208780D03*
Y1206220D03*
Y1203660D03*
Y1201100D03*
Y1198540D03*
Y1195980D03*
X1116100Y1307375D03*
Y1304820D03*
Y1302260D03*
Y1299700D03*
Y1297140D03*
Y1294580D03*
Y1292025D03*
X1093900D03*
Y1294580D03*
Y1297140D03*
Y1299700D03*
Y1302260D03*
Y1304820D03*
Y1307375D03*
X1200912Y1399993D03*
Y1397433D03*
Y1394873D03*
Y1392313D03*
Y1389753D03*
Y1387193D03*
Y1384633D03*
Y1382073D03*
Y1379513D03*
Y1376953D03*
X1178712D03*
Y1379513D03*
Y1382073D03*
Y1384633D03*
Y1387193D03*
Y1389753D03*
Y1392313D03*
Y1394873D03*
Y1397433D03*
Y1399993D03*
G54D75*
X723200Y1443500D03*
X1030643Y1431399D03*
G54D93*
X957000Y1199500D03*
X955425D03*
X953850D03*
X952276D03*
Y1215500D03*
X953850D03*
X955425D03*
X957000D03*
X961724Y1199500D03*
X960150D03*
X958575D03*
Y1215500D03*
X960150D03*
X961724D03*
X1119888Y1396773D03*
X1121462D03*
X1123037D03*
X1124612D03*
X1126187D03*
X1127762D03*
X1129336D03*
Y1380773D03*
X1127762D03*
X1126187D03*
X1124612D03*
X1123037D03*
X1121462D03*
X1119888D03*
G54D48*
X126709Y57719D03*
X128909D03*
X126709Y59919D03*
X128909D03*
X126709Y510475D03*
X128909D03*
X126709Y512675D03*
X128909D03*
X126709Y963231D03*
X128909D03*
X126709Y965431D03*
X128909D03*
X250921Y57719D03*
X253121D03*
X250921Y59919D03*
X253121D03*
X250921Y510475D03*
X253121D03*
X250921Y512675D03*
X253121D03*
X250921Y963231D03*
X253121D03*
X250921Y965431D03*
X253121D03*
X375134Y57719D03*
X377334D03*
X375134Y59919D03*
X377334D03*
X375134Y510475D03*
X377334D03*
X375134Y512675D03*
X377334D03*
X375134Y963231D03*
X377334D03*
X375134Y965431D03*
X377334D03*
X499346Y57719D03*
X501546D03*
X499346Y59919D03*
X501546D03*
X499346Y510475D03*
X501546D03*
X499346Y512675D03*
X501546D03*
X499346Y963231D03*
X501546D03*
X499346Y965431D03*
X501546D03*
X623559Y57719D03*
X625759D03*
X623559Y59919D03*
X625759D03*
X623559Y510475D03*
X625759D03*
X623559Y512675D03*
X625759D03*
X623559Y965431D03*
X625759D03*
X623559Y963231D03*
X625759D03*
X747772Y57719D03*
X749972D03*
X747772Y59919D03*
X749972D03*
X747772Y510475D03*
X749972D03*
X747772Y512675D03*
X749972D03*
X747772Y965431D03*
X749972D03*
X747772Y963231D03*
X749972D03*
G54D66*
X231674Y1421000D03*
X220074D03*
X1378174D03*
X1366574D03*
X1758440Y1420946D03*
X1746840D03*
G54D58*
X184874Y1420050D03*
X107474Y1462200D03*
X198800Y41000D03*
X440400Y39300D03*
X524211Y1432734D03*
X669761Y1457300D03*
X695600Y40900D03*
X834470Y940730D03*
X924000Y885300D03*
X951569Y1403232D03*
X950339Y1390603D03*
X1002118Y1467665D03*
X978443Y1445199D03*
X1125615Y1314870D03*
X1175800Y1312700D03*
X1208933Y1312744D03*
X1200962Y1409402D03*
X1324000Y1420050D03*
X1712126D03*
X1803100Y78600D03*
G54D85*
X859113Y1290032D03*
Y1301000D03*
X871556Y1290030D03*
Y1300998D03*
X884056Y1290030D03*
Y1300998D03*
X901435Y1396353D03*
Y1385385D03*
X913935Y1396353D03*
Y1385385D03*
X888776Y1396385D03*
Y1385417D03*
X1023823Y379318D03*
Y368350D03*
G54D76*
X718800Y1443500D03*
X1026243Y1431399D03*
G54D49*
X150500Y29300D03*
X143300Y594500D03*
Y1047500D03*
X144674Y1457000D03*
X267300Y594500D03*
X267000Y1047500D03*
X228174Y1430000D03*
X391800Y594500D03*
Y1047500D03*
X515800Y594500D03*
Y1047500D03*
X510300Y1465500D03*
X640300Y594500D03*
Y1047500D03*
X842290Y641690D03*
X840000Y800500D03*
X862658Y1392892D03*
X932800Y759320D03*
X872300Y892000D03*
X934300Y880000D03*
X984141Y563811D03*
X1010200Y1129300D03*
X1050500Y1417000D03*
X1043350Y1480314D03*
X1291674Y1457000D03*
X1375174Y1430000D03*
X1671926Y1457000D03*
X1817300Y28900D03*
X1755426Y1430000D03*
G54D67*
X384055Y1330472D03*
Y1320472D03*
X354055Y1330472D03*
X364055D03*
X354055Y1320472D03*
X364055D03*
X324055Y1330472D03*
X334055D03*
X324055Y1320472D03*
X334055D03*
X304055Y1330472D03*
Y1320472D03*
X294055Y1330472D03*
Y1320472D03*
X384055Y1340472D03*
Y1350472D03*
X354055Y1340472D03*
Y1350472D03*
X364055Y1340472D03*
Y1350472D03*
X324055Y1340472D03*
Y1350472D03*
X334055Y1340472D03*
Y1350472D03*
X304055D03*
Y1340472D03*
X294055Y1350472D03*
Y1340472D03*
X474055Y1330472D03*
X484055D03*
X474055Y1320472D03*
X484055D03*
X444055Y1330472D03*
X454055D03*
X444055Y1320472D03*
X454055D03*
X414055Y1330472D03*
X424055D03*
X414055Y1320472D03*
X424055D03*
X394055Y1330472D03*
Y1320472D03*
X474055Y1340472D03*
Y1350472D03*
X484055Y1340472D03*
Y1350472D03*
X444055Y1340472D03*
Y1350472D03*
X454055Y1340472D03*
Y1350472D03*
X414055Y1340472D03*
Y1350472D03*
X424055Y1340472D03*
Y1350472D03*
X394055Y1340472D03*
Y1350472D03*
G54D94*
X934500Y1367958D03*
Y1396242D03*
G54D59*
X145445Y1425760D03*
Y1423200D03*
Y1420640D03*
X151945D03*
Y1425760D03*
G54D77*
X679950Y1446610D03*
Y1460390D03*
X700050D03*
Y1446610D03*
X987393Y1434509D03*
Y1448289D03*
X1007493D03*
Y1434509D03*
G54D86*
X786631Y1305085D03*
Y1310085D03*
Y1315085D03*
X787101Y1347591D03*
Y1352591D03*
Y1357591D03*
X786880Y1385259D03*
Y1390259D03*
Y1395259D03*
X1005118Y1312489D03*
Y1317489D03*
Y1322489D03*
Y1368089D03*
Y1373089D03*
Y1378089D03*
Y1340289D03*
Y1345289D03*
Y1350289D03*
G54D95*
X974015Y284449D03*
X986614D03*
X1002362D03*
X1014960D03*
X1030709D03*
X1043307D03*
X974015Y261812D03*
X986614D03*
X1002362D03*
X1014960D03*
X1030709D03*
X1043307D03*
X974015Y307087D03*
X986614D03*
X1002362D03*
X1014960D03*
X1030709D03*
X1043307D03*
G54D68*
X418505Y1423348D03*
X390221D03*
G54D78*
X680250Y1448579D03*
Y1450547D03*
Y1452516D03*
Y1454484D03*
Y1456453D03*
Y1458421D03*
X699750D03*
Y1456453D03*
Y1454484D03*
Y1452516D03*
Y1450547D03*
Y1448579D03*
X987693Y1436478D03*
Y1438446D03*
Y1440415D03*
Y1442383D03*
Y1444352D03*
Y1446320D03*
X1007193D03*
Y1444352D03*
Y1442383D03*
Y1440415D03*
Y1438446D03*
Y1436478D03*
G54D87*
X794631Y1312585D03*
X795101Y1355091D03*
X794880Y1392759D03*
X1013118Y1319989D03*
Y1375589D03*
Y1347789D03*
G54D96*
X974015Y278544D03*
X1002362D03*
X1030709D03*
X974015Y267717D03*
X1002362D03*
X1030709D03*
X974015Y255906D03*
X1002362D03*
X1030709D03*
X986614Y278544D03*
X1014960D03*
X1043307D03*
X986614Y267717D03*
X1014960D03*
X1043307D03*
X986614Y255906D03*
X1014960D03*
X1043307D03*
X974015Y312993D03*
X1002362D03*
X1030709D03*
X974015Y301182D03*
X1002362D03*
X1030709D03*
X974015Y290355D03*
X1002362D03*
X1030709D03*
X986614Y312993D03*
X1014960D03*
X1043307D03*
X986614Y301182D03*
X1014960D03*
X1043307D03*
X986614Y290355D03*
X1014960D03*
X1043307D03*
X1101405Y1120040D03*
X1119633D03*
X1101405Y1132638D03*
X1119633D03*
G54D69*
X462000Y1382985D03*
Y1372985D03*
Y1362985D03*
X474000Y1382985D03*
Y1372985D03*
Y1362985D03*
X426000D03*
X450000Y1372985D03*
Y1382985D03*
X414000Y1372985D03*
X450000Y1362985D03*
X438000Y1372985D03*
X414000Y1362985D03*
X438000D03*
X426000Y1372985D03*
X438000Y1382985D03*
X414000D03*
X426000D03*
X498000Y1332985D03*
X510000Y1344485D03*
X498000Y1352985D03*
X522000Y1344485D03*
X498000Y1342985D03*
X510000Y1354485D03*
X522000D03*
X510000Y1364485D03*
X522000D03*
X510000Y1374485D03*
Y1384485D03*
X522000Y1374485D03*
Y1384485D03*
X498000Y1382985D03*
Y1372985D03*
X486000Y1382985D03*
Y1372985D03*
X498000Y1362985D03*
X486000D03*
X658200Y1329200D03*
X666100D03*
X581800Y1321200D03*
Y1329100D03*
X589700D03*
Y1321200D03*
X594800Y1313500D03*
X597600Y1321200D03*
Y1329100D03*
X610600Y1313500D03*
Y1305600D03*
Y1297600D03*
X602700Y1313500D03*
Y1305600D03*
Y1297600D03*
X629200Y1329100D03*
X605500Y1321200D03*
X613400D03*
X605500Y1329100D03*
X613400D03*
X621300D03*
X666100Y1360800D03*
Y1368700D03*
Y1376600D03*
Y1352900D03*
X658200Y1360800D03*
Y1368700D03*
Y1376600D03*
Y1352900D03*
X666100Y1337100D03*
Y1345000D03*
X658200Y1337100D03*
Y1345000D03*
X581800Y1376500D03*
Y1384400D03*
Y1392300D03*
Y1360700D03*
Y1368600D03*
Y1352800D03*
Y1344900D03*
Y1337000D03*
X589700Y1392300D03*
Y1400200D03*
Y1344900D03*
Y1352800D03*
Y1384400D03*
Y1376500D03*
Y1368600D03*
Y1360700D03*
Y1337000D03*
X597600Y1400200D03*
Y1408100D03*
Y1360700D03*
Y1368600D03*
Y1392300D03*
Y1376500D03*
Y1384400D03*
Y1352800D03*
Y1337000D03*
Y1344900D03*
X629200D03*
X621300D03*
X613400D03*
X605500D03*
Y1360700D03*
X613400D03*
X621300D03*
X629200D03*
X605500Y1352800D03*
X613400D03*
X621300D03*
X629200D03*
Y1368600D03*
Y1376500D03*
X605500Y1408100D03*
Y1400200D03*
Y1392300D03*
Y1384400D03*
Y1376500D03*
Y1368600D03*
X613400Y1400200D03*
Y1392300D03*
Y1384400D03*
Y1376500D03*
Y1368600D03*
X621300Y1376500D03*
Y1368600D03*
X629200Y1337000D03*
X613400D03*
X621300D03*
X605500D03*
X613400Y1408100D03*
X705600Y1329200D03*
X697700Y1321300D03*
Y1329200D03*
X689800D03*
Y1321300D03*
X693800Y1313900D03*
Y1306000D03*
X685900D03*
X678000D03*
Y1313900D03*
X685900D03*
X681900Y1321300D03*
X674000D03*
Y1329200D03*
X681900D03*
X693800Y1298000D03*
X685900D03*
X678000D03*
X768867Y1311110D03*
Y1335110D03*
Y1327110D03*
Y1319110D03*
X705600Y1337100D03*
Y1360800D03*
Y1352900D03*
Y1345000D03*
Y1376600D03*
Y1368700D03*
X699600Y1408200D03*
Y1392400D03*
Y1400300D03*
X697700Y1345000D03*
Y1360800D03*
Y1368700D03*
Y1376600D03*
X697100Y1384600D03*
X697700Y1352900D03*
Y1337100D03*
X691700Y1408200D03*
Y1400300D03*
X675900D03*
X683800D03*
Y1408200D03*
X675900D03*
X689800Y1352900D03*
Y1384500D03*
Y1376600D03*
X691700Y1392400D03*
X689800Y1368700D03*
Y1360800D03*
X674000D03*
X681900D03*
Y1368700D03*
X674000D03*
X675900Y1392400D03*
X683800D03*
X674000Y1376600D03*
X681900D03*
Y1384500D03*
X674000D03*
Y1352900D03*
X681900D03*
X689800Y1345000D03*
Y1337100D03*
X681900D03*
X674000D03*
X681900Y1345000D03*
X674000D03*
X768867Y1383110D03*
Y1359110D03*
Y1367110D03*
Y1351110D03*
Y1343110D03*
Y1391110D03*
Y1399110D03*
Y1375110D03*
X786200Y1334100D03*
X794200D03*
X801000Y1333800D03*
X786200Y1326100D03*
X794200D03*
X776867Y1311110D03*
Y1335110D03*
Y1327110D03*
Y1319110D03*
X775600Y1302400D03*
X801000Y1325800D03*
X790056Y1297863D03*
X798056D03*
X782056D03*
X834000Y1324500D03*
Y1317500D03*
Y1310500D03*
Y1303500D03*
X827000D03*
X820000D03*
X827000Y1310500D03*
X820000D03*
X827000Y1317500D03*
X820000D03*
X827000Y1324500D03*
X820000D03*
X776867Y1399110D03*
X790330Y1407929D03*
X782330D03*
X798330D03*
X795000Y1377900D03*
X786600Y1378100D03*
X790950Y1372703D03*
X776867Y1383110D03*
Y1359110D03*
X782950Y1372703D03*
X776867Y1367110D03*
Y1375110D03*
X798950Y1372703D03*
X776867Y1391110D03*
X790223Y1339930D03*
X782223Y1339430D03*
X798223Y1339930D03*
X776867Y1351110D03*
Y1343110D03*
X834000Y1386000D03*
Y1379000D03*
Y1363000D03*
Y1356000D03*
Y1349000D03*
Y1342000D03*
X827000D03*
X820000D03*
X827000Y1349000D03*
X820000D03*
X827000Y1356000D03*
X820000D03*
X827000Y1363000D03*
X820000D03*
X827000Y1379000D03*
X820000D03*
X827000Y1386000D03*
X820000D03*
X827000Y1393000D03*
X820000D03*
X958200Y1303900D03*
X942400D03*
X950300D03*
X934500D03*
X926600D03*
X958200Y1311800D03*
X926600D03*
X934500D03*
X950300D03*
X942400D03*
X903500Y1319400D03*
X950300Y1319700D03*
X958200D03*
X934500D03*
X942400D03*
X926600D03*
X918700D03*
X910800D03*
X887800Y1327100D03*
X934700Y1327500D03*
X895200D03*
X903100D03*
X911000D03*
X926800D03*
X918900D03*
X887800Y1335000D03*
X886400Y1368100D03*
Y1376000D03*
X894300D03*
Y1368100D03*
X934700Y1335400D03*
X926800D03*
X918900D03*
X895200D03*
X903100D03*
X911000D03*
X890400Y1358900D03*
X887800Y1350800D03*
Y1342900D03*
X937300Y1359300D03*
X934700Y1343300D03*
Y1351200D03*
X926800Y1343300D03*
Y1351200D03*
X929400Y1359300D03*
X918900Y1343300D03*
Y1351200D03*
X921500Y1359300D03*
X918000Y1368100D03*
Y1376000D03*
X910100Y1368100D03*
Y1376000D03*
X911000Y1343300D03*
Y1351200D03*
X913600Y1359300D03*
X903100Y1343300D03*
Y1351200D03*
X905700Y1359300D03*
X902200Y1376000D03*
Y1368100D03*
X897800Y1359300D03*
X895200Y1351200D03*
Y1343300D03*
X998600Y1300900D03*
X991500Y1312100D03*
X1020800Y1300400D03*
X991455Y1320416D03*
X996400Y1315900D03*
X996200Y1307800D03*
X1014000Y1300600D03*
X991755Y1327716D03*
X996055Y1324116D03*
X1007100Y1301100D03*
X1011100Y1305300D03*
X1019829Y1306139D03*
X1002700Y1305700D03*
X991800Y1303400D03*
X1000200Y1311700D03*
Y1320500D03*
X1016429Y1333939D03*
X1021829D03*
X1011029D03*
X1005629D03*
X986755Y1323816D03*
X986700Y1307600D03*
X1000200Y1328100D03*
X1050818Y1311189D03*
Y1316589D03*
X1045418Y1321989D03*
X1050818D03*
X1034618Y1311189D03*
X1040018D03*
X1045418D03*
X1040018Y1316589D03*
X1034618D03*
X1040018Y1321989D03*
X1031600Y1335100D03*
X1037200Y1335000D03*
X1034618Y1321989D03*
X997900Y1335800D03*
X992500D03*
X997900Y1341200D03*
X992500D03*
X997900Y1346600D03*
X992500D03*
X997900Y1352000D03*
X992500D03*
Y1357400D03*
X997900D03*
X989083Y1387764D03*
X989509Y1393422D03*
X994700Y1385000D03*
X999700Y1374500D03*
X989100Y1381700D03*
X994200Y1362700D03*
X1019829Y1389539D03*
X1013692Y1389688D03*
X1019829Y1361739D03*
X1014306Y1361710D03*
X1008870Y1361681D03*
X1003367Y1361655D03*
X1004217Y1389394D03*
X1008298Y1393071D03*
X994400Y1377300D03*
X999930Y1393070D03*
X999800Y1381600D03*
X999900Y1366800D03*
X994300Y1370100D03*
X989200Y1374800D03*
X988900Y1366900D03*
X1034600Y1349600D03*
X1042400Y1349500D03*
X1037540Y1344964D03*
X1034799Y1340183D03*
X1044700Y1335500D03*
X1043300Y1342500D03*
X1048000Y1346100D03*
X1037111Y1372380D03*
X1039988Y1367352D03*
X1044400Y1363100D03*
X1036900Y1362600D03*
X1034380Y1367469D03*
X1031300Y1362700D03*
X1042100Y1377100D03*
X1034300Y1377200D03*
X1047401Y1375084D03*
X1066481Y1327759D03*
X1061081D03*
X1066481Y1333159D03*
X1061081D03*
X1061618Y1316589D03*
X1056218Y1311189D03*
X1061618D03*
X1056218Y1316589D03*
X1060218Y1321989D03*
X1066491Y1319983D03*
X1066407Y1313972D03*
X1066481Y1338559D03*
X1061081D03*
X1066481Y1343959D03*
X1061081D03*
X1066481Y1376359D03*
Y1349359D03*
Y1354759D03*
Y1360159D03*
Y1365559D03*
Y1370959D03*
X1061081Y1376359D03*
Y1370959D03*
Y1365559D03*
Y1360159D03*
Y1354759D03*
Y1349359D03*
G54D97*
X1042147Y379090D03*
X1066947D03*
G54D79*
X683110Y1463550D03*
X696890D03*
Y1443450D03*
X683110D03*
X990553Y1451449D03*
X1004333D03*
Y1431349D03*
X990553D03*
G54D88*
X809631Y1320085D03*
Y1315085D03*
Y1310085D03*
Y1305085D03*
X810101Y1362591D03*
Y1357591D03*
Y1352591D03*
Y1347591D03*
X809880Y1400259D03*
Y1395259D03*
Y1390259D03*
Y1385259D03*
X1028118Y1327489D03*
Y1322489D03*
Y1317489D03*
Y1312489D03*
Y1383089D03*
Y1378089D03*
Y1373089D03*
Y1368089D03*
Y1355289D03*
Y1350289D03*
Y1345289D03*
Y1340289D03*
G54D98*
X1047000Y1425700D03*
X1049000Y1431300D03*
X1045000D03*
G54D89*
X959913Y519617D03*
Y522177D03*
Y524737D03*
Y527297D03*
X978571Y553411D03*
Y550851D03*
Y548291D03*
Y545731D03*
X962271D03*
Y548291D03*
Y550851D03*
Y553411D03*
X976213Y527297D03*
Y524737D03*
Y522177D03*
Y519617D03*
G54D99*
X1104752Y1120040D03*
X1122980D03*
X1104752Y1132638D03*
X1122980D03*
M02*
